G04 ================== begin FILE IDENTIFICATION RECORD ==================*
G04 Layout Name:  DA0T6MTH8C0_t6m_tray_bp_c_brd_103112_274.brd*
G04 Film Name:    fab.art*
G04 File Format:  Gerber RS274X*
G04 File Origin:  Cadence Allegro 16.3-S048*
G04 Origin Date:  Tue Nov 26 11:26:41 2013*
G04 *
G04 Layer:  MANUFACTURING/NCDRILL_LEGEND*
G04 Layer:  MANUFACTURING/NCDRILL_FIGURE*
G04 Layer:  MANUFACTURING/NCLEGEND-1-8*
G04 Layer:  MANUFACTURING/PHOTOPLOT_OUTLINE*
G04 Layer:  MANUFACTURING/DIMENSION*
G04 Layer:  MANUFACTURING/DETAILS*
G04 Layer:  DRAWING FORMAT/TITLE_BLOCK*
G04 Layer:  DRAWING FORMAT/TITLE_DATA_FAB*
G04 Layer:  BOARD GEOMETRY/OUTLINE*
G04 *
G04 Offset:    (0.00 0.00)*
G04 Mirror:    No*
G04 Mode:      Positive*
G04 Rotation:  0*
G04 FullContactRelief:  No*
G04 UndefLineWidth:     6.00*
G04 ================== end FILE IDENTIFICATION RECORD ====================*
%FSLAX25Y25*MOIN*%
%IR0*IPPOS*OFA0.00000B0.00000*MIA0B0*SFA1.00000B1.00000*%
%AMMACRO22*
1,1,.006,.014497,-.035*
20,1,.006,.014497,-.035,-.014497,-.035,0.0*
1,1,.006,-.014497,-.035*
20,1,.006,-.014497,-.035,-.035,-.014497,0.0*
1,1,.006,-.035,-.014497*
20,1,.006,-.035,-.014497,-.035,.014497,0.0*
1,1,.006,-.035,.014497*
20,1,.006,-.035,.014497,-.014497,.035,0.0*
1,1,.006,-.014497,.035*
20,1,.006,-.014497,.035,.014497,.035,0.0*
1,1,.006,.014497,.035*
20,1,.006,.014497,.035,.035,.014497,0.0*
1,1,.006,.035,.014497*
20,1,.006,.035,.014497,.035,-.014497,0.0*
1,1,.006,.035,-.014497*
20,1,.006,.035,-.014497,.014497,-.035,0.0*
1,1,.006,.014497,-.035*
1,1,.006,-.0385,-.0175*
20,1,.006,-.0385,-.0175,-.0385,.01225,0.0*
1,1,.006,-.0385,.01225*
20,1,.006,-.0385,.01225,-.03733,.01517,0.0*
1,1,.006,-.03733,.01517*
20,1,.006,-.03733,.01517,-.035,.01692,0.0*
1,1,.006,-.035,.01692*
20,1,.006,-.035,.01692,-.0315,.0175,0.0*
1,1,.006,-.0315,.0175*
20,1,.006,-.0315,.0175,-.028,.01633,0.0*
1,1,.006,-.028,.01633*
20,1,.006,-.028,.01633,-.02625,.01342,0.0*
1,1,.006,-.02625,.01342*
1,1,.006,-.03325,.0035*
20,1,.006,-.03325,.0035,-.04492,.0035,0.0*
1,1,.006,-.04492,.0035*
1,1,.006,.00001,.00583*
20,1,.006,.00001,.00583,.00001,-.0175,0.0*
1,1,.006,.00001,-.0175*
1,1,.006,.00001,.01517*
20,1,.006,.00001,.01517,-.00116,.01575,0.0*
1,1,.006,-.00116,.01575*
20,1,.006,-.00116,.01575,-.00116,.01692,0.0*
1,1,.006,-.00116,.01692*
20,1,.006,-.00116,.01692,.00001,.0175,0.0*
1,1,.006,.00001,.0175*
20,1,.006,.00001,.0175,.00118,.01692,0.0*
1,1,.006,.00118,.01692*
20,1,.006,.00118,.01692,.00118,.01575,0.0*
1,1,.006,.00118,.01575*
20,1,.006,.00118,.01575,.00001,.01517,0.0*
1,1,.006,.00001,.01517*
1,1,.006,.03502,.0175*
20,1,.006,.03502,.0175,.03502,-.0175,0.0*
1,1,.006,.03502,-.0175*
1,1,.006,.02685,.00583*
20,1,.006,.02685,.00583,.04319,.00583,0.0*
1,1,.006,.04319,.00583*
%
%ADD22MACRO22*%
%AMMACRO25*
1,1,.006,-.019,-.0125*
20,1,.006,-.019,-.0125,-.019,.0125,0.0*
1,1,.006,-.019,.0125*
20,1,.006,-.019,.0125,-.018711,.015799,0.0*
1,1,.006,-.018711,.015799*
20,1,.006,-.018711,.015799,-.017854,.018998,0.0*
1,1,.006,-.017854,.018998*
20,1,.006,-.017854,.018998,-.016454,.022,0.0*
1,1,.006,-.016454,.022*
20,1,.006,-.016454,.022,-.014555,.024713,0.0*
1,1,.006,-.014555,.024713*
20,1,.006,-.014555,.024713,-.012213,.027055,0.0*
1,1,.006,-.012213,.027055*
20,1,.006,-.012213,.027055,-.0095,.028954,0.0*
1,1,.006,-.0095,.028954*
20,1,.006,-.0095,.028954,-.006498,.030354,0.0*
1,1,.006,-.006498,.030354*
20,1,.006,-.006498,.030354,-.003299,.031211,0.0*
1,1,.006,-.003299,.031211*
20,1,.006,-.003299,.031211,0.0,.0315,0.0*
1,1,.006,0.0,.0315*
20,1,.006,0.0,.0315,.003299,.031211,0.0*
1,1,.006,.003299,.031211*
20,1,.006,.003299,.031211,.006498,.030354,0.0*
1,1,.006,.006498,.030354*
20,1,.006,.006498,.030354,.0095,.028954,0.0*
1,1,.006,.0095,.028954*
20,1,.006,.0095,.028954,.012213,.027055,0.0*
1,1,.006,.012213,.027055*
20,1,.006,.012213,.027055,.014555,.024713,0.0*
1,1,.006,.014555,.024713*
20,1,.006,.014555,.024713,.016454,.022,0.0*
1,1,.006,.016454,.022*
20,1,.006,.016454,.022,.017854,.018998,0.0*
1,1,.006,.017854,.018998*
20,1,.006,.017854,.018998,.018711,.015799,0.0*
1,1,.006,.018711,.015799*
20,1,.006,.018711,.015799,.019,.0125,0.0*
1,1,.006,.019,.0125*
20,1,.006,.019,.0125,.019,-.0125,0.0*
1,1,.006,.019,-.0125*
20,1,.006,.019,-.0125,.018711,-.015799,0.0*
1,1,.006,.018711,-.015799*
20,1,.006,.018711,-.015799,.017854,-.018998,0.0*
1,1,.006,.017854,-.018998*
20,1,.006,.017854,-.018998,.016454,-.022,0.0*
1,1,.006,.016454,-.022*
20,1,.006,.016454,-.022,.014555,-.024713,0.0*
1,1,.006,.014555,-.024713*
20,1,.006,.014555,-.024713,.012213,-.027055,0.0*
1,1,.006,.012213,-.027055*
20,1,.006,.012213,-.027055,.0095,-.028954,0.0*
1,1,.006,.0095,-.028954*
20,1,.006,.0095,-.028954,.006498,-.030354,0.0*
1,1,.006,.006498,-.030354*
20,1,.006,.006498,-.030354,.003299,-.031211,0.0*
1,1,.006,.003299,-.031211*
20,1,.006,.003299,-.031211,0.0,-.0315,0.0*
1,1,.006,0.0,-.0315*
20,1,.006,0.0,-.0315,-.003299,-.031211,0.0*
1,1,.006,-.003299,-.031211*
20,1,.006,-.003299,-.031211,-.006498,-.030354,0.0*
1,1,.006,-.006498,-.030354*
20,1,.006,-.006498,-.030354,-.0095,-.028954,0.0*
1,1,.006,-.0095,-.028954*
20,1,.006,-.0095,-.028954,-.012213,-.027055,0.0*
1,1,.006,-.012213,-.027055*
20,1,.006,-.012213,-.027055,-.014555,-.024713,0.0*
1,1,.006,-.014555,-.024713*
20,1,.006,-.014555,-.024713,-.016454,-.022,0.0*
1,1,.006,-.016454,-.022*
20,1,.006,-.016454,-.022,-.017854,-.018998,0.0*
1,1,.006,-.017854,-.018998*
20,1,.006,-.017854,-.018998,-.018711,-.015799,0.0*
1,1,.006,-.018711,-.015799*
20,1,.006,-.018711,-.015799,-.019,-.0125,0.0*
1,1,.006,-.019,-.0125*
1,1,.006,-.02248,-.00317*
20,1,.006,-.02248,-.00317,-.01488,-.00317,0.0*
1,1,.006,-.01488,-.00317*
1,1,.006,-.019,.00095*
20,1,.006,-.019,.00095,-.019,-.00728,0.0*
1,1,.006,-.019,-.00728*
1,1,.006,-.00791,-.0095*
20,1,.006,-.00791,-.0095,.00001,.0095,0.0*
1,1,.006,.00001,.0095*
20,1,.006,.00001,.0095,.00793,-.0095,0.0*
1,1,.006,.00793,-.0095*
1,1,.006,.00508,-.00285*
20,1,.006,.00508,-.00285,-.00506,-.00285,0.0*
1,1,.006,-.00506,-.00285*
1,1,.006,.01079,-.0095*
20,1,.006,.01079,-.0095,.01079,.0095,0.0*
1,1,.006,.01079,.0095*
20,1,.006,.01079,.0095,.01902,-.00633,0.0*
1,1,.006,.01902,-.00633*
20,1,.006,.01902,-.00633,.02725,.0095,0.0*
1,1,.006,.02725,.0095*
20,1,.006,.02725,.0095,.02725,-.0095,0.0*
1,1,.006,.02725,-.0095*
%
%ADD25MACRO25*%
%AMMACRO23*
1,1,.006,.0425,0.0*
20,1,.006,.0425,0.0,0.0,-.0425,0.0*
1,1,.006,0.0,-.0425*
20,1,.006,0.0,-.0425,-.0425,0.0,0.0*
1,1,.006,-.0425,0.0*
20,1,.006,-.0425,0.0,0.0,.0425,0.0*
1,1,.006,0.0,.0425*
20,1,.006,0.0,.0425,.0425,0.0,0.0*
1,1,.006,.0425,0.0*
1,1,.006,-.05525,-.03542*
20,1,.006,-.05525,-.03542,-.05525,.00708,0.0*
1,1,.006,-.05525,.00708*
1,1,.006,-.05525,.00071*
20,1,.006,-.05525,.00071,-.05171,.00425,0.0*
1,1,.006,-.05171,.00425*
20,1,.006,-.05171,.00425,-.04817,.00637,0.0*
1,1,.006,-.04817,.00637*
20,1,.006,-.04817,.00637,-.0425,.00708,0.0*
1,1,.006,-.0425,.00708*
20,1,.006,-.0425,.00708,-.03754,.00637,0.0*
1,1,.006,-.03754,.00637*
20,1,.006,-.03754,.00637,-.03258,.00283,0.0*
1,1,.006,-.03258,.00283*
20,1,.006,-.03258,.00283,-.03046,-.00213,0.0*
1,1,.006,-.03046,-.00213*
20,1,.006,-.03046,-.00213,-.02975,-.00708,0.0*
1,1,.006,-.02975,-.00708*
20,1,.006,-.02975,-.00708,-.03046,-.01204,0.0*
1,1,.006,-.03046,-.01204*
20,1,.006,-.03046,-.01204,-.03258,-.017,0.0*
1,1,.006,-.03258,-.017*
20,1,.006,-.03258,-.017,-.03683,-.01983,0.0*
1,1,.006,-.03683,-.01983*
20,1,.006,-.03683,-.01983,-.0425,-.02125,0.0*
1,1,.006,-.0425,-.02125*
20,1,.006,-.0425,-.02125,-.04746,-.02054,0.0*
1,1,.006,-.04746,-.02054*
20,1,.006,-.04746,-.02054,-.05242,-.01842,0.0*
1,1,.006,-.05242,-.01842*
20,1,.006,-.05242,-.01842,-.05525,-.01558,0.0*
1,1,.006,-.05525,-.01558*
1,1,.006,.00001,.00708*
20,1,.006,.00001,.00708,.00001,-.02125,0.0*
1,1,.006,.00001,-.02125*
1,1,.006,.00001,.01842*
20,1,.006,.00001,.01842,-.00141,.01912,0.0*
1,1,.006,-.00141,.01912*
20,1,.006,-.00141,.01912,-.00141,.02054,0.0*
1,1,.006,-.00141,.02054*
20,1,.006,-.00141,.02054,.00001,.02125,0.0*
1,1,.006,.00001,.02125*
20,1,.006,.00001,.02125,.00143,.02054,0.0*
1,1,.006,.00143,.02054*
20,1,.006,.00143,.02054,.00143,.01912,0.0*
1,1,.006,.00143,.01912*
20,1,.006,.00143,.01912,.00001,.01842,0.0*
1,1,.006,.00001,.01842*
1,1,.006,.04252,.02125*
20,1,.006,.04252,.02125,.04252,-.02125,0.0*
1,1,.006,.04252,-.02125*
1,1,.006,.0326,.00708*
20,1,.006,.0326,.00708,.05244,.00708,0.0*
1,1,.006,.05244,.00708*
%
%ADD23MACRO23*%
%AMMACRO10*
1,1,.006,.035,.035*
20,1,.006,.035,.035,.035,-.035,0.0*
1,1,.006,.035,-.035*
20,1,.006,.035,-.035,-.035,-.035,0.0*
1,1,.006,-.035,-.035*
20,1,.006,-.035,-.035,-.035,.035,0.0*
1,1,.006,-.035,.035*
20,1,.006,-.035,.035,.035,.035,0.0*
1,1,.006,.035,.035*
1,1,.006,-.035,.0175*
20,1,.006,-.035,.0175,-.03967,.01633,0.0*
1,1,.006,-.03967,.01633*
20,1,.006,-.03967,.01633,-.04317,.01342,0.0*
1,1,.006,-.04317,.01342*
20,1,.006,-.04317,.01342,-.0455,.00992,0.0*
1,1,.006,-.0455,.00992*
20,1,.006,-.0455,.00992,-.04725,.00525,0.0*
1,1,.006,-.04725,.00525*
20,1,.006,-.04725,.00525,-.04783,0.0,0.0*
1,1,.006,-.04783,0.0*
20,1,.006,-.04783,0.0,-.04725,-.00525,0.0*
1,1,.006,-.04725,-.00525*
20,1,.006,-.04725,-.00525,-.0455,-.00992,0.0*
1,1,.006,-.0455,-.00992*
20,1,.006,-.0455,-.00992,-.04317,-.01342,0.0*
1,1,.006,-.04317,-.01342*
20,1,.006,-.04317,-.01342,-.03967,-.01633,0.0*
1,1,.006,-.03967,-.01633*
20,1,.006,-.03967,-.01633,-.035,-.0175,0.0*
1,1,.006,-.035,-.0175*
20,1,.006,-.035,-.0175,-.03033,-.01633,0.0*
1,1,.006,-.03033,-.01633*
20,1,.006,-.03033,-.01633,-.02683,-.01342,0.0*
1,1,.006,-.02683,-.01342*
20,1,.006,-.02683,-.01342,-.0245,-.00992,0.0*
1,1,.006,-.0245,-.00992*
20,1,.006,-.0245,-.00992,-.02275,-.00525,0.0*
1,1,.006,-.02275,-.00525*
20,1,.006,-.02275,-.00525,-.02217,0.0,0.0*
1,1,.006,-.02217,0.0*
20,1,.006,-.02217,0.0,-.02275,.00525,0.0*
1,1,.006,-.02275,.00525*
20,1,.006,-.02275,.00525,-.0245,.00992,0.0*
1,1,.006,-.0245,.00992*
20,1,.006,-.0245,.00992,-.02683,.01342,0.0*
1,1,.006,-.02683,.01342*
20,1,.006,-.02683,.01342,-.03033,.01633,0.0*
1,1,.006,-.03033,.01633*
20,1,.006,-.03033,.01633,-.035,.0175,0.0*
1,1,.006,-.035,.0175*
1,1,.006,-.01107,.01167*
20,1,.006,-.01107,.01167,-.00757,.01517,0.0*
1,1,.006,-.00757,.01517*
20,1,.006,-.00757,.01517,-.00349,.01692,0.0*
1,1,.006,-.00349,.01692*
20,1,.006,-.00349,.01692,.00118,.0175,0.0*
1,1,.006,.00118,.0175*
20,1,.006,.00118,.0175,.00701,.01633,0.0*
1,1,.006,.00701,.01633*
20,1,.006,.00701,.01633,.01109,.01342,0.0*
1,1,.006,.01109,.01342*
20,1,.006,.01109,.01342,.01226,.00992,0.0*
1,1,.006,.01226,.00992*
20,1,.006,.01226,.00992,.01168,.00642,0.0*
1,1,.006,.01168,.00642*
20,1,.006,.01168,.00642,.00934,.0035,0.0*
1,1,.006,.00934,.0035*
20,1,.006,.00934,.0035,-.00232,-.00233,0.0*
1,1,.006,-.00232,-.00233*
20,1,.006,-.00232,-.00233,-.00757,-.00642,0.0*
1,1,.006,-.00757,-.00642*
20,1,.006,-.00757,-.00642,-.01107,-.01225,0.0*
1,1,.006,-.01107,-.01225*
20,1,.006,-.01107,-.01225,-.01224,-.0175,0.0*
1,1,.006,-.01224,-.0175*
20,1,.006,-.01224,-.0175,.01226,-.0175,0.0*
1,1,.006,.01226,-.0175*
1,1,.006,.02394,.01167*
20,1,.006,.02394,.01167,.02744,.01517,0.0*
1,1,.006,.02744,.01517*
20,1,.006,.02744,.01517,.03152,.01692,0.0*
1,1,.006,.03152,.01692*
20,1,.006,.03152,.01692,.03619,.0175,0.0*
1,1,.006,.03619,.0175*
20,1,.006,.03619,.0175,.04202,.01633,0.0*
1,1,.006,.04202,.01633*
20,1,.006,.04202,.01633,.0461,.01342,0.0*
1,1,.006,.0461,.01342*
20,1,.006,.0461,.01342,.04727,.00992,0.0*
1,1,.006,.04727,.00992*
20,1,.006,.04727,.00992,.04669,.00642,0.0*
1,1,.006,.04669,.00642*
20,1,.006,.04669,.00642,.04435,.0035,0.0*
1,1,.006,.04435,.0035*
20,1,.006,.04435,.0035,.03269,-.00233,0.0*
1,1,.006,.03269,-.00233*
20,1,.006,.03269,-.00233,.02744,-.00642,0.0*
1,1,.006,.02744,-.00642*
20,1,.006,.02744,-.00642,.02394,-.01225,0.0*
1,1,.006,.02394,-.01225*
20,1,.006,.02394,-.01225,.02277,-.0175,0.0*
1,1,.006,.02277,-.0175*
20,1,.006,.02277,-.0175,.04727,-.0175,0.0*
1,1,.006,.04727,-.0175*
%
%ADD10MACRO10*%
%AMMACRO26*
1,1,.006,.035,.035*
20,1,.006,.035,.035,.035,-.035,0.0*
1,1,.006,.035,-.035*
20,1,.006,.035,-.035,-.035,-.035,0.0*
1,1,.006,-.035,-.035*
20,1,.006,-.035,-.035,-.035,.035,0.0*
1,1,.006,-.035,.035*
20,1,.006,-.035,.035,.035,.035,0.0*
1,1,.006,.035,.035*
1,1,.006,-.035,.0175*
20,1,.006,-.035,.0175,-.03967,.01633,0.0*
1,1,.006,-.03967,.01633*
20,1,.006,-.03967,.01633,-.04317,.01342,0.0*
1,1,.006,-.04317,.01342*
20,1,.006,-.04317,.01342,-.0455,.00992,0.0*
1,1,.006,-.0455,.00992*
20,1,.006,-.0455,.00992,-.04725,.00525,0.0*
1,1,.006,-.04725,.00525*
20,1,.006,-.04725,.00525,-.04783,0.0,0.0*
1,1,.006,-.04783,0.0*
20,1,.006,-.04783,0.0,-.04725,-.00525,0.0*
1,1,.006,-.04725,-.00525*
20,1,.006,-.04725,-.00525,-.0455,-.00992,0.0*
1,1,.006,-.0455,-.00992*
20,1,.006,-.0455,-.00992,-.04317,-.01342,0.0*
1,1,.006,-.04317,-.01342*
20,1,.006,-.04317,-.01342,-.03967,-.01633,0.0*
1,1,.006,-.03967,-.01633*
20,1,.006,-.03967,-.01633,-.035,-.0175,0.0*
1,1,.006,-.035,-.0175*
20,1,.006,-.035,-.0175,-.03033,-.01633,0.0*
1,1,.006,-.03033,-.01633*
20,1,.006,-.03033,-.01633,-.02683,-.01342,0.0*
1,1,.006,-.02683,-.01342*
20,1,.006,-.02683,-.01342,-.0245,-.00992,0.0*
1,1,.006,-.0245,-.00992*
20,1,.006,-.0245,-.00992,-.02275,-.00525,0.0*
1,1,.006,-.02275,-.00525*
20,1,.006,-.02275,-.00525,-.02217,0.0,0.0*
1,1,.006,-.02217,0.0*
20,1,.006,-.02217,0.0,-.02275,.00525,0.0*
1,1,.006,-.02275,.00525*
20,1,.006,-.02275,.00525,-.0245,.00992,0.0*
1,1,.006,-.0245,.00992*
20,1,.006,-.0245,.00992,-.02683,.01342,0.0*
1,1,.006,-.02683,.01342*
20,1,.006,-.02683,.01342,-.03033,.01633,0.0*
1,1,.006,-.03033,.01633*
20,1,.006,-.03033,.01633,-.035,.0175,0.0*
1,1,.006,-.035,.0175*
1,1,.006,-.01282,-.0105*
20,1,.006,-.01282,-.0105,-.00932,-.01458,0.0*
1,1,.006,-.00932,-.01458*
20,1,.006,-.00932,-.01458,-.00466,-.01692,0.0*
1,1,.006,-.00466,-.01692*
20,1,.006,-.00466,-.01692,.00059,-.0175,0.0*
1,1,.006,.00059,-.0175*
20,1,.006,.00059,-.0175,.00526,-.01692,0.0*
1,1,.006,.00526,-.01692*
20,1,.006,.00526,-.01692,.00993,-.014,0.0*
1,1,.006,.00993,-.014*
20,1,.006,.00993,-.014,.01284,-.0105,0.0*
1,1,.006,.01284,-.0105*
20,1,.006,.01284,-.0105,.01343,-.007,0.0*
1,1,.006,.01343,-.007*
20,1,.006,.01343,-.007,.01226,-.00292,0.0*
1,1,.006,.01226,-.00292*
20,1,.006,.01226,-.00292,.00818,0.0,0.0*
1,1,.006,.00818,0.0*
20,1,.006,.00818,0.0,.00409,.00117,0.0*
1,1,.006,.00409,.00117*
20,1,.006,.00409,.00117,-.00116,.00117,0.0*
1,1,.006,-.00116,.00117*
1,1,.006,.00409,.00117*
20,1,.006,.00409,.00117,.00759,.00292,0.0*
1,1,.006,.00759,.00292*
20,1,.006,.00759,.00292,.01051,.00583,0.0*
1,1,.006,.01051,.00583*
20,1,.006,.01051,.00583,.01168,.00933,0.0*
1,1,.006,.01168,.00933*
20,1,.006,.01168,.00933,.01051,.01283,0.0*
1,1,.006,.01051,.01283*
20,1,.006,.01051,.01283,.00759,.01575,0.0*
1,1,.006,.00759,.01575*
20,1,.006,.00759,.01575,.00234,.0175,0.0*
1,1,.006,.00234,.0175*
20,1,.006,.00234,.0175,-.00291,.01692,0.0*
1,1,.006,-.00291,.01692*
20,1,.006,-.00291,.01692,-.00816,.01458,0.0*
1,1,.006,-.00816,.01458*
1,1,.006,.02219,-.01225*
20,1,.006,.02219,-.01225,.02569,-.01517,0.0*
1,1,.006,.02569,-.01517*
20,1,.006,.02569,-.01517,.02977,-.01692,0.0*
1,1,.006,.02977,-.01692*
20,1,.006,.02977,-.01692,.03502,-.0175,0.0*
1,1,.006,.03502,-.0175*
20,1,.006,.03502,-.0175,.04027,-.01633,0.0*
1,1,.006,.04027,-.01633*
20,1,.006,.04027,-.01633,.04435,-.014,0.0*
1,1,.006,.04435,-.014*
20,1,.006,.04435,-.014,.04727,-.00992,0.0*
1,1,.006,.04727,-.00992*
20,1,.006,.04727,-.00992,.04785,-.00525,0.0*
1,1,.006,.04785,-.00525*
20,1,.006,.04785,-.00525,.04669,-.00058,0.0*
1,1,.006,.04669,-.00058*
20,1,.006,.04669,-.00058,.04377,.00233,0.0*
1,1,.006,.04377,.00233*
20,1,.006,.04377,.00233,.03969,.00467,0.0*
1,1,.006,.03969,.00467*
20,1,.006,.03969,.00467,.0356,.00525,0.0*
1,1,.006,.0356,.00525*
20,1,.006,.0356,.00525,.03152,.00467,0.0*
1,1,.006,.03152,.00467*
20,1,.006,.03152,.00467,.02627,.00233,0.0*
1,1,.006,.02627,.00233*
20,1,.006,.02627,.00233,.02802,.0175,0.0*
1,1,.006,.02802,.0175*
20,1,.006,.02802,.0175,.04377,.0175,0.0*
1,1,.006,.04377,.0175*
%
%ADD26MACRO26*%
%AMMACRO19*
1,1,.006,.035,.035*
20,1,.006,.035,.035,.035,-.035,0.0*
1,1,.006,.035,-.035*
20,1,.006,.035,-.035,-.035,-.035,0.0*
1,1,.006,-.035,-.035*
20,1,.006,-.035,-.035,-.035,.035,0.0*
1,1,.006,-.035,.035*
20,1,.006,-.035,.035,.035,.035,0.0*
1,1,.006,.035,.035*
1,1,.006,-.035,.0175*
20,1,.006,-.035,.0175,-.03967,.01633,0.0*
1,1,.006,-.03967,.01633*
20,1,.006,-.03967,.01633,-.04317,.01342,0.0*
1,1,.006,-.04317,.01342*
20,1,.006,-.04317,.01342,-.0455,.00992,0.0*
1,1,.006,-.0455,.00992*
20,1,.006,-.0455,.00992,-.04725,.00525,0.0*
1,1,.006,-.04725,.00525*
20,1,.006,-.04725,.00525,-.04783,0.0,0.0*
1,1,.006,-.04783,0.0*
20,1,.006,-.04783,0.0,-.04725,-.00525,0.0*
1,1,.006,-.04725,-.00525*
20,1,.006,-.04725,-.00525,-.0455,-.00992,0.0*
1,1,.006,-.0455,-.00992*
20,1,.006,-.0455,-.00992,-.04317,-.01342,0.0*
1,1,.006,-.04317,-.01342*
20,1,.006,-.04317,-.01342,-.03967,-.01633,0.0*
1,1,.006,-.03967,-.01633*
20,1,.006,-.03967,-.01633,-.035,-.0175,0.0*
1,1,.006,-.035,-.0175*
20,1,.006,-.035,-.0175,-.03033,-.01633,0.0*
1,1,.006,-.03033,-.01633*
20,1,.006,-.03033,-.01633,-.02683,-.01342,0.0*
1,1,.006,-.02683,-.01342*
20,1,.006,-.02683,-.01342,-.0245,-.00992,0.0*
1,1,.006,-.0245,-.00992*
20,1,.006,-.0245,-.00992,-.02275,-.00525,0.0*
1,1,.006,-.02275,-.00525*
20,1,.006,-.02275,-.00525,-.02217,0.0,0.0*
1,1,.006,-.02217,0.0*
20,1,.006,-.02217,0.0,-.02275,.00525,0.0*
1,1,.006,-.02275,.00525*
20,1,.006,-.02275,.00525,-.0245,.00992,0.0*
1,1,.006,-.0245,.00992*
20,1,.006,-.0245,.00992,-.02683,.01342,0.0*
1,1,.006,-.02683,.01342*
20,1,.006,-.02683,.01342,-.03033,.01633,0.0*
1,1,.006,-.03033,.01633*
20,1,.006,-.03033,.01633,-.035,.0175,0.0*
1,1,.006,-.035,.0175*
1,1,.006,-.01282,-.0105*
20,1,.006,-.01282,-.0105,-.00932,-.01458,0.0*
1,1,.006,-.00932,-.01458*
20,1,.006,-.00932,-.01458,-.00466,-.01692,0.0*
1,1,.006,-.00466,-.01692*
20,1,.006,-.00466,-.01692,.00059,-.0175,0.0*
1,1,.006,.00059,-.0175*
20,1,.006,.00059,-.0175,.00526,-.01692,0.0*
1,1,.006,.00526,-.01692*
20,1,.006,.00526,-.01692,.00993,-.014,0.0*
1,1,.006,.00993,-.014*
20,1,.006,.00993,-.014,.01284,-.0105,0.0*
1,1,.006,.01284,-.0105*
20,1,.006,.01284,-.0105,.01343,-.007,0.0*
1,1,.006,.01343,-.007*
20,1,.006,.01343,-.007,.01226,-.00292,0.0*
1,1,.006,.01226,-.00292*
20,1,.006,.01226,-.00292,.00818,0.0,0.0*
1,1,.006,.00818,0.0*
20,1,.006,.00818,0.0,.00409,.00117,0.0*
1,1,.006,.00409,.00117*
20,1,.006,.00409,.00117,-.00116,.00117,0.0*
1,1,.006,-.00116,.00117*
1,1,.006,.00409,.00117*
20,1,.006,.00409,.00117,.00759,.00292,0.0*
1,1,.006,.00759,.00292*
20,1,.006,.00759,.00292,.01051,.00583,0.0*
1,1,.006,.01051,.00583*
20,1,.006,.01051,.00583,.01168,.00933,0.0*
1,1,.006,.01168,.00933*
20,1,.006,.01168,.00933,.01051,.01283,0.0*
1,1,.006,.01051,.01283*
20,1,.006,.01051,.01283,.00759,.01575,0.0*
1,1,.006,.00759,.01575*
20,1,.006,.00759,.01575,.00234,.0175,0.0*
1,1,.006,.00234,.0175*
20,1,.006,.00234,.0175,-.00291,.01692,0.0*
1,1,.006,-.00291,.01692*
20,1,.006,-.00291,.01692,-.00816,.01458,0.0*
1,1,.006,-.00816,.01458*
1,1,.006,.03502,-.0175*
20,1,.006,.03502,-.0175,.0391,-.01692,0.0*
1,1,.006,.0391,-.01692*
20,1,.006,.0391,-.01692,.04377,-.01517,0.0*
1,1,.006,.04377,-.01517*
20,1,.006,.04377,-.01517,.04669,-.01225,0.0*
1,1,.006,.04669,-.01225*
20,1,.006,.04669,-.01225,.04785,-.00817,0.0*
1,1,.006,.04785,-.00817*
20,1,.006,.04785,-.00817,.04669,-.00408,0.0*
1,1,.006,.04669,-.00408*
20,1,.006,.04669,-.00408,.04319,-.00058,0.0*
1,1,.006,.04319,-.00058*
20,1,.006,.04319,-.00058,.03794,.00117,0.0*
1,1,.006,.03794,.00117*
20,1,.006,.03794,.00117,.0321,.00117,0.0*
1,1,.006,.0321,.00117*
20,1,.006,.0321,.00117,.0286,.00233,0.0*
1,1,.006,.0286,.00233*
20,1,.006,.0286,.00233,.02569,.00525,0.0*
1,1,.006,.02569,.00525*
20,1,.006,.02569,.00525,.02452,.00933,0.0*
1,1,.006,.02452,.00933*
20,1,.006,.02452,.00933,.02627,.01342,0.0*
1,1,.006,.02627,.01342*
20,1,.006,.02627,.01342,.03035,.01633,0.0*
1,1,.006,.03035,.01633*
20,1,.006,.03035,.01633,.03502,.0175,0.0*
1,1,.006,.03502,.0175*
20,1,.006,.03502,.0175,.03969,.01633,0.0*
1,1,.006,.03969,.01633*
20,1,.006,.03969,.01633,.04377,.01342,0.0*
1,1,.006,.04377,.01342*
20,1,.006,.04377,.01342,.04552,.00933,0.0*
1,1,.006,.04552,.00933*
20,1,.006,.04552,.00933,.04435,.00525,0.0*
1,1,.006,.04435,.00525*
20,1,.006,.04435,.00525,.04144,.00233,0.0*
1,1,.006,.04144,.00233*
20,1,.006,.04144,.00233,.03794,.00117,0.0*
1,1,.006,.03794,.00117*
20,1,.006,.03794,.00117,.0321,.00117,0.0*
1,1,.006,.0321,.00117*
20,1,.006,.0321,.00117,.02685,-.00058,0.0*
1,1,.006,.02685,-.00058*
20,1,.006,.02685,-.00058,.02335,-.00408,0.0*
1,1,.006,.02335,-.00408*
20,1,.006,.02335,-.00408,.02219,-.00817,0.0*
1,1,.006,.02219,-.00817*
20,1,.006,.02219,-.00817,.02335,-.01225,0.0*
1,1,.006,.02335,-.01225*
20,1,.006,.02335,-.01225,.02627,-.01517,0.0*
1,1,.006,.02627,-.01517*
20,1,.006,.02627,-.01517,.03094,-.01692,0.0*
1,1,.006,.03094,-.01692*
20,1,.006,.03094,-.01692,.03502,-.0175,0.0*
1,1,.006,.03502,-.0175*
%
%ADD19MACRO19*%
%AMMACRO13*
1,1,.006,.069,0.0*
20,1,.006,.069,0.0,.0345,.059756,0.0*
1,1,.006,.0345,.059756*
20,1,.006,.0345,.059756,-.0345,.059756,0.0*
1,1,.006,-.0345,.059756*
20,1,.006,-.0345,.059756,-.069,0.0,0.0*
1,1,.006,-.069,0.0*
20,1,.006,-.069,0.0,-.0345,-.059756,0.0*
1,1,.006,-.0345,-.059756*
20,1,.006,-.0345,-.059756,.0345,-.059756,0.0*
1,1,.006,.0345,-.059756*
20,1,.006,.0345,-.059756,.069,0.0,0.0*
1,1,.006,.069,0.0*
1,1,.006,-.0483,-.0575*
20,1,.006,-.0483,-.0575,-.0483,.0115,0.0*
1,1,.006,-.0483,.0115*
1,1,.006,-.0483,.00115*
20,1,.006,-.0483,.00115,-.05405,.0069,0.0*
1,1,.006,-.05405,.0069*
20,1,.006,-.05405,.0069,-.06095,.01035,0.0*
1,1,.006,-.06095,.01035*
20,1,.006,-.06095,.01035,-.069,.0115,0.0*
1,1,.006,-.069,.0115*
20,1,.006,-.069,.0115,-.0759,.01035,0.0*
1,1,.006,-.0759,.01035*
20,1,.006,-.0759,.01035,-.08395,.0046,0.0*
1,1,.006,-.08395,.0046*
20,1,.006,-.08395,.0046,-.08855,-.00345,0.0*
1,1,.006,-.08855,-.00345*
20,1,.006,-.08855,-.00345,-.0897,-.0115,0.0*
1,1,.006,-.0897,-.0115*
20,1,.006,-.0897,-.0115,-.08855,-.01955,0.0*
1,1,.006,-.08855,-.01955*
20,1,.006,-.08855,-.01955,-.08395,-.0276,0.0*
1,1,.006,-.08395,-.0276*
20,1,.006,-.08395,-.0276,-.0759,-.03335,0.0*
1,1,.006,-.0759,-.03335*
20,1,.006,-.0759,-.03335,-.069,-.0345,0.0*
1,1,.006,-.069,-.0345*
20,1,.006,-.069,-.0345,-.06095,-.03335,0.0*
1,1,.006,-.06095,-.03335*
20,1,.006,-.06095,-.03335,-.05405,-.0299,0.0*
1,1,.006,-.05405,-.0299*
20,1,.006,-.05405,-.0299,-.0483,-.02415,0.0*
1,1,.006,-.0483,-.02415*
1,1,.006,-.01724,-.00345*
20,1,.006,-.01724,-.00345,.01956,-.00345,0.0*
1,1,.006,.01956,-.00345*
20,1,.006,.01956,-.00345,.01611,.0046,0.0*
1,1,.006,.01611,.0046*
20,1,.006,.01611,.0046,.01036,.0092,0.0*
1,1,.006,.01036,.0092*
20,1,.006,.01036,.0092,.00231,.0115,0.0*
1,1,.006,.00231,.0115*
20,1,.006,.00231,.0115,-.00574,.01035,0.0*
1,1,.006,-.00574,.01035*
20,1,.006,-.00574,.01035,-.01264,.0069,0.0*
1,1,.006,-.01264,.0069*
20,1,.006,-.01264,.0069,-.01724,-.00115,0.0*
1,1,.006,-.01724,-.00115*
20,1,.006,-.01724,-.00115,-.01954,-.00805,0.0*
1,1,.006,-.01954,-.00805*
20,1,.006,-.01954,-.00805,-.01954,-.01495,0.0*
1,1,.006,-.01954,-.01495*
20,1,.006,-.01954,-.01495,-.01724,-.02185,0.0*
1,1,.006,-.01724,-.02185*
20,1,.006,-.01724,-.02185,-.01149,-.02875,0.0*
1,1,.006,-.01149,-.02875*
20,1,.006,-.01149,-.02875,-.00459,-.03335,0.0*
1,1,.006,-.00459,-.03335*
20,1,.006,-.00459,-.03335,.00346,-.0345,0.0*
1,1,.006,.00346,-.0345*
20,1,.006,.00346,-.0345,.01151,-.0322,0.0*
1,1,.006,.01151,-.0322*
20,1,.006,.01151,-.0322,.01956,-.0253,0.0*
1,1,.006,.01956,-.0253*
1,1,.006,.06902,.0115*
20,1,.006,.06902,.0115,.06902,-.0345,0.0*
1,1,.006,.06902,-.0345*
1,1,.006,.06902,.0299*
20,1,.006,.06902,.0299,.06672,.03105,0.0*
1,1,.006,.06672,.03105*
20,1,.006,.06672,.03105,.06672,.03335,0.0*
1,1,.006,.06672,.03335*
20,1,.006,.06672,.03335,.06902,.0345,0.0*
1,1,.006,.06902,.0345*
20,1,.006,.06902,.0345,.07132,.03335,0.0*
1,1,.006,.07132,.03335*
20,1,.006,.07132,.03335,.07132,.03105,0.0*
1,1,.006,.07132,.03105*
20,1,.006,.07132,.03105,.06902,.0299,0.0*
1,1,.006,.06902,.0299*
%
%ADD13MACRO13*%
%AMMACRO14*
1,1,.006,0.0,.035*
20,1,.006,0.0,.035,.035,-.035,0.0*
1,1,.006,.035,-.035*
20,1,.006,.035,-.035,-.035,-.035,0.0*
1,1,.006,-.035,-.035*
20,1,.006,-.035,-.035,0.0,.035,0.0*
1,1,.006,0.0,.035*
1,1,.006,-.0455,-.02917*
20,1,.006,-.0455,-.02917,-.0455,.00583,0.0*
1,1,.006,-.0455,.00583*
1,1,.006,-.0455,.00058*
20,1,.006,-.0455,.00058,-.04258,.0035,0.0*
1,1,.006,-.04258,.0035*
20,1,.006,-.04258,.0035,-.03967,.00525,0.0*
1,1,.006,-.03967,.00525*
20,1,.006,-.03967,.00525,-.035,.00583,0.0*
1,1,.006,-.035,.00583*
20,1,.006,-.035,.00583,-.03092,.00525,0.0*
1,1,.006,-.03092,.00525*
20,1,.006,-.03092,.00525,-.02683,.00233,0.0*
1,1,.006,-.02683,.00233*
20,1,.006,-.02683,.00233,-.02508,-.00175,0.0*
1,1,.006,-.02508,-.00175*
20,1,.006,-.02508,-.00175,-.0245,-.00583,0.0*
1,1,.006,-.0245,-.00583*
20,1,.006,-.0245,-.00583,-.02508,-.00992,0.0*
1,1,.006,-.02508,-.00992*
20,1,.006,-.02508,-.00992,-.02683,-.014,0.0*
1,1,.006,-.02683,-.014*
20,1,.006,-.02683,-.014,-.03033,-.01633,0.0*
1,1,.006,-.03033,-.01633*
20,1,.006,-.03033,-.01633,-.035,-.0175,0.0*
1,1,.006,-.035,-.0175*
20,1,.006,-.035,-.0175,-.03908,-.01692,0.0*
1,1,.006,-.03908,-.01692*
20,1,.006,-.03908,-.01692,-.04317,-.01517,0.0*
1,1,.006,-.04317,-.01517*
20,1,.006,-.04317,-.01517,-.0455,-.01283,0.0*
1,1,.006,-.0455,-.01283*
1,1,.006,-.00816,-.0175*
20,1,.006,-.00816,-.0175,-.00816,.00583,0.0*
1,1,.006,-.00816,.00583*
1,1,.006,-.00816,.00117*
20,1,.006,-.00816,.00117,-.00524,.0035,0.0*
1,1,.006,-.00524,.0035*
20,1,.006,-.00524,.0035,-.00232,.00525,0.0*
1,1,.006,-.00232,.00525*
20,1,.006,-.00232,.00525,.00176,.00583,0.0*
1,1,.006,.00176,.00583*
20,1,.006,.00176,.00583,.00468,.00525,0.0*
1,1,.006,.00468,.00525*
20,1,.006,.00468,.00525,.00818,.0035,0.0*
1,1,.006,.00818,.0035*
1,1,.006,.02627,-.00175*
20,1,.006,.02627,-.00175,.04494,-.00175,0.0*
1,1,.006,.04494,-.00175*
20,1,.006,.04494,-.00175,.04319,.00233,0.0*
1,1,.006,.04319,.00233*
20,1,.006,.04319,.00233,.04027,.00467,0.0*
1,1,.006,.04027,.00467*
20,1,.006,.04027,.00467,.03619,.00583,0.0*
1,1,.006,.03619,.00583*
20,1,.006,.03619,.00583,.0321,.00525,0.0*
1,1,.006,.0321,.00525*
20,1,.006,.0321,.00525,.0286,.0035,0.0*
1,1,.006,.0286,.0035*
20,1,.006,.0286,.0035,.02627,-.00058,0.0*
1,1,.006,.02627,-.00058*
20,1,.006,.02627,-.00058,.0251,-.00408,0.0*
1,1,.006,.0251,-.00408*
20,1,.006,.0251,-.00408,.0251,-.00758,0.0*
1,1,.006,.0251,-.00758*
20,1,.006,.0251,-.00758,.02627,-.01108,0.0*
1,1,.006,.02627,-.01108*
20,1,.006,.02627,-.01108,.02919,-.01458,0.0*
1,1,.006,.02919,-.01458*
20,1,.006,.02919,-.01458,.03269,-.01692,0.0*
1,1,.006,.03269,-.01692*
20,1,.006,.03269,-.01692,.03677,-.0175,0.0*
1,1,.006,.03677,-.0175*
20,1,.006,.03677,-.0175,.04085,-.01633,0.0*
1,1,.006,.04085,-.01633*
20,1,.006,.04085,-.01633,.04494,-.01283,0.0*
1,1,.006,.04494,-.01283*
%
%ADD14MACRO14*%
%AMMACRO20*
1,1,.006,.035,0.0*
20,1,.006,.035,0.0,.034468,-.006078,0.0*
1,1,.006,.034468,-.006078*
20,1,.006,.034468,-.006078,.032889,-.011971,0.0*
1,1,.006,.032889,-.011971*
20,1,.006,.032889,-.011971,.030311,-.0175,0.0*
1,1,.006,.030311,-.0175*
20,1,.006,.030311,-.0175,.026812,-.022498,0.0*
1,1,.006,.026812,-.022498*
20,1,.006,.026812,-.022498,.022498,-.026812,0.0*
1,1,.006,.022498,-.026812*
20,1,.006,.022498,-.026812,.0175,-.030311,0.0*
1,1,.006,.0175,-.030311*
20,1,.006,.0175,-.030311,.011971,-.032889,0.0*
1,1,.006,.011971,-.032889*
20,1,.006,.011971,-.032889,.006078,-.034468,0.0*
1,1,.006,.006078,-.034468*
20,1,.006,.006078,-.034468,0.0,-.035,0.0*
1,1,.006,0.0,-.035*
20,1,.006,0.0,-.035,-.006078,-.034468,0.0*
1,1,.006,-.006078,-.034468*
20,1,.006,-.006078,-.034468,-.011971,-.032889,0.0*
1,1,.006,-.011971,-.032889*
20,1,.006,-.011971,-.032889,-.0175,-.030311,0.0*
1,1,.006,-.0175,-.030311*
20,1,.006,-.0175,-.030311,-.022498,-.026812,0.0*
1,1,.006,-.022498,-.026812*
20,1,.006,-.022498,-.026812,-.026812,-.022498,0.0*
1,1,.006,-.026812,-.022498*
20,1,.006,-.026812,-.022498,-.030311,-.0175,0.0*
1,1,.006,-.030311,-.0175*
20,1,.006,-.030311,-.0175,-.032889,-.011971,0.0*
1,1,.006,-.032889,-.011971*
20,1,.006,-.032889,-.011971,-.034468,-.006078,0.0*
1,1,.006,-.034468,-.006078*
20,1,.006,-.034468,-.006078,-.035,0.0,0.0*
1,1,.006,-.035,0.0*
20,1,.006,-.035,0.0,-.034468,.006078,0.0*
1,1,.006,-.034468,.006078*
20,1,.006,-.034468,.006078,-.032889,.011971,0.0*
1,1,.006,-.032889,.011971*
20,1,.006,-.032889,.011971,-.030311,.0175,0.0*
1,1,.006,-.030311,.0175*
20,1,.006,-.030311,.0175,-.026812,.022498,0.0*
1,1,.006,-.026812,.022498*
20,1,.006,-.026812,.022498,-.022498,.026812,0.0*
1,1,.006,-.022498,.026812*
20,1,.006,-.022498,.026812,-.0175,.030311,0.0*
1,1,.006,-.0175,.030311*
20,1,.006,-.0175,.030311,-.011971,.032889,0.0*
1,1,.006,-.011971,.032889*
20,1,.006,-.011971,.032889,-.006078,.034468,0.0*
1,1,.006,-.006078,.034468*
20,1,.006,-.006078,.034468,0.0,.035,0.0*
1,1,.006,0.0,.035*
20,1,.006,0.0,.035,.006078,.034468,0.0*
1,1,.006,.006078,.034468*
20,1,.006,.006078,.034468,.011971,.032889,0.0*
1,1,.006,.011971,.032889*
20,1,.006,.011971,.032889,.0175,.030311,0.0*
1,1,.006,.0175,.030311*
20,1,.006,.0175,.030311,.022498,.026812,0.0*
1,1,.006,.022498,.026812*
20,1,.006,.022498,.026812,.026812,.022498,0.0*
1,1,.006,.026812,.022498*
20,1,.006,.026812,.022498,.030311,.0175,0.0*
1,1,.006,.030311,.0175*
20,1,.006,.030311,.0175,.032889,.011971,0.0*
1,1,.006,.032889,.011971*
20,1,.006,.032889,.011971,.034468,.006078,0.0*
1,1,.006,.034468,.006078*
20,1,.006,.034468,.006078,.035,0.0,0.0*
1,1,.006,.035,0.0*
1,1,.006,-.04958,.0175*
20,1,.006,-.04958,.0175,-.035,-.0175,0.0*
1,1,.006,-.035,-.0175*
20,1,.006,-.035,-.0175,-.02042,.0175,0.0*
1,1,.006,-.02042,.0175*
1,1,.006,.00001,-.0175*
20,1,.006,.00001,-.0175,.00001,.0175,0.0*
1,1,.006,.00001,.0175*
20,1,.006,.00001,.0175,-.00699,.0105,0.0*
1,1,.006,-.00699,.0105*
1,1,.006,-.00699,-.0175*
20,1,.006,-.00699,-.0175,.00701,-.0175,0.0*
1,1,.006,.00701,-.0175*
1,1,.006,.03502,.0175*
20,1,.006,.03502,.0175,.03035,.01633,0.0*
1,1,.006,.03035,.01633*
20,1,.006,.03035,.01633,.02685,.01342,0.0*
1,1,.006,.02685,.01342*
20,1,.006,.02685,.01342,.02452,.00992,0.0*
1,1,.006,.02452,.00992*
20,1,.006,.02452,.00992,.02277,.00525,0.0*
1,1,.006,.02277,.00525*
20,1,.006,.02277,.00525,.02219,0.0,0.0*
1,1,.006,.02219,0.0*
20,1,.006,.02219,0.0,.02277,-.00525,0.0*
1,1,.006,.02277,-.00525*
20,1,.006,.02277,-.00525,.02452,-.00992,0.0*
1,1,.006,.02452,-.00992*
20,1,.006,.02452,-.00992,.02685,-.01342,0.0*
1,1,.006,.02685,-.01342*
20,1,.006,.02685,-.01342,.03035,-.01633,0.0*
1,1,.006,.03035,-.01633*
20,1,.006,.03035,-.01633,.03502,-.0175,0.0*
1,1,.006,.03502,-.0175*
20,1,.006,.03502,-.0175,.03969,-.01633,0.0*
1,1,.006,.03969,-.01633*
20,1,.006,.03969,-.01633,.04319,-.01342,0.0*
1,1,.006,.04319,-.01342*
20,1,.006,.04319,-.01342,.04552,-.00992,0.0*
1,1,.006,.04552,-.00992*
20,1,.006,.04552,-.00992,.04727,-.00525,0.0*
1,1,.006,.04727,-.00525*
20,1,.006,.04727,-.00525,.04785,0.0,0.0*
1,1,.006,.04785,0.0*
20,1,.006,.04785,0.0,.04727,.00525,0.0*
1,1,.006,.04727,.00525*
20,1,.006,.04727,.00525,.04552,.00992,0.0*
1,1,.006,.04552,.00992*
20,1,.006,.04552,.00992,.04319,.01342,0.0*
1,1,.006,.04319,.01342*
20,1,.006,.04319,.01342,.03969,.01633,0.0*
1,1,.006,.03969,.01633*
20,1,.006,.03969,.01633,.03502,.0175,0.0*
1,1,.006,.03502,.0175*
%
%ADD20MACRO20*%
%AMMACRO16*
1,1,.006,.035,0.0*
20,1,.006,.035,0.0,.034468,-.006078,0.0*
1,1,.006,.034468,-.006078*
20,1,.006,.034468,-.006078,.032889,-.011971,0.0*
1,1,.006,.032889,-.011971*
20,1,.006,.032889,-.011971,.030311,-.0175,0.0*
1,1,.006,.030311,-.0175*
20,1,.006,.030311,-.0175,.026812,-.022498,0.0*
1,1,.006,.026812,-.022498*
20,1,.006,.026812,-.022498,.022498,-.026812,0.0*
1,1,.006,.022498,-.026812*
20,1,.006,.022498,-.026812,.0175,-.030311,0.0*
1,1,.006,.0175,-.030311*
20,1,.006,.0175,-.030311,.011971,-.032889,0.0*
1,1,.006,.011971,-.032889*
20,1,.006,.011971,-.032889,.006078,-.034468,0.0*
1,1,.006,.006078,-.034468*
20,1,.006,.006078,-.034468,0.0,-.035,0.0*
1,1,.006,0.0,-.035*
20,1,.006,0.0,-.035,-.006078,-.034468,0.0*
1,1,.006,-.006078,-.034468*
20,1,.006,-.006078,-.034468,-.011971,-.032889,0.0*
1,1,.006,-.011971,-.032889*
20,1,.006,-.011971,-.032889,-.0175,-.030311,0.0*
1,1,.006,-.0175,-.030311*
20,1,.006,-.0175,-.030311,-.022498,-.026812,0.0*
1,1,.006,-.022498,-.026812*
20,1,.006,-.022498,-.026812,-.026812,-.022498,0.0*
1,1,.006,-.026812,-.022498*
20,1,.006,-.026812,-.022498,-.030311,-.0175,0.0*
1,1,.006,-.030311,-.0175*
20,1,.006,-.030311,-.0175,-.032889,-.011971,0.0*
1,1,.006,-.032889,-.011971*
20,1,.006,-.032889,-.011971,-.034468,-.006078,0.0*
1,1,.006,-.034468,-.006078*
20,1,.006,-.034468,-.006078,-.035,0.0,0.0*
1,1,.006,-.035,0.0*
20,1,.006,-.035,0.0,-.034468,.006078,0.0*
1,1,.006,-.034468,.006078*
20,1,.006,-.034468,.006078,-.032889,.011971,0.0*
1,1,.006,-.032889,.011971*
20,1,.006,-.032889,.011971,-.030311,.0175,0.0*
1,1,.006,-.030311,.0175*
20,1,.006,-.030311,.0175,-.026812,.022498,0.0*
1,1,.006,-.026812,.022498*
20,1,.006,-.026812,.022498,-.022498,.026812,0.0*
1,1,.006,-.022498,.026812*
20,1,.006,-.022498,.026812,-.0175,.030311,0.0*
1,1,.006,-.0175,.030311*
20,1,.006,-.0175,.030311,-.011971,.032889,0.0*
1,1,.006,-.011971,.032889*
20,1,.006,-.011971,.032889,-.006078,.034468,0.0*
1,1,.006,-.006078,.034468*
20,1,.006,-.006078,.034468,0.0,.035,0.0*
1,1,.006,0.0,.035*
20,1,.006,0.0,.035,.006078,.034468,0.0*
1,1,.006,.006078,.034468*
20,1,.006,.006078,.034468,.011971,.032889,0.0*
1,1,.006,.011971,.032889*
20,1,.006,.011971,.032889,.0175,.030311,0.0*
1,1,.006,.0175,.030311*
20,1,.006,.0175,.030311,.022498,.026812,0.0*
1,1,.006,.022498,.026812*
20,1,.006,.022498,.026812,.026812,.022498,0.0*
1,1,.006,.026812,.022498*
20,1,.006,.026812,.022498,.030311,.0175,0.0*
1,1,.006,.030311,.0175*
20,1,.006,.030311,.0175,.032889,.011971,0.0*
1,1,.006,.032889,.011971*
20,1,.006,.032889,.011971,.034468,.006078,0.0*
1,1,.006,.034468,.006078*
20,1,.006,.034468,.006078,.035,0.0,0.0*
1,1,.006,.035,0.0*
1,1,.006,-.04958,.0175*
20,1,.006,-.04958,.0175,-.035,-.0175,0.0*
1,1,.006,-.035,-.0175*
20,1,.006,-.035,-.0175,-.02042,.0175,0.0*
1,1,.006,-.02042,.0175*
1,1,.006,-.01107,.01167*
20,1,.006,-.01107,.01167,-.00757,.01517,0.0*
1,1,.006,-.00757,.01517*
20,1,.006,-.00757,.01517,-.00349,.01692,0.0*
1,1,.006,-.00349,.01692*
20,1,.006,-.00349,.01692,.00118,.0175,0.0*
1,1,.006,.00118,.0175*
20,1,.006,.00118,.0175,.00701,.01633,0.0*
1,1,.006,.00701,.01633*
20,1,.006,.00701,.01633,.01109,.01342,0.0*
1,1,.006,.01109,.01342*
20,1,.006,.01109,.01342,.01226,.00992,0.0*
1,1,.006,.01226,.00992*
20,1,.006,.01226,.00992,.01168,.00642,0.0*
1,1,.006,.01168,.00642*
20,1,.006,.01168,.00642,.00934,.0035,0.0*
1,1,.006,.00934,.0035*
20,1,.006,.00934,.0035,-.00232,-.00233,0.0*
1,1,.006,-.00232,-.00233*
20,1,.006,-.00232,-.00233,-.00757,-.00642,0.0*
1,1,.006,-.00757,-.00642*
20,1,.006,-.00757,-.00642,-.01107,-.01225,0.0*
1,1,.006,-.01107,-.01225*
20,1,.006,-.01107,-.01225,-.01224,-.0175,0.0*
1,1,.006,-.01224,-.0175*
20,1,.006,-.01224,-.0175,.01226,-.0175,0.0*
1,1,.006,.01226,-.0175*
1,1,.006,.03502,.0175*
20,1,.006,.03502,.0175,.03035,.01633,0.0*
1,1,.006,.03035,.01633*
20,1,.006,.03035,.01633,.02685,.01342,0.0*
1,1,.006,.02685,.01342*
20,1,.006,.02685,.01342,.02452,.00992,0.0*
1,1,.006,.02452,.00992*
20,1,.006,.02452,.00992,.02277,.00525,0.0*
1,1,.006,.02277,.00525*
20,1,.006,.02277,.00525,.02219,0.0,0.0*
1,1,.006,.02219,0.0*
20,1,.006,.02219,0.0,.02277,-.00525,0.0*
1,1,.006,.02277,-.00525*
20,1,.006,.02277,-.00525,.02452,-.00992,0.0*
1,1,.006,.02452,-.00992*
20,1,.006,.02452,-.00992,.02685,-.01342,0.0*
1,1,.006,.02685,-.01342*
20,1,.006,.02685,-.01342,.03035,-.01633,0.0*
1,1,.006,.03035,-.01633*
20,1,.006,.03035,-.01633,.03502,-.0175,0.0*
1,1,.006,.03502,-.0175*
20,1,.006,.03502,-.0175,.03969,-.01633,0.0*
1,1,.006,.03969,-.01633*
20,1,.006,.03969,-.01633,.04319,-.01342,0.0*
1,1,.006,.04319,-.01342*
20,1,.006,.04319,-.01342,.04552,-.00992,0.0*
1,1,.006,.04552,-.00992*
20,1,.006,.04552,-.00992,.04727,-.00525,0.0*
1,1,.006,.04727,-.00525*
20,1,.006,.04727,-.00525,.04785,0.0,0.0*
1,1,.006,.04785,0.0*
20,1,.006,.04785,0.0,.04727,.00525,0.0*
1,1,.006,.04727,.00525*
20,1,.006,.04727,.00525,.04552,.00992,0.0*
1,1,.006,.04552,.00992*
20,1,.006,.04552,.00992,.04319,.01342,0.0*
1,1,.006,.04319,.01342*
20,1,.006,.04319,.01342,.03969,.01633,0.0*
1,1,.006,.03969,.01633*
20,1,.006,.03969,.01633,.03502,.0175,0.0*
1,1,.006,.03502,.0175*
%
%ADD16MACRO16*%
%AMMACRO24*
1,1,.006,0.0,.035*
20,1,.006,0.0,.035,.035,-.035,0.0*
1,1,.006,.035,-.035*
20,1,.006,.035,-.035,-.035,-.035,0.0*
1,1,.006,-.035,-.035*
20,1,.006,-.035,-.035,0.0,.035,0.0*
1,1,.006,0.0,.035*
1,1,.006,-.0455,-.02917*
20,1,.006,-.0455,-.02917,-.0455,.00583,0.0*
1,1,.006,-.0455,.00583*
1,1,.006,-.0455,.00058*
20,1,.006,-.0455,.00058,-.04258,.0035,0.0*
1,1,.006,-.04258,.0035*
20,1,.006,-.04258,.0035,-.03967,.00525,0.0*
1,1,.006,-.03967,.00525*
20,1,.006,-.03967,.00525,-.035,.00583,0.0*
1,1,.006,-.035,.00583*
20,1,.006,-.035,.00583,-.03092,.00525,0.0*
1,1,.006,-.03092,.00525*
20,1,.006,-.03092,.00525,-.02683,.00233,0.0*
1,1,.006,-.02683,.00233*
20,1,.006,-.02683,.00233,-.02508,-.00175,0.0*
1,1,.006,-.02508,-.00175*
20,1,.006,-.02508,-.00175,-.0245,-.00583,0.0*
1,1,.006,-.0245,-.00583*
20,1,.006,-.0245,-.00583,-.02508,-.00992,0.0*
1,1,.006,-.02508,-.00992*
20,1,.006,-.02508,-.00992,-.02683,-.014,0.0*
1,1,.006,-.02683,-.014*
20,1,.006,-.02683,-.014,-.03033,-.01633,0.0*
1,1,.006,-.03033,-.01633*
20,1,.006,-.03033,-.01633,-.035,-.0175,0.0*
1,1,.006,-.035,-.0175*
20,1,.006,-.035,-.0175,-.03908,-.01692,0.0*
1,1,.006,-.03908,-.01692*
20,1,.006,-.03908,-.01692,-.04317,-.01517,0.0*
1,1,.006,-.04317,-.01517*
20,1,.006,-.04317,-.01517,-.0455,-.01283,0.0*
1,1,.006,-.0455,-.01283*
1,1,.006,-.01224,-.028*
20,1,.006,-.01224,-.028,-.00874,-.02917,0.0*
1,1,.006,-.00874,-.02917*
20,1,.006,-.00874,-.02917,-.00407,-.028,0.0*
1,1,.006,-.00407,-.028*
20,1,.006,-.00407,-.028,-.00116,-.02567,0.0*
1,1,.006,-.00116,-.02567*
20,1,.006,-.00116,-.02567,.00118,-.02275,0.0*
1,1,.006,.00118,-.02275*
20,1,.006,.00118,-.02275,.00468,-.01342,0.0*
1,1,.006,.00468,-.01342*
20,1,.006,.00468,-.01342,.01226,.00583,0.0*
1,1,.006,.01226,.00583*
1,1,.006,-.00641,.00583*
20,1,.006,-.00641,.00583,.00468,-.01342,0.0*
1,1,.006,.00468,-.01342*
1,1,.006,.02627,-.00175*
20,1,.006,.02627,-.00175,.04494,-.00175,0.0*
1,1,.006,.04494,-.00175*
20,1,.006,.04494,-.00175,.04319,.00233,0.0*
1,1,.006,.04319,.00233*
20,1,.006,.04319,.00233,.04027,.00467,0.0*
1,1,.006,.04027,.00467*
20,1,.006,.04027,.00467,.03619,.00583,0.0*
1,1,.006,.03619,.00583*
20,1,.006,.03619,.00583,.0321,.00525,0.0*
1,1,.006,.0321,.00525*
20,1,.006,.0321,.00525,.0286,.0035,0.0*
1,1,.006,.0286,.0035*
20,1,.006,.0286,.0035,.02627,-.00058,0.0*
1,1,.006,.02627,-.00058*
20,1,.006,.02627,-.00058,.0251,-.00408,0.0*
1,1,.006,.0251,-.00408*
20,1,.006,.0251,-.00408,.0251,-.00758,0.0*
1,1,.006,.0251,-.00758*
20,1,.006,.0251,-.00758,.02627,-.01108,0.0*
1,1,.006,.02627,-.01108*
20,1,.006,.02627,-.01108,.02919,-.01458,0.0*
1,1,.006,.02919,-.01458*
20,1,.006,.02919,-.01458,.03269,-.01692,0.0*
1,1,.006,.03269,-.01692*
20,1,.006,.03269,-.01692,.03677,-.0175,0.0*
1,1,.006,.03677,-.0175*
20,1,.006,.03677,-.0175,.04085,-.01633,0.0*
1,1,.006,.04085,-.01633*
20,1,.006,.04085,-.01633,.04494,-.01283,0.0*
1,1,.006,.04494,-.01283*
%
%ADD24MACRO24*%
%AMMACRO29*
1,1,.006,.0495,0.0*
20,1,.006,.0495,0.0,0.0,-.0495,0.0*
1,1,.006,0.0,-.0495*
20,1,.006,0.0,-.0495,-.0495,0.0,0.0*
1,1,.006,-.0495,0.0*
20,1,.006,-.0495,0.0,0.0,.0495,0.0*
1,1,.006,0.0,.0495*
20,1,.006,0.0,.0495,.0495,0.0,0.0*
1,1,.006,.0495,0.0*
1,1,.006,-.0495,.02475*
20,1,.006,-.0495,.02475,-.0561,.0231,0.0*
1,1,.006,-.0561,.0231*
20,1,.006,-.0561,.0231,-.06105,.01897,0.0*
1,1,.006,-.06105,.01897*
20,1,.006,-.06105,.01897,-.06435,.01403,0.0*
1,1,.006,-.06435,.01403*
20,1,.006,-.06435,.01403,-.06683,.00742,0.0*
1,1,.006,-.06683,.00742*
20,1,.006,-.06683,.00742,-.06765,0.0,0.0*
1,1,.006,-.06765,0.0*
20,1,.006,-.06765,0.0,-.06683,-.00743,0.0*
1,1,.006,-.06683,-.00743*
20,1,.006,-.06683,-.00743,-.06435,-.01403,0.0*
1,1,.006,-.06435,-.01403*
20,1,.006,-.06435,-.01403,-.06105,-.01898,0.0*
1,1,.006,-.06105,-.01898*
20,1,.006,-.06105,-.01898,-.0561,-.0231,0.0*
1,1,.006,-.0561,-.0231*
20,1,.006,-.0561,-.0231,-.0495,-.02475,0.0*
1,1,.006,-.0495,-.02475*
20,1,.006,-.0495,-.02475,-.0429,-.0231,0.0*
1,1,.006,-.0429,-.0231*
20,1,.006,-.0429,-.0231,-.03795,-.01898,0.0*
1,1,.006,-.03795,-.01898*
20,1,.006,-.03795,-.01898,-.03465,-.01403,0.0*
1,1,.006,-.03465,-.01403*
20,1,.006,-.03465,-.01403,-.03217,-.00743,0.0*
1,1,.006,-.03217,-.00743*
20,1,.006,-.03217,-.00743,-.03135,0.0,0.0*
1,1,.006,-.03135,0.0*
20,1,.006,-.03135,0.0,-.03217,.00742,0.0*
1,1,.006,-.03217,.00742*
20,1,.006,-.03217,.00742,-.03465,.01403,0.0*
1,1,.006,-.03465,.01403*
20,1,.006,-.03465,.01403,-.03795,.01897,0.0*
1,1,.006,-.03795,.01897*
20,1,.006,-.03795,.01897,-.0429,.0231,0.0*
1,1,.006,-.0429,.0231*
20,1,.006,-.0429,.0231,-.0495,.02475,0.0*
1,1,.006,-.0495,.02475*
1,1,.006,-.01402,-.01898*
20,1,.006,-.01402,-.01898,-.00824,-.0231,0.0*
1,1,.006,-.00824,-.0231*
20,1,.006,-.00824,-.0231,-.00164,-.02475,0.0*
1,1,.006,-.00164,-.02475*
20,1,.006,-.00164,-.02475,.00496,-.0231,0.0*
1,1,.006,.00496,-.0231*
20,1,.006,.00496,-.0231,.01073,-.01815,0.0*
1,1,.006,.01073,-.01815*
20,1,.006,.01073,-.01815,.01486,-.01072,0.0*
1,1,.006,.01486,-.01072*
20,1,.006,.01486,-.01072,.01651,-.0033,0.0*
1,1,.006,.01651,-.0033*
20,1,.006,.01651,-.0033,.01651,.00577,0.0*
1,1,.006,.01651,.00577*
20,1,.006,.01651,.00577,.01486,.0132,0.0*
1,1,.006,.01486,.0132*
20,1,.006,.01486,.0132,.01073,.0198,0.0*
1,1,.006,.01073,.0198*
20,1,.006,.01073,.0198,.00578,.0231,0.0*
1,1,.006,.00578,.0231*
20,1,.006,.00578,.0231,.00001,.02475,0.0*
1,1,.006,.00001,.02475*
20,1,.006,.00001,.02475,-.00659,.0231,0.0*
1,1,.006,-.00659,.0231*
20,1,.006,-.00659,.0231,-.01154,.0198,0.0*
1,1,.006,-.01154,.0198*
20,1,.006,-.01154,.0198,-.01484,.01485,0.0*
1,1,.006,-.01484,.01485*
20,1,.006,-.01484,.01485,-.01649,.00825,0.0*
1,1,.006,-.01649,.00825*
20,1,.006,-.01649,.00825,-.01484,.00248,0.0*
1,1,.006,-.01484,.00248*
20,1,.006,-.01484,.00248,-.01071,-.0033,0.0*
1,1,.006,-.01071,-.0033*
20,1,.006,-.01071,-.0033,-.00576,-.0066,0.0*
1,1,.006,-.00576,-.0066*
20,1,.006,-.00576,-.0066,.00001,-.00743,0.0*
1,1,.006,.00001,-.00743*
20,1,.006,.00001,-.00743,.00661,-.00578,0.0*
1,1,.006,.00661,-.00578*
20,1,.006,.00661,-.00578,.01156,-.00165,0.0*
1,1,.006,.01156,-.00165*
20,1,.006,.01156,-.00165,.01651,.00577,0.0*
1,1,.006,.01651,.00577*
1,1,.006,.03549,-.01898*
20,1,.006,.03549,-.01898,.04127,-.0231,0.0*
1,1,.006,.04127,-.0231*
20,1,.006,.04127,-.0231,.04787,-.02475,0.0*
1,1,.006,.04787,-.02475*
20,1,.006,.04787,-.02475,.05447,-.0231,0.0*
1,1,.006,.05447,-.0231*
20,1,.006,.05447,-.0231,.06024,-.01815,0.0*
1,1,.006,.06024,-.01815*
20,1,.006,.06024,-.01815,.06437,-.01072,0.0*
1,1,.006,.06437,-.01072*
20,1,.006,.06437,-.01072,.06602,-.0033,0.0*
1,1,.006,.06602,-.0033*
20,1,.006,.06602,-.0033,.06602,.00577,0.0*
1,1,.006,.06602,.00577*
20,1,.006,.06602,.00577,.06437,.0132,0.0*
1,1,.006,.06437,.0132*
20,1,.006,.06437,.0132,.06024,.0198,0.0*
1,1,.006,.06024,.0198*
20,1,.006,.06024,.0198,.05529,.0231,0.0*
1,1,.006,.05529,.0231*
20,1,.006,.05529,.0231,.04952,.02475,0.0*
1,1,.006,.04952,.02475*
20,1,.006,.04952,.02475,.04292,.0231,0.0*
1,1,.006,.04292,.0231*
20,1,.006,.04292,.0231,.03797,.0198,0.0*
1,1,.006,.03797,.0198*
20,1,.006,.03797,.0198,.03467,.01485,0.0*
1,1,.006,.03467,.01485*
20,1,.006,.03467,.01485,.03302,.00825,0.0*
1,1,.006,.03302,.00825*
20,1,.006,.03302,.00825,.03467,.00248,0.0*
1,1,.006,.03467,.00248*
20,1,.006,.03467,.00248,.0388,-.0033,0.0*
1,1,.006,.0388,-.0033*
20,1,.006,.0388,-.0033,.04375,-.0066,0.0*
1,1,.006,.04375,-.0066*
20,1,.006,.04375,-.0066,.04952,-.00743,0.0*
1,1,.006,.04952,-.00743*
20,1,.006,.04952,-.00743,.05612,-.00578,0.0*
1,1,.006,.05612,-.00578*
20,1,.006,.05612,-.00578,.06107,-.00165,0.0*
1,1,.006,.06107,-.00165*
20,1,.006,.06107,-.00165,.06602,.00577,0.0*
1,1,.006,.06602,.00577*
%
%ADD29MACRO29*%
%AMMACRO28*
1,1,.006,.064,0.0*
20,1,.006,.064,0.0,.032,.055426,0.0*
1,1,.006,.032,.055426*
20,1,.006,.032,.055426,-.032,.055426,0.0*
1,1,.006,-.032,.055426*
20,1,.006,-.032,.055426,-.064,0.0,0.0*
1,1,.006,-.064,0.0*
20,1,.006,-.064,0.0,-.032,-.055426,0.0*
1,1,.006,-.032,-.055426*
20,1,.006,-.032,-.055426,.032,-.055426,0.0*
1,1,.006,.032,-.055426*
20,1,.006,.032,-.055426,.064,0.0,0.0*
1,1,.006,.064,0.0*
1,1,.006,-.0448,-.05333*
20,1,.006,-.0448,-.05333,-.0448,.01067,0.0*
1,1,.006,-.0448,.01067*
1,1,.006,-.0448,.00107*
20,1,.006,-.0448,.00107,-.05013,.0064,0.0*
1,1,.006,-.05013,.0064*
20,1,.006,-.05013,.0064,-.05653,.0096,0.0*
1,1,.006,-.05653,.0096*
20,1,.006,-.05653,.0096,-.064,.01067,0.0*
1,1,.006,-.064,.01067*
20,1,.006,-.064,.01067,-.0704,.0096,0.0*
1,1,.006,-.0704,.0096*
20,1,.006,-.0704,.0096,-.07787,.00427,0.0*
1,1,.006,-.07787,.00427*
20,1,.006,-.07787,.00427,-.08213,-.0032,0.0*
1,1,.006,-.08213,-.0032*
20,1,.006,-.08213,-.0032,-.0832,-.01067,0.0*
1,1,.006,-.0832,-.01067*
20,1,.006,-.0832,-.01067,-.08213,-.01813,0.0*
1,1,.006,-.08213,-.01813*
20,1,.006,-.08213,-.01813,-.07787,-.0256,0.0*
1,1,.006,-.07787,-.0256*
20,1,.006,-.07787,-.0256,-.0704,-.03093,0.0*
1,1,.006,-.0704,-.03093*
20,1,.006,-.0704,-.03093,-.064,-.032,0.0*
1,1,.006,-.064,-.032*
20,1,.006,-.064,-.032,-.05653,-.03093,0.0*
1,1,.006,-.05653,-.03093*
20,1,.006,-.05653,-.03093,-.05013,-.02773,0.0*
1,1,.006,-.05013,-.02773*
20,1,.006,-.05013,-.02773,-.0448,-.0224,0.0*
1,1,.006,-.0448,-.0224*
1,1,.006,-.02666,.01067*
20,1,.006,-.02666,.01067,-.01386,-.032,0.0*
1,1,.006,-.01386,-.032*
20,1,.006,-.01386,-.032,.00001,.01067,0.0*
1,1,.006,.00001,.01067*
20,1,.006,.00001,.01067,.01388,-.032,0.0*
1,1,.006,.01388,-.032*
20,1,.006,.01388,-.032,.02668,.01067,0.0*
1,1,.006,.02668,.01067*
1,1,.006,.06402,.01067*
20,1,.006,.06402,.01067,.06402,-.032,0.0*
1,1,.006,.06402,-.032*
1,1,.006,.06402,.02773*
20,1,.006,.06402,.02773,.06189,.0288,0.0*
1,1,.006,.06189,.0288*
20,1,.006,.06189,.0288,.06189,.03093,0.0*
1,1,.006,.06189,.03093*
20,1,.006,.06189,.03093,.06402,.032,0.0*
1,1,.006,.06402,.032*
20,1,.006,.06402,.032,.06615,.03093,0.0*
1,1,.006,.06615,.03093*
20,1,.006,.06615,.03093,.06615,.0288,0.0*
1,1,.006,.06615,.0288*
20,1,.006,.06615,.0288,.06402,.02773,0.0*
1,1,.006,.06402,.02773*
%
%ADD28MACRO28*%
%AMMACRO12*
1,1,.006,.071,0.0*
20,1,.006,.071,0.0,.0355,.061488,0.0*
1,1,.006,.0355,.061488*
20,1,.006,.0355,.061488,-.0355,.061488,0.0*
1,1,.006,-.0355,.061488*
20,1,.006,-.0355,.061488,-.071,0.0,0.0*
1,1,.006,-.071,0.0*
20,1,.006,-.071,0.0,-.0355,-.061488,0.0*
1,1,.006,-.0355,-.061488*
20,1,.006,-.0355,-.061488,.0355,-.061488,0.0*
1,1,.006,.0355,-.061488*
20,1,.006,.0355,-.061488,.071,0.0,0.0*
1,1,.006,.071,0.0*
1,1,.006,-.0497,-.05917*
20,1,.006,-.0497,-.05917,-.0497,.01183,0.0*
1,1,.006,-.0497,.01183*
1,1,.006,-.0497,.00118*
20,1,.006,-.0497,.00118,-.05562,.0071,0.0*
1,1,.006,-.05562,.0071*
20,1,.006,-.05562,.0071,-.06272,.01065,0.0*
1,1,.006,-.06272,.01065*
20,1,.006,-.06272,.01065,-.071,.01183,0.0*
1,1,.006,-.071,.01183*
20,1,.006,-.071,.01183,-.0781,.01065,0.0*
1,1,.006,-.0781,.01065*
20,1,.006,-.0781,.01065,-.08638,.00473,0.0*
1,1,.006,-.08638,.00473*
20,1,.006,-.08638,.00473,-.09112,-.00355,0.0*
1,1,.006,-.09112,-.00355*
20,1,.006,-.09112,-.00355,-.0923,-.01183,0.0*
1,1,.006,-.0923,-.01183*
20,1,.006,-.0923,-.01183,-.09112,-.02012,0.0*
1,1,.006,-.09112,-.02012*
20,1,.006,-.09112,-.02012,-.08638,-.0284,0.0*
1,1,.006,-.08638,-.0284*
20,1,.006,-.08638,-.0284,-.0781,-.03432,0.0*
1,1,.006,-.0781,-.03432*
20,1,.006,-.0781,-.03432,-.071,-.0355,0.0*
1,1,.006,-.071,-.0355*
20,1,.006,-.071,-.0355,-.06272,-.03432,0.0*
1,1,.006,-.06272,-.03432*
20,1,.006,-.06272,-.03432,-.05562,-.03077,0.0*
1,1,.006,-.05562,-.03077*
20,1,.006,-.05562,-.03077,-.0497,-.02485,0.0*
1,1,.006,-.0497,-.02485*
1,1,.006,-.01656,-.0355*
20,1,.006,-.01656,-.0355,-.01656,.01183,0.0*
1,1,.006,-.01656,.01183*
1,1,.006,-.01656,.00237*
20,1,.006,-.01656,.00237,-.01064,.0071,0.0*
1,1,.006,-.01064,.0071*
20,1,.006,-.01064,.0071,-.00472,.01065,0.0*
1,1,.006,-.00472,.01065*
20,1,.006,-.00472,.01065,.00356,.01183,0.0*
1,1,.006,.00356,.01183*
20,1,.006,.00356,.01183,.00948,.01065,0.0*
1,1,.006,.00948,.01065*
20,1,.006,.00948,.01065,.01658,.0071,0.0*
1,1,.006,.01658,.0071*
1,1,.006,.04144,.01183*
20,1,.006,.04144,.01183,.05564,-.0355,0.0*
1,1,.006,.05564,-.0355*
20,1,.006,.05564,-.0355,.07102,.01183,0.0*
1,1,.006,.07102,.01183*
20,1,.006,.07102,.01183,.0864,-.0355,0.0*
1,1,.006,.0864,-.0355*
20,1,.006,.0864,-.0355,.1006,.01183,0.0*
1,1,.006,.1006,.01183*
%
%ADD12MACRO12*%
%AMMACRO18*
1,1,.006,0.0,.035*
20,1,.006,0.0,.035,.035,-.035,0.0*
1,1,.006,.035,-.035*
20,1,.006,.035,-.035,-.035,-.035,0.0*
1,1,.006,-.035,-.035*
20,1,.006,-.035,-.035,0.0,.035,0.0*
1,1,.006,0.0,.035*
1,1,.006,-.0455,-.02917*
20,1,.006,-.0455,-.02917,-.0455,.00583,0.0*
1,1,.006,-.0455,.00583*
1,1,.006,-.0455,.00058*
20,1,.006,-.0455,.00058,-.04258,.0035,0.0*
1,1,.006,-.04258,.0035*
20,1,.006,-.04258,.0035,-.03967,.00525,0.0*
1,1,.006,-.03967,.00525*
20,1,.006,-.03967,.00525,-.035,.00583,0.0*
1,1,.006,-.035,.00583*
20,1,.006,-.035,.00583,-.03092,.00525,0.0*
1,1,.006,-.03092,.00525*
20,1,.006,-.03092,.00525,-.02683,.00233,0.0*
1,1,.006,-.02683,.00233*
20,1,.006,-.02683,.00233,-.02508,-.00175,0.0*
1,1,.006,-.02508,-.00175*
20,1,.006,-.02508,-.00175,-.0245,-.00583,0.0*
1,1,.006,-.0245,-.00583*
20,1,.006,-.0245,-.00583,-.02508,-.00992,0.0*
1,1,.006,-.02508,-.00992*
20,1,.006,-.02508,-.00992,-.02683,-.014,0.0*
1,1,.006,-.02683,-.014*
20,1,.006,-.02683,-.014,-.03033,-.01633,0.0*
1,1,.006,-.03033,-.01633*
20,1,.006,-.03033,-.01633,-.035,-.0175,0.0*
1,1,.006,-.035,-.0175*
20,1,.006,-.035,-.0175,-.03908,-.01692,0.0*
1,1,.006,-.03908,-.01692*
20,1,.006,-.03908,-.01692,-.04317,-.01517,0.0*
1,1,.006,-.04317,-.01517*
20,1,.006,-.04317,-.01517,-.0455,-.01283,0.0*
1,1,.006,-.0455,-.01283*
1,1,.006,-.00816,-.0175*
20,1,.006,-.00816,-.0175,-.00816,.00583,0.0*
1,1,.006,-.00816,.00583*
1,1,.006,-.00816,.00117*
20,1,.006,-.00816,.00117,-.00524,.0035,0.0*
1,1,.006,-.00524,.0035*
20,1,.006,-.00524,.0035,-.00232,.00525,0.0*
1,1,.006,-.00232,.00525*
20,1,.006,-.00232,.00525,.00176,.00583,0.0*
1,1,.006,.00176,.00583*
20,1,.006,.00176,.00583,.00468,.00525,0.0*
1,1,.006,.00468,.00525*
20,1,.006,.00468,.00525,.00818,.0035,0.0*
1,1,.006,.00818,.0035*
1,1,.006,.02044,.00583*
20,1,.006,.02044,.00583,.02744,-.0175,0.0*
1,1,.006,.02744,-.0175*
20,1,.006,.02744,-.0175,.03502,.00583,0.0*
1,1,.006,.03502,.00583*
20,1,.006,.03502,.00583,.0426,-.0175,0.0*
1,1,.006,.0426,-.0175*
20,1,.006,.0426,-.0175,.0496,.00583,0.0*
1,1,.006,.0496,.00583*
%
%ADD18MACRO18*%
%AMMACRO15*
1,1,.006,0.0,.035*
20,1,.006,0.0,.035,.035,-.035,0.0*
1,1,.006,.035,-.035*
20,1,.006,.035,-.035,-.035,-.035,0.0*
1,1,.006,-.035,-.035*
20,1,.006,-.035,-.035,0.0,.035,0.0*
1,1,.006,0.0,.035*
1,1,.006,-.035,.0175*
20,1,.006,-.035,.0175,-.03967,.01633,0.0*
1,1,.006,-.03967,.01633*
20,1,.006,-.03967,.01633,-.04317,.01342,0.0*
1,1,.006,-.04317,.01342*
20,1,.006,-.04317,.01342,-.0455,.00992,0.0*
1,1,.006,-.0455,.00992*
20,1,.006,-.0455,.00992,-.04725,.00525,0.0*
1,1,.006,-.04725,.00525*
20,1,.006,-.04725,.00525,-.04783,0.0,0.0*
1,1,.006,-.04783,0.0*
20,1,.006,-.04783,0.0,-.04725,-.00525,0.0*
1,1,.006,-.04725,-.00525*
20,1,.006,-.04725,-.00525,-.0455,-.00992,0.0*
1,1,.006,-.0455,-.00992*
20,1,.006,-.0455,-.00992,-.04317,-.01342,0.0*
1,1,.006,-.04317,-.01342*
20,1,.006,-.04317,-.01342,-.03967,-.01633,0.0*
1,1,.006,-.03967,-.01633*
20,1,.006,-.03967,-.01633,-.035,-.0175,0.0*
1,1,.006,-.035,-.0175*
20,1,.006,-.035,-.0175,-.03033,-.01633,0.0*
1,1,.006,-.03033,-.01633*
20,1,.006,-.03033,-.01633,-.02683,-.01342,0.0*
1,1,.006,-.02683,-.01342*
20,1,.006,-.02683,-.01342,-.0245,-.00992,0.0*
1,1,.006,-.0245,-.00992*
20,1,.006,-.0245,-.00992,-.02275,-.00525,0.0*
1,1,.006,-.02275,-.00525*
20,1,.006,-.02275,-.00525,-.02217,0.0,0.0*
1,1,.006,-.02217,0.0*
20,1,.006,-.02217,0.0,-.02275,.00525,0.0*
1,1,.006,-.02275,.00525*
20,1,.006,-.02275,.00525,-.0245,.00992,0.0*
1,1,.006,-.0245,.00992*
20,1,.006,-.0245,.00992,-.02683,.01342,0.0*
1,1,.006,-.02683,.01342*
20,1,.006,-.02683,.01342,-.03033,.01633,0.0*
1,1,.006,-.03033,.01633*
20,1,.006,-.03033,.01633,-.035,.0175,0.0*
1,1,.006,-.035,.0175*
1,1,.006,.00701,-.0175*
20,1,.006,.00701,-.0175,.00701,.0175,0.0*
1,1,.006,.00701,.0175*
20,1,.006,.00701,.0175,-.01457,-.00758,0.0*
1,1,.006,-.01457,-.00758*
20,1,.006,-.01457,-.00758,.01459,-.00758,0.0*
1,1,.006,.01459,-.00758*
1,1,.006,.02219,-.0105*
20,1,.006,.02219,-.0105,.02569,-.01458,0.0*
1,1,.006,.02569,-.01458*
20,1,.006,.02569,-.01458,.03035,-.01692,0.0*
1,1,.006,.03035,-.01692*
20,1,.006,.03035,-.01692,.0356,-.0175,0.0*
1,1,.006,.0356,-.0175*
20,1,.006,.0356,-.0175,.04027,-.01692,0.0*
1,1,.006,.04027,-.01692*
20,1,.006,.04027,-.01692,.04494,-.014,0.0*
1,1,.006,.04494,-.014*
20,1,.006,.04494,-.014,.04785,-.0105,0.0*
1,1,.006,.04785,-.0105*
20,1,.006,.04785,-.0105,.04844,-.007,0.0*
1,1,.006,.04844,-.007*
20,1,.006,.04844,-.007,.04727,-.00292,0.0*
1,1,.006,.04727,-.00292*
20,1,.006,.04727,-.00292,.04319,0.0,0.0*
1,1,.006,.04319,0.0*
20,1,.006,.04319,0.0,.0391,.00117,0.0*
1,1,.006,.0391,.00117*
20,1,.006,.0391,.00117,.03385,.00117,0.0*
1,1,.006,.03385,.00117*
1,1,.006,.0391,.00117*
20,1,.006,.0391,.00117,.0426,.00292,0.0*
1,1,.006,.0426,.00292*
20,1,.006,.0426,.00292,.04552,.00583,0.0*
1,1,.006,.04552,.00583*
20,1,.006,.04552,.00583,.04669,.00933,0.0*
1,1,.006,.04669,.00933*
20,1,.006,.04669,.00933,.04552,.01283,0.0*
1,1,.006,.04552,.01283*
20,1,.006,.04552,.01283,.0426,.01575,0.0*
1,1,.006,.0426,.01575*
20,1,.006,.0426,.01575,.03735,.0175,0.0*
1,1,.006,.03735,.0175*
20,1,.006,.03735,.0175,.0321,.01692,0.0*
1,1,.006,.0321,.01692*
20,1,.006,.0321,.01692,.02685,.01458,0.0*
1,1,.006,.02685,.01458*
%
%ADD15MACRO15*%
%AMMACRO30*
1,1,.006,0.0,.035*
20,1,.006,0.0,.035,.035,-.035,0.0*
1,1,.006,.035,-.035*
20,1,.006,.035,-.035,-.035,-.035,0.0*
1,1,.006,-.035,-.035*
20,1,.006,-.035,-.035,0.0,.035,0.0*
1,1,.006,0.0,.035*
1,1,.006,-.035,.0175*
20,1,.006,-.035,.0175,-.03967,.01633,0.0*
1,1,.006,-.03967,.01633*
20,1,.006,-.03967,.01633,-.04317,.01342,0.0*
1,1,.006,-.04317,.01342*
20,1,.006,-.04317,.01342,-.0455,.00992,0.0*
1,1,.006,-.0455,.00992*
20,1,.006,-.0455,.00992,-.04725,.00525,0.0*
1,1,.006,-.04725,.00525*
20,1,.006,-.04725,.00525,-.04783,0.0,0.0*
1,1,.006,-.04783,0.0*
20,1,.006,-.04783,0.0,-.04725,-.00525,0.0*
1,1,.006,-.04725,-.00525*
20,1,.006,-.04725,-.00525,-.0455,-.00992,0.0*
1,1,.006,-.0455,-.00992*
20,1,.006,-.0455,-.00992,-.04317,-.01342,0.0*
1,1,.006,-.04317,-.01342*
20,1,.006,-.04317,-.01342,-.03967,-.01633,0.0*
1,1,.006,-.03967,-.01633*
20,1,.006,-.03967,-.01633,-.035,-.0175,0.0*
1,1,.006,-.035,-.0175*
20,1,.006,-.035,-.0175,-.03033,-.01633,0.0*
1,1,.006,-.03033,-.01633*
20,1,.006,-.03033,-.01633,-.02683,-.01342,0.0*
1,1,.006,-.02683,-.01342*
20,1,.006,-.02683,-.01342,-.0245,-.00992,0.0*
1,1,.006,-.0245,-.00992*
20,1,.006,-.0245,-.00992,-.02275,-.00525,0.0*
1,1,.006,-.02275,-.00525*
20,1,.006,-.02275,-.00525,-.02217,0.0,0.0*
1,1,.006,-.02217,0.0*
20,1,.006,-.02217,0.0,-.02275,.00525,0.0*
1,1,.006,-.02275,.00525*
20,1,.006,-.02275,.00525,-.0245,.00992,0.0*
1,1,.006,-.0245,.00992*
20,1,.006,-.0245,.00992,-.02683,.01342,0.0*
1,1,.006,-.02683,.01342*
20,1,.006,-.02683,.01342,-.03033,.01633,0.0*
1,1,.006,-.03033,.01633*
20,1,.006,-.03033,.01633,-.035,.0175,0.0*
1,1,.006,-.035,.0175*
1,1,.006,-.01107,-.00292*
20,1,.006,-.01107,-.00292,-.00699,.00117,0.0*
1,1,.006,-.00699,.00117*
20,1,.006,-.00699,.00117,-.00349,.0035,0.0*
1,1,.006,-.00349,.0035*
20,1,.006,-.00349,.0035,.00118,.00467,0.0*
1,1,.006,.00118,.00467*
20,1,.006,.00118,.00467,.00526,.0035,0.0*
1,1,.006,.00526,.0035*
20,1,.006,.00526,.0035,.00818,.00117,0.0*
1,1,.006,.00818,.00117*
20,1,.006,.00818,.00117,.01051,-.00233,0.0*
1,1,.006,.01051,-.00233*
20,1,.006,.01051,-.00233,.01109,-.00642,0.0*
1,1,.006,.01109,-.00642*
20,1,.006,.01109,-.00642,.01051,-.00992,0.0*
1,1,.006,.01051,-.00992*
20,1,.006,.01051,-.00992,.00818,-.01342,0.0*
1,1,.006,.00818,-.01342*
20,1,.006,.00818,-.01342,.00468,-.01633,0.0*
1,1,.006,.00468,-.01633*
20,1,.006,.00468,-.01633,.00059,-.0175,0.0*
1,1,.006,.00059,-.0175*
20,1,.006,.00059,-.0175,-.00407,-.01633,0.0*
1,1,.006,-.00407,-.01633*
20,1,.006,-.00407,-.01633,-.00816,-.01283,0.0*
1,1,.006,-.00816,-.01283*
20,1,.006,-.00816,-.01283,-.01049,-.00758,0.0*
1,1,.006,-.01049,-.00758*
20,1,.006,-.01049,-.00758,-.01107,-.00175,0.0*
1,1,.006,-.01107,-.00175*
20,1,.006,-.01107,-.00175,-.00991,.00583,0.0*
1,1,.006,-.00991,.00583*
20,1,.006,-.00991,.00583,-.00816,.00992,0.0*
1,1,.006,-.00816,.00992*
20,1,.006,-.00816,.00992,-.00524,.014,0.0*
1,1,.006,-.00524,.014*
20,1,.006,-.00524,.014,-.00116,.01692,0.0*
1,1,.006,-.00116,.01692*
20,1,.006,-.00116,.01692,.00293,.0175,0.0*
1,1,.006,.00293,.0175*
20,1,.006,.00293,.0175,.00701,.01633,0.0*
1,1,.006,.00701,.01633*
20,1,.006,.00701,.01633,.00993,.01342,0.0*
1,1,.006,.00993,.01342*
1,1,.006,.02394,.01167*
20,1,.006,.02394,.01167,.02744,.01517,0.0*
1,1,.006,.02744,.01517*
20,1,.006,.02744,.01517,.03152,.01692,0.0*
1,1,.006,.03152,.01692*
20,1,.006,.03152,.01692,.03619,.0175,0.0*
1,1,.006,.03619,.0175*
20,1,.006,.03619,.0175,.04202,.01633,0.0*
1,1,.006,.04202,.01633*
20,1,.006,.04202,.01633,.0461,.01342,0.0*
1,1,.006,.0461,.01342*
20,1,.006,.0461,.01342,.04727,.00992,0.0*
1,1,.006,.04727,.00992*
20,1,.006,.04727,.00992,.04669,.00642,0.0*
1,1,.006,.04669,.00642*
20,1,.006,.04669,.00642,.04435,.0035,0.0*
1,1,.006,.04435,.0035*
20,1,.006,.04435,.0035,.03269,-.00233,0.0*
1,1,.006,.03269,-.00233*
20,1,.006,.03269,-.00233,.02744,-.00642,0.0*
1,1,.006,.02744,-.00642*
20,1,.006,.02744,-.00642,.02394,-.01225,0.0*
1,1,.006,.02394,-.01225*
20,1,.006,.02394,-.01225,.02277,-.0175,0.0*
1,1,.006,.02277,-.0175*
20,1,.006,.02277,-.0175,.04727,-.0175,0.0*
1,1,.006,.04727,-.0175*
%
%ADD30MACRO30*%
%AMMACRO27*
1,1,.006,0.0,.04*
20,1,.006,0.0,.04,.04,-.04,0.0*
1,1,.006,.04,-.04*
20,1,.006,.04,-.04,-.04,-.04,0.0*
1,1,.006,-.04,-.04*
20,1,.006,-.04,-.04,0.0,.04,0.0*
1,1,.006,0.0,.04*
1,1,.006,-.04,.02*
20,1,.006,-.04,.02,-.04533,.01867,0.0*
1,1,.006,-.04533,.01867*
20,1,.006,-.04533,.01867,-.04933,.01533,0.0*
1,1,.006,-.04933,.01533*
20,1,.006,-.04933,.01533,-.052,.01133,0.0*
1,1,.006,-.052,.01133*
20,1,.006,-.052,.01133,-.054,.006,0.0*
1,1,.006,-.054,.006*
20,1,.006,-.054,.006,-.05467,0.0,0.0*
1,1,.006,-.05467,0.0*
20,1,.006,-.05467,0.0,-.054,-.006,0.0*
1,1,.006,-.054,-.006*
20,1,.006,-.054,-.006,-.052,-.01133,0.0*
1,1,.006,-.052,-.01133*
20,1,.006,-.052,-.01133,-.04933,-.01533,0.0*
1,1,.006,-.04933,-.01533*
20,1,.006,-.04933,-.01533,-.04533,-.01867,0.0*
1,1,.006,-.04533,-.01867*
20,1,.006,-.04533,-.01867,-.04,-.02,0.0*
1,1,.006,-.04,-.02*
20,1,.006,-.04,-.02,-.03467,-.01867,0.0*
1,1,.006,-.03467,-.01867*
20,1,.006,-.03467,-.01867,-.03067,-.01533,0.0*
1,1,.006,-.03067,-.01533*
20,1,.006,-.03067,-.01533,-.028,-.01133,0.0*
1,1,.006,-.028,-.01133*
20,1,.006,-.028,-.01133,-.026,-.006,0.0*
1,1,.006,-.026,-.006*
20,1,.006,-.026,-.006,-.02533,0.0,0.0*
1,1,.006,-.02533,0.0*
20,1,.006,-.02533,0.0,-.026,.006,0.0*
1,1,.006,-.026,.006*
20,1,.006,-.026,.006,-.028,.01133,0.0*
1,1,.006,-.028,.01133*
20,1,.006,-.028,.01133,-.03067,.01533,0.0*
1,1,.006,-.03067,.01533*
20,1,.006,-.03067,.01533,-.03467,.01867,0.0*
1,1,.006,-.03467,.01867*
20,1,.006,-.03467,.01867,-.04,.02,0.0*
1,1,.006,-.04,.02*
1,1,.006,.00001,-.02*
20,1,.006,.00001,-.02,.00468,-.01933,0.0*
1,1,.006,.00468,-.01933*
20,1,.006,.00468,-.01933,.01001,-.01733,0.0*
1,1,.006,.01001,-.01733*
20,1,.006,.01001,-.01733,.01334,-.014,0.0*
1,1,.006,.01334,-.014*
20,1,.006,.01334,-.014,.01468,-.00933,0.0*
1,1,.006,.01468,-.00933*
20,1,.006,.01468,-.00933,.01334,-.00467,0.0*
1,1,.006,.01334,-.00467*
20,1,.006,.01334,-.00467,.00934,-.00067,0.0*
1,1,.006,.00934,-.00067*
20,1,.006,.00934,-.00067,.00334,.00133,0.0*
1,1,.006,.00334,.00133*
20,1,.006,.00334,.00133,-.00332,.00133,0.0*
1,1,.006,-.00332,.00133*
20,1,.006,-.00332,.00133,-.00732,.00267,0.0*
1,1,.006,-.00732,.00267*
20,1,.006,-.00732,.00267,-.01066,.006,0.0*
1,1,.006,-.01066,.006*
20,1,.006,-.01066,.006,-.01199,.01067,0.0*
1,1,.006,-.01199,.01067*
20,1,.006,-.01199,.01067,-.00999,.01533,0.0*
1,1,.006,-.00999,.01533*
20,1,.006,-.00999,.01533,-.00532,.01867,0.0*
1,1,.006,-.00532,.01867*
20,1,.006,-.00532,.01867,.00001,.02,0.0*
1,1,.006,.00001,.02*
20,1,.006,.00001,.02,.00534,.01867,0.0*
1,1,.006,.00534,.01867*
20,1,.006,.00534,.01867,.01001,.01533,0.0*
1,1,.006,.01001,.01533*
20,1,.006,.01001,.01533,.01201,.01067,0.0*
1,1,.006,.01201,.01067*
20,1,.006,.01201,.01067,.01068,.006,0.0*
1,1,.006,.01068,.006*
20,1,.006,.01068,.006,.00734,.00267,0.0*
1,1,.006,.00734,.00267*
20,1,.006,.00734,.00267,.00334,.00133,0.0*
1,1,.006,.00334,.00133*
20,1,.006,.00334,.00133,-.00332,.00133,0.0*
1,1,.006,-.00332,.00133*
20,1,.006,-.00332,.00133,-.00932,-.00067,0.0*
1,1,.006,-.00932,-.00067*
20,1,.006,-.00932,-.00067,-.01332,-.00467,0.0*
1,1,.006,-.01332,-.00467*
20,1,.006,-.01332,-.00467,-.01466,-.00933,0.0*
1,1,.006,-.01466,-.00933*
20,1,.006,-.01466,-.00933,-.01332,-.014,0.0*
1,1,.006,-.01332,-.014*
20,1,.006,-.01332,-.014,-.00999,-.01733,0.0*
1,1,.006,-.00999,-.01733*
20,1,.006,-.00999,-.01733,-.00466,-.01933,0.0*
1,1,.006,-.00466,-.01933*
20,1,.006,-.00466,-.01933,.00001,-.02,0.0*
1,1,.006,.00001,-.02*
1,1,.006,.04002,.02*
20,1,.006,.04002,.02,.03469,.01867,0.0*
1,1,.006,.03469,.01867*
20,1,.006,.03469,.01867,.03069,.01533,0.0*
1,1,.006,.03069,.01533*
20,1,.006,.03069,.01533,.02802,.01133,0.0*
1,1,.006,.02802,.01133*
20,1,.006,.02802,.01133,.02602,.006,0.0*
1,1,.006,.02602,.006*
20,1,.006,.02602,.006,.02535,0.0,0.0*
1,1,.006,.02535,0.0*
20,1,.006,.02535,0.0,.02602,-.006,0.0*
1,1,.006,.02602,-.006*
20,1,.006,.02602,-.006,.02802,-.01133,0.0*
1,1,.006,.02802,-.01133*
20,1,.006,.02802,-.01133,.03069,-.01533,0.0*
1,1,.006,.03069,-.01533*
20,1,.006,.03069,-.01533,.03469,-.01867,0.0*
1,1,.006,.03469,-.01867*
20,1,.006,.03469,-.01867,.04002,-.02,0.0*
1,1,.006,.04002,-.02*
20,1,.006,.04002,-.02,.04535,-.01867,0.0*
1,1,.006,.04535,-.01867*
20,1,.006,.04535,-.01867,.04935,-.01533,0.0*
1,1,.006,.04935,-.01533*
20,1,.006,.04935,-.01533,.05202,-.01133,0.0*
1,1,.006,.05202,-.01133*
20,1,.006,.05202,-.01133,.05402,-.006,0.0*
1,1,.006,.05402,-.006*
20,1,.006,.05402,-.006,.05469,0.0,0.0*
1,1,.006,.05469,0.0*
20,1,.006,.05469,0.0,.05402,.006,0.0*
1,1,.006,.05402,.006*
20,1,.006,.05402,.006,.05202,.01133,0.0*
1,1,.006,.05202,.01133*
20,1,.006,.05202,.01133,.04935,.01533,0.0*
1,1,.006,.04935,.01533*
20,1,.006,.04935,.01533,.04535,.01867,0.0*
1,1,.006,.04535,.01867*
20,1,.006,.04535,.01867,.04002,.02,0.0*
1,1,.006,.04002,.02*
%
%ADD27MACRO27*%
%AMMACRO11*
1,1,.006,0.0,.035*
20,1,.006,0.0,.035,.035,-.035,0.0*
1,1,.006,.035,-.035*
20,1,.006,.035,-.035,-.035,-.035,0.0*
1,1,.006,-.035,-.035*
20,1,.006,-.035,-.035,0.0,.035,0.0*
1,1,.006,0.0,.035*
1,1,.006,-.035,.0175*
20,1,.006,-.035,.0175,-.03967,.01633,0.0*
1,1,.006,-.03967,.01633*
20,1,.006,-.03967,.01633,-.04317,.01342,0.0*
1,1,.006,-.04317,.01342*
20,1,.006,-.04317,.01342,-.0455,.00992,0.0*
1,1,.006,-.0455,.00992*
20,1,.006,-.0455,.00992,-.04725,.00525,0.0*
1,1,.006,-.04725,.00525*
20,1,.006,-.04725,.00525,-.04783,0.0,0.0*
1,1,.006,-.04783,0.0*
20,1,.006,-.04783,0.0,-.04725,-.00525,0.0*
1,1,.006,-.04725,-.00525*
20,1,.006,-.04725,-.00525,-.0455,-.00992,0.0*
1,1,.006,-.0455,-.00992*
20,1,.006,-.0455,-.00992,-.04317,-.01342,0.0*
1,1,.006,-.04317,-.01342*
20,1,.006,-.04317,-.01342,-.03967,-.01633,0.0*
1,1,.006,-.03967,-.01633*
20,1,.006,-.03967,-.01633,-.035,-.0175,0.0*
1,1,.006,-.035,-.0175*
20,1,.006,-.035,-.0175,-.03033,-.01633,0.0*
1,1,.006,-.03033,-.01633*
20,1,.006,-.03033,-.01633,-.02683,-.01342,0.0*
1,1,.006,-.02683,-.01342*
20,1,.006,-.02683,-.01342,-.0245,-.00992,0.0*
1,1,.006,-.0245,-.00992*
20,1,.006,-.0245,-.00992,-.02275,-.00525,0.0*
1,1,.006,-.02275,-.00525*
20,1,.006,-.02275,-.00525,-.02217,0.0,0.0*
1,1,.006,-.02217,0.0*
20,1,.006,-.02217,0.0,-.02275,.00525,0.0*
1,1,.006,-.02275,.00525*
20,1,.006,-.02275,.00525,-.0245,.00992,0.0*
1,1,.006,-.0245,.00992*
20,1,.006,-.0245,.00992,-.02683,.01342,0.0*
1,1,.006,-.02683,.01342*
20,1,.006,-.02683,.01342,-.03033,.01633,0.0*
1,1,.006,-.03033,.01633*
20,1,.006,-.03033,.01633,-.035,.0175,0.0*
1,1,.006,-.035,.0175*
1,1,.006,.00701,-.0175*
20,1,.006,.00701,-.0175,.00701,.0175,0.0*
1,1,.006,.00701,.0175*
20,1,.006,.00701,.0175,-.01457,-.00758,0.0*
1,1,.006,-.01457,-.00758*
20,1,.006,-.01457,-.00758,.01459,-.00758,0.0*
1,1,.006,.01459,-.00758*
1,1,.006,.02394,-.00292*
20,1,.006,.02394,-.00292,.02802,.00117,0.0*
1,1,.006,.02802,.00117*
20,1,.006,.02802,.00117,.03152,.0035,0.0*
1,1,.006,.03152,.0035*
20,1,.006,.03152,.0035,.03619,.00467,0.0*
1,1,.006,.03619,.00467*
20,1,.006,.03619,.00467,.04027,.0035,0.0*
1,1,.006,.04027,.0035*
20,1,.006,.04027,.0035,.04319,.00117,0.0*
1,1,.006,.04319,.00117*
20,1,.006,.04319,.00117,.04552,-.00233,0.0*
1,1,.006,.04552,-.00233*
20,1,.006,.04552,-.00233,.0461,-.00642,0.0*
1,1,.006,.0461,-.00642*
20,1,.006,.0461,-.00642,.04552,-.00992,0.0*
1,1,.006,.04552,-.00992*
20,1,.006,.04552,-.00992,.04319,-.01342,0.0*
1,1,.006,.04319,-.01342*
20,1,.006,.04319,-.01342,.03969,-.01633,0.0*
1,1,.006,.03969,-.01633*
20,1,.006,.03969,-.01633,.0356,-.0175,0.0*
1,1,.006,.0356,-.0175*
20,1,.006,.0356,-.0175,.03094,-.01633,0.0*
1,1,.006,.03094,-.01633*
20,1,.006,.03094,-.01633,.02685,-.01283,0.0*
1,1,.006,.02685,-.01283*
20,1,.006,.02685,-.01283,.02452,-.00758,0.0*
1,1,.006,.02452,-.00758*
20,1,.006,.02452,-.00758,.02394,-.00175,0.0*
1,1,.006,.02394,-.00175*
20,1,.006,.02394,-.00175,.0251,.00583,0.0*
1,1,.006,.0251,.00583*
20,1,.006,.0251,.00583,.02685,.00992,0.0*
1,1,.006,.02685,.00992*
20,1,.006,.02685,.00992,.02977,.014,0.0*
1,1,.006,.02977,.014*
20,1,.006,.02977,.014,.03385,.01692,0.0*
1,1,.006,.03385,.01692*
20,1,.006,.03385,.01692,.03794,.0175,0.0*
1,1,.006,.03794,.0175*
20,1,.006,.03794,.0175,.04202,.01633,0.0*
1,1,.006,.04202,.01633*
20,1,.006,.04202,.01633,.04494,.01342,0.0*
1,1,.006,.04494,.01342*
%
%ADD11MACRO11*%
%AMMACRO21*
1,1,.006,.079,0.0*
20,1,.006,.079,0.0,.0395,.068416,0.0*
1,1,.006,.0395,.068416*
20,1,.006,.0395,.068416,-.0395,.068416,0.0*
1,1,.006,-.0395,.068416*
20,1,.006,-.0395,.068416,-.079,0.0,0.0*
1,1,.006,-.079,0.0*
20,1,.006,-.079,0.0,-.0395,-.068416,0.0*
1,1,.006,-.0395,-.068416*
20,1,.006,-.0395,-.068416,.0395,-.068416,0.0*
1,1,.006,.0395,-.068416*
20,1,.006,.0395,-.068416,.079,0.0,0.0*
1,1,.006,.079,0.0*
1,1,.006,-.079,-.0395*
20,1,.006,-.079,-.0395,-.079,.0395,0.0*
1,1,.006,-.079,.0395*
20,1,.006,-.079,.0395,-.0948,.0237,0.0*
1,1,.006,-.0948,.0237*
1,1,.006,-.0948,-.0395*
20,1,.006,-.0948,-.0395,-.0632,-.0395,0.0*
1,1,.006,-.0632,-.0395*
1,1,.006,-.02896,-.02765*
20,1,.006,-.02896,-.02765,-.02106,-.03423,0.0*
1,1,.006,-.02106,-.03423*
20,1,.006,-.02106,-.03423,-.01184,-.03818,0.0*
1,1,.006,-.01184,-.03818*
20,1,.006,-.01184,-.03818,.00001,-.0395,0.0*
1,1,.006,.00001,-.0395*
20,1,.006,.00001,-.0395,.01186,-.03687,0.0*
1,1,.006,.01186,-.03687*
20,1,.006,.01186,-.03687,.02108,-.0316,0.0*
1,1,.006,.02108,-.0316*
20,1,.006,.02108,-.0316,.02766,-.02238,0.0*
1,1,.006,.02766,-.02238*
20,1,.006,.02766,-.02238,.02898,-.01185,0.0*
1,1,.006,.02898,-.01185*
20,1,.006,.02898,-.01185,.02634,-.00132,0.0*
1,1,.006,.02634,-.00132*
20,1,.006,.02634,-.00132,.01976,.00527,0.0*
1,1,.006,.01976,.00527*
20,1,.006,.01976,.00527,.01054,.01053,0.0*
1,1,.006,.01054,.01053*
20,1,.006,.01054,.01053,.00133,.01185,0.0*
1,1,.006,.00133,.01185*
20,1,.006,.00133,.01185,-.00789,.01053,0.0*
1,1,.006,-.00789,.01053*
20,1,.006,-.00789,.01053,-.01974,.00527,0.0*
1,1,.006,-.01974,.00527*
20,1,.006,-.01974,.00527,-.01579,.0395,0.0*
1,1,.006,-.01579,.0395*
20,1,.006,-.01579,.0395,.01976,.0395,0.0*
1,1,.006,.01976,.0395*
1,1,.006,.07902,-.0395*
20,1,.006,.07902,-.0395,.08824,-.03818,0.0*
1,1,.006,.08824,-.03818*
20,1,.006,.08824,-.03818,.09877,-.03423,0.0*
1,1,.006,.09877,-.03423*
20,1,.006,.09877,-.03423,.10535,-.02765,0.0*
1,1,.006,.10535,-.02765*
20,1,.006,.10535,-.02765,.10799,-.01843,0.0*
1,1,.006,.10799,-.01843*
20,1,.006,.10799,-.01843,.10535,-.00922,0.0*
1,1,.006,.10535,-.00922*
20,1,.006,.10535,-.00922,.09745,-.00132,0.0*
1,1,.006,.09745,-.00132*
20,1,.006,.09745,-.00132,.0856,.00263,0.0*
1,1,.006,.0856,.00263*
20,1,.006,.0856,.00263,.07244,.00263,0.0*
1,1,.006,.07244,.00263*
20,1,.006,.07244,.00263,.06454,.00527,0.0*
1,1,.006,.06454,.00527*
20,1,.006,.06454,.00527,.05795,.01185,0.0*
1,1,.006,.05795,.01185*
20,1,.006,.05795,.01185,.05532,.02107,0.0*
1,1,.006,.05532,.02107*
20,1,.006,.05532,.02107,.05927,.03028,0.0*
1,1,.006,.05927,.03028*
20,1,.006,.05927,.03028,.06849,.03687,0.0*
1,1,.006,.06849,.03687*
20,1,.006,.06849,.03687,.07902,.0395,0.0*
1,1,.006,.07902,.0395*
20,1,.006,.07902,.0395,.08955,.03687,0.0*
1,1,.006,.08955,.03687*
20,1,.006,.08955,.03687,.09877,.03028,0.0*
1,1,.006,.09877,.03028*
20,1,.006,.09877,.03028,.10272,.02107,0.0*
1,1,.006,.10272,.02107*
20,1,.006,.10272,.02107,.10009,.01185,0.0*
1,1,.006,.10009,.01185*
20,1,.006,.10009,.01185,.0935,.00527,0.0*
1,1,.006,.0935,.00527*
20,1,.006,.0935,.00527,.0856,.00263,0.0*
1,1,.006,.0856,.00263*
20,1,.006,.0856,.00263,.07244,.00263,0.0*
1,1,.006,.07244,.00263*
20,1,.006,.07244,.00263,.06059,-.00132,0.0*
1,1,.006,.06059,-.00132*
20,1,.006,.06059,-.00132,.05269,-.00922,0.0*
1,1,.006,.05269,-.00922*
20,1,.006,.05269,-.00922,.05005,-.01843,0.0*
1,1,.006,.05005,-.01843*
20,1,.006,.05005,-.01843,.05269,-.02765,0.0*
1,1,.006,.05269,-.02765*
20,1,.006,.05269,-.02765,.05927,-.03423,0.0*
1,1,.006,.05927,-.03423*
20,1,.006,.05927,-.03423,.0698,-.03818,0.0*
1,1,.006,.0698,-.03818*
20,1,.006,.0698,-.03818,.07902,-.0395,0.0*
1,1,.006,.07902,-.0395*
%
%ADD21MACRO21*%
%AMMACRO17*
1,1,.006,.035,0.0*
20,1,.006,.035,0.0,.034468,-.006078,0.0*
1,1,.006,.034468,-.006078*
20,1,.006,.034468,-.006078,.032889,-.011971,0.0*
1,1,.006,.032889,-.011971*
20,1,.006,.032889,-.011971,.030311,-.0175,0.0*
1,1,.006,.030311,-.0175*
20,1,.006,.030311,-.0175,.026812,-.022498,0.0*
1,1,.006,.026812,-.022498*
20,1,.006,.026812,-.022498,.022498,-.026812,0.0*
1,1,.006,.022498,-.026812*
20,1,.006,.022498,-.026812,.0175,-.030311,0.0*
1,1,.006,.0175,-.030311*
20,1,.006,.0175,-.030311,.011971,-.032889,0.0*
1,1,.006,.011971,-.032889*
20,1,.006,.011971,-.032889,.006078,-.034468,0.0*
1,1,.006,.006078,-.034468*
20,1,.006,.006078,-.034468,0.0,-.035,0.0*
1,1,.006,0.0,-.035*
20,1,.006,0.0,-.035,-.006078,-.034468,0.0*
1,1,.006,-.006078,-.034468*
20,1,.006,-.006078,-.034468,-.011971,-.032889,0.0*
1,1,.006,-.011971,-.032889*
20,1,.006,-.011971,-.032889,-.0175,-.030311,0.0*
1,1,.006,-.0175,-.030311*
20,1,.006,-.0175,-.030311,-.022498,-.026812,0.0*
1,1,.006,-.022498,-.026812*
20,1,.006,-.022498,-.026812,-.026812,-.022498,0.0*
1,1,.006,-.026812,-.022498*
20,1,.006,-.026812,-.022498,-.030311,-.0175,0.0*
1,1,.006,-.030311,-.0175*
20,1,.006,-.030311,-.0175,-.032889,-.011971,0.0*
1,1,.006,-.032889,-.011971*
20,1,.006,-.032889,-.011971,-.034468,-.006078,0.0*
1,1,.006,-.034468,-.006078*
20,1,.006,-.034468,-.006078,-.035,0.0,0.0*
1,1,.006,-.035,0.0*
20,1,.006,-.035,0.0,-.034468,.006078,0.0*
1,1,.006,-.034468,.006078*
20,1,.006,-.034468,.006078,-.032889,.011971,0.0*
1,1,.006,-.032889,.011971*
20,1,.006,-.032889,.011971,-.030311,.0175,0.0*
1,1,.006,-.030311,.0175*
20,1,.006,-.030311,.0175,-.026812,.022498,0.0*
1,1,.006,-.026812,.022498*
20,1,.006,-.026812,.022498,-.022498,.026812,0.0*
1,1,.006,-.022498,.026812*
20,1,.006,-.022498,.026812,-.0175,.030311,0.0*
1,1,.006,-.0175,.030311*
20,1,.006,-.0175,.030311,-.011971,.032889,0.0*
1,1,.006,-.011971,.032889*
20,1,.006,-.011971,.032889,-.006078,.034468,0.0*
1,1,.006,-.006078,.034468*
20,1,.006,-.006078,.034468,0.0,.035,0.0*
1,1,.006,0.0,.035*
20,1,.006,0.0,.035,.006078,.034468,0.0*
1,1,.006,.006078,.034468*
20,1,.006,.006078,.034468,.011971,.032889,0.0*
1,1,.006,.011971,.032889*
20,1,.006,.011971,.032889,.0175,.030311,0.0*
1,1,.006,.0175,.030311*
20,1,.006,.0175,.030311,.022498,.026812,0.0*
1,1,.006,.022498,.026812*
20,1,.006,.022498,.026812,.026812,.022498,0.0*
1,1,.006,.026812,.022498*
20,1,.006,.026812,.022498,.030311,.0175,0.0*
1,1,.006,.030311,.0175*
20,1,.006,.030311,.0175,.032889,.011971,0.0*
1,1,.006,.032889,.011971*
20,1,.006,.032889,.011971,.034468,.006078,0.0*
1,1,.006,.034468,.006078*
20,1,.006,.034468,.006078,.035,0.0,0.0*
1,1,.006,.035,0.0*
1,1,.006,-.0455,.00583*
20,1,.006,-.0455,.00583,-.035,-.0175,0.0*
1,1,.006,-.035,-.0175*
20,1,.006,-.035,-.0175,-.0245,.00583,0.0*
1,1,.006,-.0245,.00583*
1,1,.006,.00001,.00583*
20,1,.006,.00001,.00583,.00001,-.0175,0.0*
1,1,.006,.00001,-.0175*
1,1,.006,.00001,.01517*
20,1,.006,.00001,.01517,-.00116,.01575,0.0*
1,1,.006,-.00116,.01575*
20,1,.006,-.00116,.01575,-.00116,.01692,0.0*
1,1,.006,-.00116,.01692*
20,1,.006,-.00116,.01692,.00001,.0175,0.0*
1,1,.006,.00001,.0175*
20,1,.006,.00001,.0175,.00118,.01692,0.0*
1,1,.006,.00118,.01692*
20,1,.006,.00118,.01692,.00118,.01575,0.0*
1,1,.006,.00118,.01575*
20,1,.006,.00118,.01575,.00001,.01517,0.0*
1,1,.006,.00001,.01517*
1,1,.006,.04552,-.0175*
20,1,.006,.04552,-.0175,.04552,.00583,0.0*
1,1,.006,.04552,.00583*
1,1,.006,.04552,.00175*
20,1,.006,.04552,.00175,.04319,.00408,0.0*
1,1,.006,.04319,.00408*
20,1,.006,.04319,.00408,.03969,.00525,0.0*
1,1,.006,.03969,.00525*
20,1,.006,.03969,.00525,.0356,.00583,0.0*
1,1,.006,.0356,.00583*
20,1,.006,.0356,.00583,.03152,.00467,0.0*
1,1,.006,.03152,.00467*
20,1,.006,.03152,.00467,.02802,.00233,0.0*
1,1,.006,.02802,.00233*
20,1,.006,.02802,.00233,.02569,-.00117,0.0*
1,1,.006,.02569,-.00117*
20,1,.006,.02569,-.00117,.02452,-.00583,0.0*
1,1,.006,.02452,-.00583*
20,1,.006,.02452,-.00583,.02569,-.0105,0.0*
1,1,.006,.02569,-.0105*
20,1,.006,.02569,-.0105,.02802,-.014,0.0*
1,1,.006,.02802,-.014*
20,1,.006,.02802,-.014,.03152,-.01633,0.0*
1,1,.006,.03152,-.01633*
20,1,.006,.03152,-.01633,.0356,-.0175,0.0*
1,1,.006,.0356,-.0175*
20,1,.006,.0356,-.0175,.03969,-.01692,0.0*
1,1,.006,.03969,-.01692*
20,1,.006,.03969,-.01692,.04319,-.01517,0.0*
1,1,.006,.04319,-.01517*
20,1,.006,.04319,-.01517,.04552,-.01283,0.0*
1,1,.006,.04552,-.01283*
%
%ADD17MACRO17*%
%ADD31C,.006*%
G75*
%LPD*%
G75*
G36*
G01X857300Y604800D02*
Y444800D01*
X862300Y424800D01*
X872300D01*
X877300Y444800D01*
Y604300D01*
X872300Y594800D01*
X857300Y604800D01*
G37*
G54D10*
X8221Y28000D03*
Y9008D03*
X4287Y18504D03*
X17717Y5074D03*
X27213Y28000D03*
X31147Y18504D03*
X27213Y9008D03*
X17717Y31934D03*
X1661016Y28000D03*
Y9008D03*
X1657082Y18504D03*
X1670512Y5074D03*
X1680008Y28000D03*
X1683942Y18504D03*
X1680008Y9008D03*
X1670512Y31934D03*
X1776200Y299750D03*
G54D11*
X9088Y80158D03*
Y91958D03*
X19088Y80158D03*
Y91958D03*
X109288Y92458D03*
X119288D03*
X109288Y103958D03*
X119288D03*
X1776200Y110150D03*
G54D20*
X120500Y59400D03*
X114400Y59700D03*
X107500Y59500D03*
X122758Y82442D03*
X117158Y82542D03*
X112158Y82342D03*
X106958Y82142D03*
X125558Y79642D03*
X357600Y97000D03*
X367200Y124000D03*
X397800Y23600D03*
Y19500D03*
X398307Y35000D03*
Y46100D03*
X396732Y78932D03*
X417900Y6700D03*
X410200D03*
X404400Y6800D03*
X408200Y23500D03*
Y19900D03*
X405531Y21960D03*
X400531D03*
X400100Y13900D03*
X412800Y16200D03*
X417205Y35000D03*
X407600D03*
X407756Y46100D03*
X417205D03*
X410906D03*
X414055Y46200D03*
X412480Y80900D03*
X403032Y89532D03*
X415630Y80700D03*
X412300Y85600D03*
X421929Y78400D03*
X409331Y88600D03*
X406181Y82300D03*
X399882Y79318D03*
X426500Y35000D03*
X426654Y46100D03*
X426200Y78100D03*
X446000Y38400D03*
Y33900D03*
X455400Y34000D03*
Y38600D03*
X447880Y36200D03*
X453480D03*
X465600Y55900D03*
X466200Y87558D03*
X466100Y83258D03*
X466300Y100900D03*
X474500Y3900D03*
X490200Y4000D03*
X488800Y73700D03*
Y93800D03*
X507200Y4200D03*
X505700Y90200D03*
X511600Y108000D03*
X520900Y22500D03*
X525600Y22600D03*
Y13900D03*
X520800Y13800D03*
X523300Y15580D03*
Y20580D03*
X526612Y142000D03*
X559425Y13575D03*
X560198Y46100D03*
X556900Y35000D03*
X547599D03*
X557048Y46100D03*
X547599D03*
X558623Y79200D03*
X552324Y78500D03*
X546024Y79200D03*
X549174Y89400D03*
X575600Y7600D03*
X567500Y7300D03*
X563100Y7200D03*
X582416Y16466D03*
X567100Y20500D03*
X575900Y20800D03*
X575800Y24300D03*
X567000Y24400D03*
X573721Y22500D03*
X568721D03*
X563347Y46100D03*
X575946D03*
X566497D03*
X575800Y35000D03*
X566497D03*
X571221Y79700D03*
X568072Y81500D03*
X564922Y81900D03*
X561772Y80800D03*
X574371Y78400D03*
X563800Y87700D03*
X604400Y96000D03*
X626100Y99900D03*
X626600Y106100D03*
X648300Y55600D03*
X651500Y94700D03*
X651100Y91100D03*
X655200Y4100D03*
X661600Y75900D03*
X667200Y75700D03*
X665100Y55900D03*
X670414Y96486D03*
X658400Y102500D03*
X659390Y117490D03*
X668839Y117661D03*
X667500Y126200D03*
X688800Y4100D03*
X681600Y55500D03*
X698400Y90300D03*
X679862Y96538D03*
X678288Y122700D03*
X697185Y117385D03*
X687736Y118700D03*
X685600Y133200D03*
X680900D03*
X701732Y101968D03*
X745256Y96044D03*
X743681Y117400D03*
X731950Y111850D03*
X723500Y118900D03*
X722400Y102300D03*
X730900Y108900D03*
X753100Y75100D03*
X765600Y74800D03*
X754704Y96196D03*
X762578Y117300D03*
X753130D03*
X754300Y121400D03*
X764000Y124700D03*
X774600Y90300D03*
X772027Y117300D03*
X1218000Y99100D03*
X1238900Y123300D03*
X1273000Y6100D03*
X1270610Y21960D03*
X1267700Y22900D03*
Y19700D03*
X1268700Y14000D03*
X1268386Y35000D03*
Y46100D03*
X1266811Y78300D03*
X1273111Y89100D03*
X1269961Y78400D03*
X1276700Y5900D03*
X1280900D03*
X1285800D03*
X1278700Y19800D03*
Y23000D03*
X1275610Y21960D03*
X1289775Y11975D03*
X1296600Y35000D03*
X1277700D03*
X1287284D03*
X1296733Y46100D03*
X1287284D03*
X1277835D03*
X1284134D03*
X1280985Y46200D03*
X1295158Y79158D03*
X1292008Y80192D03*
X1288859Y78400D03*
X1279410Y87200D03*
X1285709Y84300D03*
X1276260Y79000D03*
X1282559Y85700D03*
X1315879Y38200D03*
X1315979Y33900D03*
X1317959Y36200D03*
X1323559D03*
X1325279Y38600D03*
Y33800D03*
X1335300Y55600D03*
X1340400Y90800D03*
X1333400Y82900D03*
X1329500Y81400D03*
X1335600Y96500D03*
X1360600Y4000D03*
X1344700Y4100D03*
X1358200Y69000D03*
X1358600Y73700D03*
X1345100Y105500D03*
X1376300Y4000D03*
X1371600Y86463D03*
Y96000D03*
X1395679Y22600D03*
X1390979Y22500D03*
X1390879Y13800D03*
X1395679Y13900D03*
X1393379Y20580D03*
Y15580D03*
X1433700Y8000D03*
X1429525Y13775D03*
X1417678Y46100D03*
X1427127D03*
X1417678Y35000D03*
X1427000D03*
X1433426Y46100D03*
X1430277D03*
X1416103Y78400D03*
X1422403D03*
X1434200Y88100D03*
X1435001Y81700D03*
X1431851Y80200D03*
X1428702Y79002D03*
X1429400Y88500D03*
X1438000Y8100D03*
X1446300Y8300D03*
X1436500Y23900D03*
Y20700D03*
X1445900Y20800D03*
X1445700Y24400D03*
X1443800Y22500D03*
X1438800D03*
X1454600Y17600D03*
X1446025Y46100D03*
X1436576D03*
X1445900Y35000D03*
X1436576D03*
X1444450Y78300D03*
X1441300Y79100D03*
X1438151Y81100D03*
X1472400Y102700D03*
X1474200Y106600D03*
X1494700Y111200D03*
X1494500Y102700D03*
X1527200Y3800D03*
X1518200Y55600D03*
X1521579Y94700D03*
X1521179Y91100D03*
X1537279Y75700D03*
X1531679Y75900D03*
X1535300Y55800D03*
X1549940Y96538D03*
X1540492Y96486D03*
X1528478Y102500D03*
X1548366Y122700D03*
X1538917Y117661D03*
X1529468Y117490D03*
X1550979Y133200D03*
X1537579Y126200D03*
X1559000Y4200D03*
X1551800Y55700D03*
X1568479Y90300D03*
X1571810Y101968D03*
X1557814Y118700D03*
X1567263Y117385D03*
X1555679Y133200D03*
X1592900Y101700D03*
X1593300Y119000D03*
X1615334Y96044D03*
X1613759Y117400D03*
X1602028Y111850D03*
X1600900Y108700D03*
X1635679Y74800D03*
X1623179Y75100D03*
X1624782Y96196D03*
X1623208Y117300D03*
X1642105D03*
X1632656D03*
X1624300Y121500D03*
X1634179Y124300D03*
X1644679Y90300D03*
X1676100Y78900D03*
X1776200Y394550D03*
G54D21*
X306772Y19685D03*
Y41850D03*
Y67913D03*
X612047Y19685D03*
Y41850D03*
Y67913D03*
X1176851Y19685D03*
Y41850D03*
Y67913D03*
X1482126Y19685D03*
Y41850D03*
Y67913D03*
X1776200Y15350D03*
G54D30*
X641212Y132244D03*
X791764D03*
X1511291D03*
X1661843D03*
X1776200Y86450D03*
G54D12*
X17717Y18504D03*
X1670512D03*
X1776200Y-150550D03*
G54D31*
G01X14716Y114173D02*
X-94875D01*
G01X-3000Y0D02*
X-83399D01*
G01X1181292Y163386D02*
X-83375D01*
G01X1308299Y196063D02*
X-73425D01*
G01X4874Y0D02*
X-47500D01*
G01X-44500Y71125D02*
Y0D01*
G01X-45500Y5000D02*
X-44500Y0D01*
X-43500Y5000D01*
X-45500D01*
G01X1667512Y18504D02*
X-62225D01*
G01X-44500Y123675D02*
Y209842D01*
G01X2906D02*
X-47500D01*
G01X-43500Y204842D02*
X-44500Y209842D01*
X-45500Y204842D01*
X-43500D01*
G01X0Y-3000D02*
Y-56199D01*
G01Y200937D02*
Y-45825D01*
G01X1683504Y165354D02*
Y190512D01*
G03X1675630Y198386I-7874J0D01*
G01X1503898D01*
X1502406Y198679D01*
X1501137Y199516D01*
X1500279Y200772D01*
X1499930Y202268D01*
X1499661Y203554D01*
X1498808Y204831D01*
X1497530Y205685D01*
X1496024Y205984D01*
X1468465D01*
G03X1464528Y202047I0J-3937D01*
G01Y200000D01*
G02X1460591Y196063I-3937J0D01*
G01X1401535D01*
G02X1397598Y200000I0J3937D01*
G01Y202047D01*
G03X1393661Y205984I-3937J0D01*
G01X1319173D01*
G03X1315236Y202047I0J-3937D01*
G01Y200000D01*
G02X1311299Y196063I-3937J0D01*
G01X1252244D01*
G02X1248307Y200000I0J3937D01*
G01Y202047D01*
G03X1244370Y205984I-3937J0D01*
G01X807047D01*
X805541Y205685D01*
X804263Y204831D01*
X803410Y203554D01*
X803141Y202268D01*
X802792Y200772D01*
X801934Y199516D01*
X800665Y198679D01*
X799173Y198386D01*
X633819D01*
X632327Y198679D01*
X631058Y199516D01*
X630200Y200772D01*
X629851Y202268D01*
X629582Y203554D01*
X628729Y204831D01*
X627451Y205685D01*
X625945Y205984D01*
X598386D01*
G03X594449Y202047I0J-3937D01*
G01Y200000D01*
G02X590512Y196063I-3937J0D01*
G01X531457D01*
G02X527520Y200000I0J3937D01*
G01Y202047D01*
G03X523583Y205984I-3937J0D01*
G01X449094D01*
G03X445157Y202047I0J-3937D01*
G01Y200000D01*
G02X441220Y196063I-3937J0D01*
G01X382165D01*
G02X378228Y200000I0J3937D01*
G01Y202047D01*
G03X374291Y205984I-3937J0D01*
G01X228661D01*
G03X220787Y198110I0J-7874D01*
G01Y170551D01*
G02X216850Y166614I-3937J0D01*
G01X208976D01*
G02X205039Y170551I0J3937D01*
G01Y203937D01*
X199134Y209842D01*
X49803D01*
X43898Y203937D01*
Y167913D01*
G02X41142I-1378J0D01*
G01Y203937D01*
X37205Y207874D01*
X35236Y209842D01*
X5906D01*
X3937Y207874D01*
X0Y203937D01*
Y7874D01*
G03X7874Y0I7874J0D01*
G01X1680354D01*
G03X1688228Y7874I0J7874D01*
G01Y39370D01*
G03X1686260Y41339I-1969J0D01*
G01X1685472D01*
G02X1683504Y43307I0J1968D01*
G01Y122047D01*
G03X1681535Y124016I-1969J0D01*
G01X1675236D01*
G02X1673268Y125984I0J1968D01*
G01Y161417D01*
G02X1675236Y163386I1968J1D01*
G01X1681535D01*
G03X1683504Y165354I1J1968D01*
G01X10433Y114173D02*
Y128497D01*
G02X25000I7283J9298D01*
G01Y114173D01*
G02X10433I-7284J0D01*
G01X0Y206937D02*
Y275700D01*
G01X5906Y212842D02*
Y231425D01*
G01X783875Y272700D02*
X0D01*
G01X5000Y273700D02*
X0Y272700D01*
X5000Y271700D01*
Y273700D01*
G01X17717Y15504D02*
Y-17375D01*
G01X17716Y117173D02*
Y228875D01*
G01X35236Y212842D02*
Y222975D01*
G01X43898Y206937D02*
Y224000D01*
G01X148971Y700232D02*
X136471D01*
X138971Y698372D01*
G01X148971D02*
Y702092D01*
G01X136471Y712632D02*
X136888Y711392D01*
X137929Y710462D01*
X139179Y709842D01*
X140846Y709377D01*
X142721Y709222D01*
X144596Y709377D01*
X146263Y709842D01*
X147513Y710462D01*
X148554Y711392D01*
X148971Y712632D01*
X148554Y713872D01*
X147513Y714802D01*
X146263Y715422D01*
X144596Y715887D01*
X142721Y716042D01*
X140846Y715887D01*
X139179Y715422D01*
X137929Y714802D01*
X136888Y713872D01*
X136471Y712632D01*
G01X148971Y721002D02*
X136471D01*
X146888Y725032D01*
X136471Y729062D01*
X148971D01*
G01Y733402D02*
X136471D01*
X146888Y737432D01*
X136471Y741462D01*
X148971D01*
G01X157830Y705052D02*
Y673556D01*
G01D02*
Y724737D01*
G01X224060Y705052D02*
X149956D01*
G01X157830Y775918D02*
Y724737D01*
G01Y744422D02*
Y775918D01*
G01X223206Y744422D02*
X149956D01*
G01X175800Y936600D02*
X177800D01*
Y934200D01*
X177200Y933400D01*
X176500Y932867D01*
X175500Y932600D01*
X174500Y932867D01*
X173800Y933400D01*
X173200Y934200D01*
X172800Y935133D01*
X172600Y936200D01*
Y937133D01*
X172800Y937933D01*
X173200Y938867D01*
X173800Y939667D01*
X174400Y940200D01*
X175200Y940600D01*
X175900D01*
X176700Y940333D01*
X177300Y939800D01*
G01X181200Y932600D02*
Y940600D01*
X183700D01*
X184500Y940200D01*
X185000Y939667D01*
X185200Y938600D01*
X185000Y937533D01*
X184400Y936867D01*
X183700Y936467D01*
X181200D01*
G01X183700D02*
X185200Y932600D01*
G01X191200D02*
X190400Y932733D01*
X189700Y933267D01*
X189100Y934067D01*
X188700Y935000D01*
X188500Y936067D01*
Y937133D01*
X188700Y938200D01*
X189100Y939133D01*
X189700Y939933D01*
X190400Y940467D01*
X191200Y940600D01*
X192000Y940467D01*
X192700Y939933D01*
X193300Y939133D01*
X193700Y938200D01*
X193900Y937133D01*
Y936067D01*
X193700Y935000D01*
X193300Y934067D01*
X192700Y933267D01*
X192000Y932733D01*
X191200Y932600D01*
G01X197000Y940600D02*
Y934867D01*
X197400Y933666D01*
X198200Y932867D01*
X199200Y932600D01*
X200200Y932867D01*
X201000Y933666D01*
X201400Y934867D01*
Y940600D01*
G01X205200Y932600D02*
Y940600D01*
X207600D01*
X208400Y940200D01*
X209000Y939267D01*
X209200Y938200D01*
X209000Y937133D01*
X208500Y936333D01*
X207600Y935933D01*
X205200D01*
G01X213100Y933666D02*
X213900Y933000D01*
X214800Y932600D01*
X215600D01*
X216400Y933000D01*
X217000Y933666D01*
X217300Y934600D01*
X217100Y935533D01*
X216600Y936333D01*
X215700Y936867D01*
X214500Y937133D01*
X213800Y937667D01*
X213500Y938600D01*
X213700Y939533D01*
X214200Y940200D01*
X214900Y940600D01*
X215600D01*
X216300Y940333D01*
X216900Y939667D01*
G01X228700Y932600D02*
X231200Y940600D01*
X233700Y932600D01*
G01X232800Y935400D02*
X229600D01*
G01X244700Y932600D02*
X247200Y940600D01*
X249700Y932600D01*
G01X248800Y935400D02*
X245600D01*
G01X252900Y932600D02*
Y940600D01*
X257500Y932600D01*
Y940600D01*
G01X261000Y932600D02*
Y940600D01*
X263000D01*
X263800Y940200D01*
X264400Y939667D01*
X264900Y938867D01*
X265300Y937933D01*
X265400Y936600D01*
X265300Y935267D01*
X264900Y934333D01*
X264400Y933533D01*
X263800Y933000D01*
X263000Y932600D01*
X261000D01*
G01X280000Y936867D02*
X280400Y937267D01*
X280700Y937933D01*
X280900Y938867D01*
X280700Y939667D01*
X280300Y940200D01*
X279600Y940600D01*
X276900D01*
Y932600D01*
X280200D01*
X280900Y933133D01*
X281300Y933933D01*
X281500Y934867D01*
X281300Y935800D01*
X280700Y936600D01*
X280000Y936867D01*
X276900D01*
G01X287000Y931133D02*
X287400Y932867D01*
G01X295200Y940600D02*
Y932600D01*
G01X292900Y940600D02*
X297500D01*
G01X301100Y932600D02*
Y940600D01*
G01X305300D02*
Y932600D01*
G01Y936600D02*
X301100D01*
G01X313200Y932600D02*
X309200D01*
Y940600D01*
X313200D01*
G01X311600Y936733D02*
X309200D01*
G01X316900Y932600D02*
Y940600D01*
X321500Y932600D01*
Y940600D01*
G01X335800Y936600D02*
X337800D01*
Y934200D01*
X337200Y933400D01*
X336500Y932867D01*
X335500Y932600D01*
X334500Y932867D01*
X333800Y933400D01*
X333200Y934200D01*
X332800Y935133D01*
X332600Y936200D01*
Y937133D01*
X332800Y937933D01*
X333200Y938867D01*
X333800Y939667D01*
X334400Y940200D01*
X335200Y940600D01*
X335900D01*
X336700Y940333D01*
X337300Y939800D01*
G01X341200Y932600D02*
Y940600D01*
X343700D01*
X344500Y940200D01*
X345000Y939667D01*
X345200Y938600D01*
X345000Y937533D01*
X344400Y936867D01*
X343700Y936467D01*
X341200D01*
G01X343700D02*
X345200Y932600D01*
G01X351200D02*
X350400Y932733D01*
X349700Y933267D01*
X349100Y934067D01*
X348700Y935000D01*
X348500Y936067D01*
Y937133D01*
X348700Y938200D01*
X349100Y939133D01*
X349700Y939933D01*
X350400Y940467D01*
X351200Y940600D01*
X352000Y940467D01*
X352700Y939933D01*
X353300Y939133D01*
X353700Y938200D01*
X353900Y937133D01*
Y936067D01*
X353700Y935000D01*
X353300Y934067D01*
X352700Y933267D01*
X352000Y932733D01*
X351200Y932600D01*
G01X357000Y940600D02*
Y934867D01*
X357400Y933666D01*
X358200Y932867D01*
X359200Y932600D01*
X360200Y932867D01*
X361000Y933666D01*
X361400Y934867D01*
Y940600D01*
G01X365200Y932600D02*
Y940600D01*
X367600D01*
X368400Y940200D01*
X369000Y939267D01*
X369200Y938200D01*
X369000Y937133D01*
X368500Y936333D01*
X367600Y935933D01*
X365200D01*
G01X380700Y932600D02*
X383200Y940600D01*
X385700Y932600D01*
G01X384800Y935400D02*
X381600D01*
G01X401400Y939933D02*
X400800Y940333D01*
X400100Y940600D01*
X399300D01*
X398400Y940200D01*
X397700Y939533D01*
X397200Y938733D01*
X396800Y937400D01*
X396700Y936200D01*
X396900Y935000D01*
X397200Y934200D01*
X397800Y933400D01*
X398500Y932867D01*
X399200Y932600D01*
X399900D01*
X400600Y932867D01*
X401200Y933267D01*
X401700Y933800D01*
G01X404700Y932600D02*
X407200Y940600D01*
X409700Y932600D01*
G01X408800Y935400D02*
X405600D01*
G01X412900Y932600D02*
Y940600D01*
X417500Y932600D01*
Y940600D01*
G01X432000Y936867D02*
X432400Y937267D01*
X432700Y937933D01*
X432900Y938867D01*
X432700Y939667D01*
X432300Y940200D01*
X431600Y940600D01*
X428900D01*
Y932600D01*
X432200D01*
X432900Y933133D01*
X433300Y933933D01*
X433500Y934867D01*
X433300Y935800D01*
X432700Y936600D01*
X432000Y936867D01*
X428900D01*
G01X441200Y932600D02*
X437200D01*
Y940600D01*
X441200D01*
G01X439600Y936733D02*
X437200D01*
G01X453200Y932600D02*
Y940600D01*
X455600D01*
X456400Y940200D01*
X457000Y939267D01*
X457200Y938200D01*
X457000Y937133D01*
X456500Y936333D01*
X455600Y935933D01*
X453200D01*
G01X461200Y940600D02*
Y932600D01*
X465200D01*
G01X468700D02*
X471200Y940600D01*
X473700Y932600D01*
G01X472800Y935400D02*
X469600D01*
G01X481400Y939933D02*
X480800Y940333D01*
X480100Y940600D01*
X479300D01*
X478400Y940200D01*
X477700Y939533D01*
X477200Y938733D01*
X476800Y937400D01*
X476700Y936200D01*
X476900Y935000D01*
X477200Y934200D01*
X477800Y933400D01*
X478500Y932867D01*
X479200Y932600D01*
X479900D01*
X480600Y932867D01*
X481200Y933267D01*
X481700Y933800D01*
G01X489200Y932600D02*
X485200D01*
Y940600D01*
X489200D01*
G01X487600Y936733D02*
X485200D01*
G01X493000Y932600D02*
Y940600D01*
X495000D01*
X495800Y940200D01*
X496400Y939667D01*
X496900Y938867D01*
X497300Y937933D01*
X497400Y936600D01*
X497300Y935267D01*
X496900Y934333D01*
X496400Y933533D01*
X495800Y933000D01*
X495000Y932600D01*
X493000D01*
G01X509100Y933666D02*
X509900Y933000D01*
X510800Y932600D01*
X511600D01*
X512400Y933000D01*
X513000Y933666D01*
X513300Y934600D01*
X513100Y935533D01*
X512600Y936333D01*
X511700Y936867D01*
X510500Y937133D01*
X509800Y937667D01*
X509500Y938600D01*
X509700Y939533D01*
X510200Y940200D01*
X510900Y940600D01*
X511600D01*
X512300Y940333D01*
X512900Y939667D01*
G01X521200Y932600D02*
X517200D01*
Y940600D01*
X521200D01*
G01X519600Y936733D02*
X517200D01*
G01X525200Y932600D02*
Y940600D01*
X527600D01*
X528400Y940200D01*
X529000Y939267D01*
X529200Y938200D01*
X529000Y937133D01*
X528500Y936333D01*
X527600Y935933D01*
X525200D01*
G01X532700Y932600D02*
X535200Y940600D01*
X537700Y932600D01*
G01X536800Y935400D02*
X533600D01*
G01X541200Y932600D02*
Y940600D01*
X543700D01*
X544500Y940200D01*
X545000Y939667D01*
X545200Y938600D01*
X545000Y937533D01*
X544400Y936867D01*
X543700Y936467D01*
X541200D01*
G01X543700D02*
X545200Y932600D01*
G01X548700D02*
X551200Y940600D01*
X553700Y932600D01*
G01X552800Y935400D02*
X549600D01*
G01X559200Y940600D02*
Y932600D01*
G01X556900Y940600D02*
X561500D01*
G01X569200Y932600D02*
X565200D01*
Y940600D01*
X569200D01*
G01X567600Y936733D02*
X565200D01*
G01X573200Y940600D02*
Y932600D01*
X577200D01*
G01X583200D02*
Y936200D01*
X581200Y940600D01*
G01X585200D02*
X583200Y936200D01*
G01X597300Y932600D02*
Y940600D01*
X601100D01*
G01X599700Y936733D02*
X597300D01*
G01X605200Y932600D02*
Y940600D01*
X607700D01*
X608500Y940200D01*
X609000Y939667D01*
X609200Y938600D01*
X609000Y937533D01*
X608400Y936867D01*
X607700Y936467D01*
X605200D01*
G01X607700D02*
X609200Y932600D01*
G01X615200D02*
X614400Y932733D01*
X613700Y933267D01*
X613100Y934067D01*
X612700Y935000D01*
X612500Y936067D01*
Y937133D01*
X612700Y938200D01*
X613100Y939133D01*
X613700Y939933D01*
X614400Y940467D01*
X615200Y940600D01*
X616000Y940467D01*
X616700Y939933D01*
X617300Y939133D01*
X617700Y938200D01*
X617900Y937133D01*
Y936067D01*
X617700Y935000D01*
X617300Y934067D01*
X616700Y933267D01*
X616000Y932733D01*
X615200Y932600D01*
G01X620600D02*
Y940600D01*
X623200Y933933D01*
X625800Y940600D01*
Y932600D01*
G01X639800Y936600D02*
X641800D01*
Y934200D01*
X641200Y933400D01*
X640500Y932867D01*
X639500Y932600D01*
X638500Y932867D01*
X637800Y933400D01*
X637200Y934200D01*
X636800Y935133D01*
X636600Y936200D01*
Y937133D01*
X636800Y937933D01*
X637200Y938867D01*
X637800Y939667D01*
X638400Y940200D01*
X639200Y940600D01*
X639900D01*
X640700Y940333D01*
X641300Y939800D01*
G01X645200Y932600D02*
Y940600D01*
X647700D01*
X648500Y940200D01*
X649000Y939667D01*
X649200Y938600D01*
X649000Y937533D01*
X648400Y936867D01*
X647700Y936467D01*
X645200D01*
G01X647700D02*
X649200Y932600D01*
G01X655200D02*
X654400Y932733D01*
X653700Y933267D01*
X653100Y934067D01*
X652700Y935000D01*
X652500Y936067D01*
Y937133D01*
X652700Y938200D01*
X653100Y939133D01*
X653700Y939933D01*
X654400Y940467D01*
X655200Y940600D01*
X656000Y940467D01*
X656700Y939933D01*
X657300Y939133D01*
X657700Y938200D01*
X657900Y937133D01*
Y936067D01*
X657700Y935000D01*
X657300Y934067D01*
X656700Y933267D01*
X656000Y932733D01*
X655200Y932600D01*
G01X661000Y940600D02*
Y934867D01*
X661400Y933666D01*
X662200Y932867D01*
X663200Y932600D01*
X664200Y932867D01*
X665000Y933666D01*
X665400Y934867D01*
Y940600D01*
G01X669200Y932600D02*
Y940600D01*
X671600D01*
X672400Y940200D01*
X673000Y939267D01*
X673200Y938200D01*
X673000Y937133D01*
X672500Y936333D01*
X671600Y935933D01*
X669200D01*
G01X688000Y936867D02*
X688400Y937267D01*
X688700Y937933D01*
X688900Y938867D01*
X688700Y939667D01*
X688300Y940200D01*
X687600Y940600D01*
X684900D01*
Y932600D01*
X688200D01*
X688900Y933133D01*
X689300Y933933D01*
X689500Y934867D01*
X689300Y935800D01*
X688700Y936600D01*
X688000Y936867D01*
X684900D01*
G01X695200Y932333D02*
X695000Y932467D01*
Y932733D01*
X695200Y932867D01*
X695400Y932733D01*
Y932467D01*
X695200Y932333D01*
G01X175200Y955600D02*
Y947600D01*
G01X172900Y955600D02*
X177500D01*
G01X183200Y947600D02*
X182400Y947733D01*
X181700Y948267D01*
X181100Y949067D01*
X180700Y950000D01*
X180500Y951067D01*
Y952133D01*
X180700Y953200D01*
X181100Y954133D01*
X181700Y954933D01*
X182400Y955467D01*
X183200Y955600D01*
X184000Y955467D01*
X184700Y954933D01*
X185300Y954133D01*
X185700Y953200D01*
X185900Y952133D01*
Y951067D01*
X185700Y950000D01*
X185300Y949067D01*
X184700Y948267D01*
X184000Y947733D01*
X183200Y947600D01*
G01X199200Y955600D02*
Y947600D01*
G01X196900Y955600D02*
X201500D01*
G01X205100Y947600D02*
Y955600D01*
G01X209300D02*
Y947600D01*
G01Y951600D02*
X205100D01*
G01X217200Y947600D02*
X213200D01*
Y955600D01*
X217200D01*
G01X215600Y951733D02*
X213200D01*
G01X232000Y951867D02*
X232400Y952267D01*
X232700Y952933D01*
X232900Y953867D01*
X232700Y954667D01*
X232300Y955200D01*
X231600Y955600D01*
X228900D01*
Y947600D01*
X232200D01*
X232900Y948133D01*
X233300Y948933D01*
X233500Y949867D01*
X233300Y950800D01*
X232700Y951600D01*
X232000Y951867D01*
X228900D01*
G01X239200Y947600D02*
X238400Y947733D01*
X237700Y948267D01*
X237100Y949067D01*
X236700Y950000D01*
X236500Y951067D01*
Y952133D01*
X236700Y953200D01*
X237100Y954133D01*
X237700Y954933D01*
X238400Y955467D01*
X239200Y955600D01*
X240000Y955467D01*
X240700Y954933D01*
X241300Y954133D01*
X241700Y953200D01*
X241900Y952133D01*
Y951067D01*
X241700Y950000D01*
X241300Y949067D01*
X240700Y948267D01*
X240000Y947733D01*
X239200Y947600D01*
G01X244700D02*
X247200Y955600D01*
X249700Y947600D01*
G01X248800Y950400D02*
X245600D01*
G01X253200Y947600D02*
Y955600D01*
X255700D01*
X256500Y955200D01*
X257000Y954667D01*
X257200Y953600D01*
X257000Y952533D01*
X256400Y951867D01*
X255700Y951467D01*
X253200D01*
G01X255700D02*
X257200Y947600D01*
G01X261000D02*
Y955600D01*
X263000D01*
X263800Y955200D01*
X264400Y954667D01*
X264900Y953867D01*
X265300Y952933D01*
X265400Y951600D01*
X265300Y950267D01*
X264900Y949333D01*
X264400Y948533D01*
X263800Y948000D01*
X263000Y947600D01*
X261000D01*
G01X281400Y954933D02*
X280800Y955333D01*
X280100Y955600D01*
X279300D01*
X278400Y955200D01*
X277700Y954533D01*
X277200Y953733D01*
X276800Y952400D01*
X276700Y951200D01*
X276900Y950000D01*
X277200Y949200D01*
X277800Y948400D01*
X278500Y947867D01*
X279200Y947600D01*
X279900D01*
X280600Y947867D01*
X281200Y948267D01*
X281700Y948800D01*
G01X287200Y947600D02*
X286400Y947733D01*
X285700Y948267D01*
X285100Y949067D01*
X284700Y950000D01*
X284500Y951067D01*
Y952133D01*
X284700Y953200D01*
X285100Y954133D01*
X285700Y954933D01*
X286400Y955467D01*
X287200Y955600D01*
X288000Y955467D01*
X288700Y954933D01*
X289300Y954133D01*
X289700Y953200D01*
X289900Y952133D01*
Y951067D01*
X289700Y950000D01*
X289300Y949067D01*
X288700Y948267D01*
X288000Y947733D01*
X287200Y947600D01*
G01X293000Y955600D02*
Y949867D01*
X293400Y948666D01*
X294200Y947867D01*
X295200Y947600D01*
X296200Y947867D01*
X297000Y948666D01*
X297400Y949867D01*
Y955600D01*
G01X301200Y947600D02*
Y955600D01*
X303600D01*
X304400Y955200D01*
X305000Y954267D01*
X305200Y953200D01*
X305000Y952133D01*
X304500Y951333D01*
X303600Y950933D01*
X301200D01*
G01X311200Y947600D02*
X310400Y947733D01*
X309700Y948267D01*
X309100Y949067D01*
X308700Y950000D01*
X308500Y951067D01*
Y952133D01*
X308700Y953200D01*
X309100Y954133D01*
X309700Y954933D01*
X310400Y955467D01*
X311200Y955600D01*
X312000Y955467D01*
X312700Y954933D01*
X313300Y954133D01*
X313700Y953200D01*
X313900Y952133D01*
Y951067D01*
X313700Y950000D01*
X313300Y949067D01*
X312700Y948267D01*
X312000Y947733D01*
X311200Y947600D01*
G01X316900D02*
Y955600D01*
X321500Y947600D01*
Y955600D01*
G01X325100Y948666D02*
X325900Y948000D01*
X326800Y947600D01*
X327600D01*
X328400Y948000D01*
X329000Y948666D01*
X329300Y949600D01*
X329100Y950533D01*
X328600Y951333D01*
X327700Y951867D01*
X326500Y952133D01*
X325800Y952667D01*
X325500Y953600D01*
X325700Y954533D01*
X326200Y955200D01*
X326900Y955600D01*
X327600D01*
X328300Y955333D01*
X328900Y954667D01*
G01X335200Y947333D02*
X335000Y947467D01*
Y947733D01*
X335200Y947867D01*
X335400Y947733D01*
Y947467D01*
X335200Y947333D01*
G01X342000Y955600D02*
X344400D01*
G01X343200D02*
Y947600D01*
G01X342000D02*
X344400D01*
G01X349300D02*
Y955600D01*
X353100D01*
G01X351700Y951733D02*
X349300D01*
G01X366000Y955600D02*
X368400D01*
G01X367200D02*
Y947600D01*
G01X366000D02*
X368400D01*
G01X375200Y955600D02*
Y947600D01*
G01X372900Y955600D02*
X377500D01*
G01X390000D02*
X392400D01*
G01X391200D02*
Y947600D01*
G01X390000D02*
X392400D01*
G01X397100Y948666D02*
X397900Y948000D01*
X398800Y947600D01*
X399600D01*
X400400Y948000D01*
X401000Y948666D01*
X401300Y949600D01*
X401100Y950533D01*
X400600Y951333D01*
X399700Y951867D01*
X398500Y952133D01*
X397800Y952667D01*
X397500Y953600D01*
X397700Y954533D01*
X398200Y955200D01*
X398900Y955600D01*
X399600D01*
X400300Y955333D01*
X400900Y954667D01*
G01X412900Y947600D02*
Y955600D01*
X417500Y947600D01*
Y955600D01*
G01X423200Y947600D02*
X422400Y947733D01*
X421700Y948267D01*
X421100Y949067D01*
X420700Y950000D01*
X420500Y951067D01*
Y952133D01*
X420700Y953200D01*
X421100Y954133D01*
X421700Y954933D01*
X422400Y955467D01*
X423200Y955600D01*
X424000Y955467D01*
X424700Y954933D01*
X425300Y954133D01*
X425700Y953200D01*
X425900Y952133D01*
Y951067D01*
X425700Y950000D01*
X425300Y949067D01*
X424700Y948267D01*
X424000Y947733D01*
X423200Y947600D01*
G01X431200Y955600D02*
Y947600D01*
G01X428900Y955600D02*
X433500D01*
G01X445200Y947600D02*
Y955600D01*
X447600D01*
X448400Y955200D01*
X449000Y954267D01*
X449200Y953200D01*
X449000Y952133D01*
X448500Y951333D01*
X447600Y950933D01*
X445200D01*
G01X455200Y947600D02*
X454400Y947733D01*
X453700Y948267D01*
X453100Y949067D01*
X452700Y950000D01*
X452500Y951067D01*
Y952133D01*
X452700Y953200D01*
X453100Y954133D01*
X453700Y954933D01*
X454400Y955467D01*
X455200Y955600D01*
X456000Y955467D01*
X456700Y954933D01*
X457300Y954133D01*
X457700Y953200D01*
X457900Y952133D01*
Y951067D01*
X457700Y950000D01*
X457300Y949067D01*
X456700Y948267D01*
X456000Y947733D01*
X455200Y947600D01*
G01X461100Y948666D02*
X461900Y948000D01*
X462800Y947600D01*
X463600D01*
X464400Y948000D01*
X465000Y948666D01*
X465300Y949600D01*
X465100Y950533D01*
X464600Y951333D01*
X463700Y951867D01*
X462500Y952133D01*
X461800Y952667D01*
X461500Y953600D01*
X461700Y954533D01*
X462200Y955200D01*
X462900Y955600D01*
X463600D01*
X464300Y955333D01*
X464900Y954667D01*
G01X469100Y948666D02*
X469900Y948000D01*
X470800Y947600D01*
X471600D01*
X472400Y948000D01*
X473000Y948666D01*
X473300Y949600D01*
X473100Y950533D01*
X472600Y951333D01*
X471700Y951867D01*
X470500Y952133D01*
X469800Y952667D01*
X469500Y953600D01*
X469700Y954533D01*
X470200Y955200D01*
X470900Y955600D01*
X471600D01*
X472300Y955333D01*
X472900Y954667D01*
G01X478000Y955600D02*
X480400D01*
G01X479200D02*
Y947600D01*
G01X478000D02*
X480400D01*
G01X488000Y951867D02*
X488400Y952267D01*
X488700Y952933D01*
X488900Y953867D01*
X488700Y954667D01*
X488300Y955200D01*
X487600Y955600D01*
X484900D01*
Y947600D01*
X488200D01*
X488900Y948133D01*
X489300Y948933D01*
X489500Y949867D01*
X489300Y950800D01*
X488700Y951600D01*
X488000Y951867D01*
X484900D01*
G01X493200Y955600D02*
Y947600D01*
X497200D01*
G01X505200D02*
X501200D01*
Y955600D01*
X505200D01*
G01X503600Y951733D02*
X501200D01*
G01X519200Y955600D02*
Y947600D01*
G01X516900Y955600D02*
X521500D01*
G01X527200Y947600D02*
X526400Y947733D01*
X525700Y948267D01*
X525100Y949067D01*
X524700Y950000D01*
X524500Y951067D01*
Y952133D01*
X524700Y953200D01*
X525100Y954133D01*
X525700Y954933D01*
X526400Y955467D01*
X527200Y955600D01*
X528000Y955467D01*
X528700Y954933D01*
X529300Y954133D01*
X529700Y953200D01*
X529900Y952133D01*
Y951067D01*
X529700Y950000D01*
X529300Y949067D01*
X528700Y948267D01*
X528000Y947733D01*
X527200Y947600D01*
G01X541300D02*
Y955600D01*
X545100D01*
G01X543700Y951733D02*
X541300D01*
G01X549200Y955600D02*
Y947600D01*
X553200D01*
G01X557200Y955600D02*
Y947600D01*
X561200D01*
G01X567200D02*
X566400Y947733D01*
X565700Y948267D01*
X565100Y949067D01*
X564700Y950000D01*
X564500Y951067D01*
Y952133D01*
X564700Y953200D01*
X565100Y954133D01*
X565700Y954933D01*
X566400Y955467D01*
X567200Y955600D01*
X568000Y955467D01*
X568700Y954933D01*
X569300Y954133D01*
X569700Y953200D01*
X569900Y952133D01*
Y951067D01*
X569700Y950000D01*
X569300Y949067D01*
X568700Y948267D01*
X568000Y947733D01*
X567200Y947600D01*
G01X572200Y955600D02*
X573600Y947600D01*
X575200Y955600D01*
X576800Y947600D01*
X578200Y955600D01*
G01X585200Y947600D02*
X581200D01*
Y955600D01*
X585200D01*
G01X583600Y951733D02*
X581200D01*
G01X589200Y947600D02*
Y955600D01*
X591700D01*
X592500Y955200D01*
X593000Y954667D01*
X593200Y953600D01*
X593000Y952533D01*
X592400Y951867D01*
X591700Y951467D01*
X589200D01*
G01X591700D02*
X593200Y947600D01*
G01X607200Y955600D02*
Y947600D01*
G01X604900Y955600D02*
X609500D01*
G01X613100Y947600D02*
Y955600D01*
G01X617300D02*
Y947600D01*
G01Y951600D02*
X613100D01*
G01X625200Y947600D02*
X621200D01*
Y955600D01*
X625200D01*
G01X623600Y951733D02*
X621200D01*
G01X637200Y955600D02*
Y947600D01*
X641200D01*
G01X647200D02*
X646400Y947733D01*
X645700Y948267D01*
X645100Y949067D01*
X644700Y950000D01*
X644500Y951067D01*
Y952133D01*
X644700Y953200D01*
X645100Y954133D01*
X645700Y954933D01*
X646400Y955467D01*
X647200Y955600D01*
X648000Y955467D01*
X648700Y954933D01*
X649300Y954133D01*
X649700Y953200D01*
X649900Y952133D01*
Y951067D01*
X649700Y950000D01*
X649300Y949067D01*
X648700Y948267D01*
X648000Y947733D01*
X647200Y947600D01*
G01X657400Y954933D02*
X656800Y955333D01*
X656100Y955600D01*
X655300D01*
X654400Y955200D01*
X653700Y954533D01*
X653200Y953733D01*
X652800Y952400D01*
X652700Y951200D01*
X652900Y950000D01*
X653200Y949200D01*
X653800Y948400D01*
X654500Y947867D01*
X655200Y947600D01*
X655900D01*
X656600Y947867D01*
X657200Y948267D01*
X657700Y948800D01*
G01X660700Y947600D02*
X663200Y955600D01*
X665700Y947600D01*
G01X664800Y950400D02*
X661600D01*
G01X671200Y955600D02*
Y947600D01*
G01X668900Y955600D02*
X673500D01*
G01X678000D02*
X680400D01*
G01X679200D02*
Y947600D01*
G01X678000D02*
X680400D01*
G01X687200D02*
X686400Y947733D01*
X685700Y948267D01*
X685100Y949067D01*
X684700Y950000D01*
X684500Y951067D01*
Y952133D01*
X684700Y953200D01*
X685100Y954133D01*
X685700Y954933D01*
X686400Y955467D01*
X687200Y955600D01*
X688000Y955467D01*
X688700Y954933D01*
X689300Y954133D01*
X689700Y953200D01*
X689900Y952133D01*
Y951067D01*
X689700Y950000D01*
X689300Y949067D01*
X688700Y948267D01*
X688000Y947733D01*
X687200Y947600D01*
G01X692900D02*
Y955600D01*
X697500Y947600D01*
Y955600D01*
G01X701100Y948666D02*
X701900Y948000D01*
X702800Y947600D01*
X703600D01*
X704400Y948000D01*
X705000Y948666D01*
X705300Y949600D01*
X705100Y950533D01*
X704600Y951333D01*
X703700Y951867D01*
X702500Y952133D01*
X701800Y952667D01*
X701500Y953600D01*
X701700Y954533D01*
X702200Y955200D01*
X702900Y955600D01*
X703600D01*
X704300Y955333D01*
X704900Y954667D01*
G01X717300Y947600D02*
Y955600D01*
X721100D01*
G01X719700Y951733D02*
X717300D01*
G01X727200Y947600D02*
X726400Y947733D01*
X725700Y948267D01*
X725100Y949067D01*
X724700Y950000D01*
X724500Y951067D01*
Y952133D01*
X724700Y953200D01*
X725100Y954133D01*
X725700Y954933D01*
X726400Y955467D01*
X727200Y955600D01*
X728000Y955467D01*
X728700Y954933D01*
X729300Y954133D01*
X729700Y953200D01*
X729900Y952133D01*
Y951067D01*
X729700Y950000D01*
X729300Y949067D01*
X728700Y948267D01*
X728000Y947733D01*
X727200Y947600D01*
G01X733200D02*
Y955600D01*
X735700D01*
X736500Y955200D01*
X737000Y954667D01*
X737200Y953600D01*
X737000Y952533D01*
X736400Y951867D01*
X735700Y951467D01*
X733200D01*
G01X735700D02*
X737200Y947600D01*
G01X752000Y951867D02*
X752400Y952267D01*
X752700Y952933D01*
X752900Y953867D01*
X752700Y954667D01*
X752300Y955200D01*
X751600Y955600D01*
X748900D01*
Y947600D01*
X752200D01*
X752900Y948133D01*
X753300Y948933D01*
X753500Y949867D01*
X753300Y950800D01*
X752700Y951600D01*
X752000Y951867D01*
X748900D01*
G01X759200Y947600D02*
X758400Y947733D01*
X757700Y948267D01*
X757100Y949067D01*
X756700Y950000D01*
X756500Y951067D01*
Y952133D01*
X756700Y953200D01*
X757100Y954133D01*
X757700Y954933D01*
X758400Y955467D01*
X759200Y955600D01*
X760000Y955467D01*
X760700Y954933D01*
X761300Y954133D01*
X761700Y953200D01*
X761900Y952133D01*
Y951067D01*
X761700Y950000D01*
X761300Y949067D01*
X760700Y948267D01*
X760000Y947733D01*
X759200Y947600D01*
G01X767200Y955600D02*
Y947600D01*
G01X764900Y955600D02*
X769500D01*
G01X773100Y947600D02*
Y955600D01*
G01X777300D02*
Y947600D01*
G01Y951600D02*
X773100D01*
G01X173200Y962600D02*
Y970600D01*
X175600D01*
X176400Y970200D01*
X177000Y969267D01*
X177200Y968200D01*
X177000Y967133D01*
X176500Y966333D01*
X175600Y965933D01*
X173200D01*
G01X181200Y970600D02*
Y962600D01*
X185200D01*
G01X193200D02*
X189200D01*
Y970600D01*
X193200D01*
G01X191600Y966733D02*
X189200D01*
G01X196700Y962600D02*
X199200Y970600D01*
X201700Y962600D01*
G01X200800Y965400D02*
X197600D01*
G01X205100Y963666D02*
X205900Y963000D01*
X206800Y962600D01*
X207600D01*
X208400Y963000D01*
X209000Y963666D01*
X209300Y964600D01*
X209100Y965533D01*
X208600Y966333D01*
X207700Y966867D01*
X206500Y967133D01*
X205800Y967667D01*
X205500Y968600D01*
X205700Y969533D01*
X206200Y970200D01*
X206900Y970600D01*
X207600D01*
X208300Y970333D01*
X208900Y969667D01*
G01X217200Y962600D02*
X213200D01*
Y970600D01*
X217200D01*
G01X215600Y966733D02*
X213200D01*
G01X229300Y962600D02*
Y970600D01*
X233100D01*
G01X231700Y966733D02*
X229300D01*
G01X239200Y962600D02*
X238400Y962733D01*
X237700Y963267D01*
X237100Y964067D01*
X236700Y965000D01*
X236500Y966067D01*
Y967133D01*
X236700Y968200D01*
X237100Y969133D01*
X237700Y969933D01*
X238400Y970467D01*
X239200Y970600D01*
X240000Y970467D01*
X240700Y969933D01*
X241300Y969133D01*
X241700Y968200D01*
X241900Y967133D01*
Y966067D01*
X241700Y965000D01*
X241300Y964067D01*
X240700Y963267D01*
X240000Y962733D01*
X239200Y962600D01*
G01X245200Y970600D02*
Y962600D01*
X249200D01*
G01X253200Y970600D02*
Y962600D01*
X257200D01*
G01X263200D02*
X262400Y962733D01*
X261700Y963267D01*
X261100Y964067D01*
X260700Y965000D01*
X260500Y966067D01*
Y967133D01*
X260700Y968200D01*
X261100Y969133D01*
X261700Y969933D01*
X262400Y970467D01*
X263200Y970600D01*
X264000Y970467D01*
X264700Y969933D01*
X265300Y969133D01*
X265700Y968200D01*
X265900Y967133D01*
Y966067D01*
X265700Y965000D01*
X265300Y964067D01*
X264700Y963267D01*
X264000Y962733D01*
X263200Y962600D01*
G01X268200Y970600D02*
X269600Y962600D01*
X271200Y970600D01*
X272800Y962600D01*
X274200Y970600D01*
G01X287200D02*
Y962600D01*
G01X284900Y970600D02*
X289500D01*
G01X293100Y962600D02*
Y970600D01*
G01X297300D02*
Y962600D01*
G01Y966600D02*
X293100D01*
G01X305200Y962600D02*
X301200D01*
Y970600D01*
X305200D01*
G01X303600Y966733D02*
X301200D01*
G01X317100Y963666D02*
X317900Y963000D01*
X318800Y962600D01*
X319600D01*
X320400Y963000D01*
X321000Y963666D01*
X321300Y964600D01*
X321100Y965533D01*
X320600Y966333D01*
X319700Y966867D01*
X318500Y967133D01*
X317800Y967667D01*
X317500Y968600D01*
X317700Y969533D01*
X318200Y970200D01*
X318900Y970600D01*
X319600D01*
X320300Y970333D01*
X320900Y969667D01*
G01X325200Y970600D02*
Y962600D01*
X329200D01*
G01X334000Y970600D02*
X336400D01*
G01X335200D02*
Y962600D01*
G01X334000D02*
X336400D01*
G01X341000D02*
Y970600D01*
X343000D01*
X343800Y970200D01*
X344400Y969667D01*
X344900Y968867D01*
X345300Y967933D01*
X345400Y966600D01*
X345300Y965267D01*
X344900Y964333D01*
X344400Y963533D01*
X343800Y963000D01*
X343000Y962600D01*
X341000D01*
G01X353200D02*
X349200D01*
Y970600D01*
X353200D01*
G01X351600Y966733D02*
X349200D01*
G01X357100Y963666D02*
X357900Y963000D01*
X358800Y962600D01*
X359600D01*
X360400Y963000D01*
X361000Y963666D01*
X361300Y964600D01*
X361100Y965533D01*
X360600Y966333D01*
X359700Y966867D01*
X358500Y967133D01*
X357800Y967667D01*
X357500Y968600D01*
X357700Y969533D01*
X358200Y970200D01*
X358900Y970600D01*
X359600D01*
X360300Y970333D01*
X360900Y969667D01*
G01X375200Y970600D02*
Y962600D01*
G01X372900Y970600D02*
X377500D01*
G01X383200Y962600D02*
X382400Y962733D01*
X381700Y963267D01*
X381100Y964067D01*
X380700Y965000D01*
X380500Y966067D01*
Y967133D01*
X380700Y968200D01*
X381100Y969133D01*
X381700Y969933D01*
X382400Y970467D01*
X383200Y970600D01*
X384000Y970467D01*
X384700Y969933D01*
X385300Y969133D01*
X385700Y968200D01*
X385900Y967133D01*
Y966067D01*
X385700Y965000D01*
X385300Y964067D01*
X384700Y963267D01*
X384000Y962733D01*
X383200Y962600D01*
G01X399800Y966600D02*
X401800D01*
Y964200D01*
X401200Y963400D01*
X400500Y962867D01*
X399500Y962600D01*
X398500Y962867D01*
X397800Y963400D01*
X397200Y964200D01*
X396800Y965133D01*
X396600Y966200D01*
Y967133D01*
X396800Y967933D01*
X397200Y968867D01*
X397800Y969667D01*
X398400Y970200D01*
X399200Y970600D01*
X399900D01*
X400700Y970333D01*
X401300Y969800D01*
G01X409200Y962600D02*
X405200D01*
Y970600D01*
X409200D01*
G01X407600Y966733D02*
X405200D01*
G01X412900Y962600D02*
Y970600D01*
X417500Y962600D01*
Y970600D01*
G01X425200Y962600D02*
X421200D01*
Y970600D01*
X425200D01*
G01X423600Y966733D02*
X421200D01*
G01X429200Y962600D02*
Y970600D01*
X431700D01*
X432500Y970200D01*
X433000Y969667D01*
X433200Y968600D01*
X433000Y967533D01*
X432400Y966867D01*
X431700Y966467D01*
X429200D01*
G01X431700D02*
X433200Y962600D01*
G01X436700D02*
X439200Y970600D01*
X441700Y962600D01*
G01X440800Y965400D02*
X437600D01*
G01X447200Y970600D02*
Y962600D01*
G01X444900Y970600D02*
X449500D01*
G01X457200Y962600D02*
X453200D01*
Y970600D01*
X457200D01*
G01X455600Y966733D02*
X453200D01*
G01X471200Y970600D02*
Y962600D01*
G01X468900Y970600D02*
X473500D01*
G01X477100Y962600D02*
Y970600D01*
G01X481300D02*
Y962600D01*
G01Y966600D02*
X477100D01*
G01X489200Y962600D02*
X485200D01*
Y970600D01*
X489200D01*
G01X487600Y966733D02*
X485200D01*
G01X501200Y962600D02*
Y970600D01*
X503600D01*
X504400Y970200D01*
X505000Y969267D01*
X505200Y968200D01*
X505000Y967133D01*
X504500Y966333D01*
X503600Y965933D01*
X501200D01*
G01X508700Y962600D02*
X511200Y970600D01*
X513700Y962600D01*
G01X512800Y965400D02*
X509600D01*
G01X517000Y962600D02*
Y970600D01*
X519000D01*
X519800Y970200D01*
X520400Y969667D01*
X520900Y968867D01*
X521300Y967933D01*
X521400Y966600D01*
X521300Y965267D01*
X520900Y964333D01*
X520400Y963533D01*
X519800Y963000D01*
X519000Y962600D01*
X517000D01*
G01X525100Y963666D02*
X525900Y963000D01*
X526800Y962600D01*
X527600D01*
X528400Y963000D01*
X529000Y963666D01*
X529300Y964600D01*
X529100Y965533D01*
X528600Y966333D01*
X527700Y966867D01*
X526500Y967133D01*
X525800Y967667D01*
X525500Y968600D01*
X525700Y969533D01*
X526200Y970200D01*
X526900Y970600D01*
X527600D01*
X528300Y970333D01*
X528900Y969667D01*
G01X540700Y962600D02*
X543200Y970600D01*
X545700Y962600D01*
G01X544800Y965400D02*
X541600D01*
G01X548900Y962600D02*
Y970600D01*
X553500Y962600D01*
Y970600D01*
G01X557000Y962600D02*
Y970600D01*
X559000D01*
X559800Y970200D01*
X560400Y969667D01*
X560900Y968867D01*
X561300Y967933D01*
X561400Y966600D01*
X561300Y965267D01*
X560900Y964333D01*
X560400Y963533D01*
X559800Y963000D01*
X559000Y962600D01*
X557000D01*
G01X572600D02*
Y970600D01*
X575200Y963933D01*
X577800Y970600D01*
Y962600D01*
G01X580700D02*
X583200Y970600D01*
X585700Y962600D01*
G01X584800Y965400D02*
X581600D01*
G01X589100Y963666D02*
X589900Y963000D01*
X590800Y962600D01*
X591600D01*
X592400Y963000D01*
X593000Y963666D01*
X593300Y964600D01*
X593100Y965533D01*
X592600Y966333D01*
X591700Y966867D01*
X590500Y967133D01*
X589800Y967667D01*
X589500Y968600D01*
X589700Y969533D01*
X590200Y970200D01*
X590900Y970600D01*
X591600D01*
X592300Y970333D01*
X592900Y969667D01*
G01X597000Y962600D02*
Y970600D01*
G01X600800D02*
X597000Y965666D01*
G01X601400Y962600D02*
X598700Y967933D01*
G01X612700Y962600D02*
X615200Y970600D01*
X617700Y962600D01*
G01X616800Y965400D02*
X613600D01*
G01X620900Y962600D02*
Y970600D01*
X625500Y962600D01*
Y970600D01*
G01X629000Y962600D02*
Y970600D01*
X631000D01*
X631800Y970200D01*
X632400Y969667D01*
X632900Y968867D01*
X633300Y967933D01*
X633400Y966600D01*
X633300Y965267D01*
X632900Y964333D01*
X632400Y963533D01*
X631800Y963000D01*
X631000Y962600D01*
X629000D01*
G01X644700D02*
X647200Y970600D01*
X649700Y962600D01*
G01X648800Y965400D02*
X645600D01*
G01X653000Y962600D02*
Y970600D01*
X655000D01*
X655800Y970200D01*
X656400Y969667D01*
X656900Y968867D01*
X657300Y967933D01*
X657400Y966600D01*
X657300Y965267D01*
X656900Y964333D01*
X656400Y963533D01*
X655800Y963000D01*
X655000Y962600D01*
X653000D01*
G01X661000D02*
Y970600D01*
X663000D01*
X663800Y970200D01*
X664400Y969667D01*
X664900Y968867D01*
X665300Y967933D01*
X665400Y966600D01*
X665300Y965267D01*
X664900Y964333D01*
X664400Y963533D01*
X663800Y963000D01*
X663000Y962600D01*
X661000D01*
G01X679200Y970600D02*
Y962600D01*
G01X676900Y970600D02*
X681500D01*
G01X685100Y962600D02*
Y970600D01*
G01X689300D02*
Y962600D01*
G01Y966600D02*
X685100D01*
G01X697200Y962600D02*
X693200D01*
Y970600D01*
X697200D01*
G01X695600Y966733D02*
X693200D01*
G01X711200Y970600D02*
Y962600D01*
G01X708900Y970600D02*
X713500D01*
G01X721200Y962600D02*
X717200D01*
Y970600D01*
X721200D01*
G01X719600Y966733D02*
X717200D01*
G01X725100Y963666D02*
X725900Y963000D01*
X726800Y962600D01*
X727600D01*
X728400Y963000D01*
X729000Y963666D01*
X729300Y964600D01*
X729100Y965533D01*
X728600Y966333D01*
X727700Y966867D01*
X726500Y967133D01*
X725800Y967667D01*
X725500Y968600D01*
X725700Y969533D01*
X726200Y970200D01*
X726900Y970600D01*
X727600D01*
X728300Y970333D01*
X728900Y969667D01*
G01X735200Y970600D02*
Y962600D01*
G01X732900Y970600D02*
X737500D01*
G01X749200Y962600D02*
Y970600D01*
X751600D01*
X752400Y970200D01*
X753000Y969267D01*
X753200Y968200D01*
X753000Y967133D01*
X752500Y966333D01*
X751600Y965933D01*
X749200D01*
G01X756700Y962600D02*
X759200Y970600D01*
X761700Y962600D01*
G01X760800Y965400D02*
X757600D01*
G01X765000Y962600D02*
Y970600D01*
X767000D01*
X767800Y970200D01*
X768400Y969667D01*
X768900Y968867D01*
X769300Y967933D01*
X769400Y966600D01*
X769300Y965267D01*
X768900Y964333D01*
X768400Y963533D01*
X767800Y963000D01*
X767000Y962600D01*
X765000D01*
G01X773100Y963666D02*
X773900Y963000D01*
X774800Y962600D01*
X775600D01*
X776400Y963000D01*
X777000Y963666D01*
X777300Y964600D01*
X777100Y965533D01*
X776600Y966333D01*
X775700Y966867D01*
X774500Y967133D01*
X773800Y967667D01*
X773500Y968600D01*
X773700Y969533D01*
X774200Y970200D01*
X774900Y970600D01*
X775600D01*
X776300Y970333D01*
X776900Y969667D01*
G01X158000Y978800D02*
X158600Y978133D01*
X159300Y977733D01*
X160200Y977600D01*
X161100Y977867D01*
X161800Y978400D01*
X162300Y979333D01*
X162400Y980400D01*
X162200Y981467D01*
X161700Y982133D01*
X161000Y982667D01*
X160300Y982800D01*
X159600Y982667D01*
X158700Y982133D01*
X159000Y985600D01*
X161700D01*
G01X168200Y977333D02*
X168000Y977467D01*
Y977733D01*
X168200Y977867D01*
X168400Y977733D01*
Y977467D01*
X168200Y977333D01*
G01X174200Y977600D02*
Y985600D01*
X176600D01*
X177400Y985200D01*
X178000Y984267D01*
X178200Y983200D01*
X178000Y982133D01*
X177500Y981333D01*
X176600Y980933D01*
X174200D01*
G01X186200Y977600D02*
X182200D01*
Y985600D01*
X186200D01*
G01X184600Y981733D02*
X182200D01*
G01X194200Y977600D02*
X190200D01*
Y985600D01*
X194200D01*
G01X192600Y981733D02*
X190200D01*
G01X198200Y985600D02*
Y977600D01*
X202200D01*
G01X207000Y985600D02*
X209400D01*
G01X208200D02*
Y977600D01*
G01X207000D02*
X209400D01*
G01X213900D02*
Y985600D01*
X218500Y977600D01*
Y985600D01*
G01X224800Y981600D02*
X226800D01*
Y979200D01*
X226200Y978400D01*
X225500Y977867D01*
X224500Y977600D01*
X223500Y977867D01*
X222800Y978400D01*
X222200Y979200D01*
X221800Y980133D01*
X221600Y981200D01*
Y982133D01*
X221800Y982933D01*
X222200Y983867D01*
X222800Y984667D01*
X223400Y985200D01*
X224200Y985600D01*
X224900D01*
X225700Y985333D01*
X226300Y984800D01*
G01X238100Y978666D02*
X238900Y978000D01*
X239800Y977600D01*
X240600D01*
X241400Y978000D01*
X242000Y978666D01*
X242300Y979600D01*
X242100Y980533D01*
X241600Y981333D01*
X240700Y981867D01*
X239500Y982133D01*
X238800Y982667D01*
X238500Y983600D01*
X238700Y984533D01*
X239200Y985200D01*
X239900Y985600D01*
X240600D01*
X241300Y985333D01*
X241900Y984667D01*
G01X248200Y985600D02*
Y977600D01*
G01X245900Y985600D02*
X250500D01*
G01X254200Y977600D02*
Y985600D01*
X256700D01*
X257500Y985200D01*
X258000Y984667D01*
X258200Y983600D01*
X258000Y982533D01*
X257400Y981867D01*
X256700Y981467D01*
X254200D01*
G01X256700D02*
X258200Y977600D01*
G01X266200D02*
X262200D01*
Y985600D01*
X266200D01*
G01X264600Y981733D02*
X262200D01*
G01X269900Y977600D02*
Y985600D01*
X274500Y977600D01*
Y985600D01*
G01X280800Y981600D02*
X282800D01*
Y979200D01*
X282200Y978400D01*
X281500Y977867D01*
X280500Y977600D01*
X279500Y977867D01*
X278800Y978400D01*
X278200Y979200D01*
X277800Y980133D01*
X277600Y981200D01*
Y982133D01*
X277800Y982933D01*
X278200Y983867D01*
X278800Y984667D01*
X279400Y985200D01*
X280200Y985600D01*
X280900D01*
X281700Y985333D01*
X282300Y984800D01*
G01X288200Y985600D02*
Y977600D01*
G01X285900Y985600D02*
X290500D01*
G01X294100Y977600D02*
Y985600D01*
G01X298300D02*
Y977600D01*
G01Y981600D02*
X294100D01*
G01X309700Y977600D02*
X312200Y985600D01*
X314700Y977600D01*
G01X313800Y980400D02*
X310600D01*
G01X317900Y977600D02*
Y985600D01*
X322500Y977600D01*
Y985600D01*
G01X326000Y977600D02*
Y985600D01*
X328000D01*
X328800Y985200D01*
X329400Y984667D01*
X329900Y983867D01*
X330300Y982933D01*
X330400Y981600D01*
X330300Y980267D01*
X329900Y979333D01*
X329400Y978533D01*
X328800Y978000D01*
X328000Y977600D01*
X326000D01*
G01X345000Y981867D02*
X345400Y982267D01*
X345700Y982933D01*
X345900Y983867D01*
X345700Y984667D01*
X345300Y985200D01*
X344600Y985600D01*
X341900D01*
Y977600D01*
X345200D01*
X345900Y978133D01*
X346300Y978933D01*
X346500Y979867D01*
X346300Y980800D01*
X345700Y981600D01*
X345000Y981867D01*
X341900D01*
G01X352800Y981600D02*
X354800D01*
Y979200D01*
X354200Y978400D01*
X353500Y977867D01*
X352500Y977600D01*
X351500Y977867D01*
X350800Y978400D01*
X350200Y979200D01*
X349800Y980133D01*
X349600Y981200D01*
Y982133D01*
X349800Y982933D01*
X350200Y983867D01*
X350800Y984667D01*
X351400Y985200D01*
X352200Y985600D01*
X352900D01*
X353700Y985333D01*
X354300Y984800D01*
G01X357700Y977600D02*
X360200Y985600D01*
X362700Y977600D01*
G01X361800Y980400D02*
X358600D01*
G01X374200Y977600D02*
Y985600D01*
X376600D01*
X377400Y985200D01*
X378000Y984267D01*
X378200Y983200D01*
X378000Y982133D01*
X377500Y981333D01*
X376600Y980933D01*
X374200D01*
G01X381700Y977600D02*
X384200Y985600D01*
X386700Y977600D01*
G01X385800Y980400D02*
X382600D01*
G01X390000Y977600D02*
Y985600D01*
X392000D01*
X392800Y985200D01*
X393400Y984667D01*
X393900Y983867D01*
X394300Y982933D01*
X394400Y981600D01*
X394300Y980267D01*
X393900Y979333D01*
X393400Y978533D01*
X392800Y978000D01*
X392000Y977600D01*
X390000D01*
G01X398100Y978666D02*
X398900Y978000D01*
X399800Y977600D01*
X400600D01*
X401400Y978000D01*
X402000Y978666D01*
X402300Y979600D01*
X402100Y980533D01*
X401600Y981333D01*
X400700Y981867D01*
X399500Y982133D01*
X398800Y982667D01*
X398500Y983600D01*
X398700Y984533D01*
X399200Y985200D01*
X399900Y985600D01*
X400600D01*
X401300Y985333D01*
X401900Y984667D01*
G01X413700Y977600D02*
X416200Y985600D01*
X418700Y977600D01*
G01X417800Y980400D02*
X414600D01*
G01X422000Y977600D02*
Y985600D01*
X424000D01*
X424800Y985200D01*
X425400Y984667D01*
X425900Y983867D01*
X426300Y982933D01*
X426400Y981600D01*
X426300Y980267D01*
X425900Y979333D01*
X425400Y978533D01*
X424800Y978000D01*
X424000Y977600D01*
X422000D01*
G01X430100D02*
Y985600D01*
G01X434300D02*
Y977600D01*
G01Y981600D02*
X430100D01*
G01X442200Y977600D02*
X438200D01*
Y985600D01*
X442200D01*
G01X440600Y981733D02*
X438200D01*
G01X446100Y978666D02*
X446900Y978000D01*
X447800Y977600D01*
X448600D01*
X449400Y978000D01*
X450000Y978666D01*
X450300Y979600D01*
X450100Y980533D01*
X449600Y981333D01*
X448700Y981867D01*
X447500Y982133D01*
X446800Y982667D01*
X446500Y983600D01*
X446700Y984533D01*
X447200Y985200D01*
X447900Y985600D01*
X448600D01*
X449300Y985333D01*
X449900Y984667D01*
G01X455000Y985600D02*
X457400D01*
G01X456200D02*
Y977600D01*
G01X455000D02*
X457400D01*
G01X464200D02*
X463400Y977733D01*
X462700Y978267D01*
X462100Y979067D01*
X461700Y980000D01*
X461500Y981067D01*
Y982133D01*
X461700Y983200D01*
X462100Y984133D01*
X462700Y984933D01*
X463400Y985467D01*
X464200Y985600D01*
X465000Y985467D01*
X465700Y984933D01*
X466300Y984133D01*
X466700Y983200D01*
X466900Y982133D01*
Y981067D01*
X466700Y980000D01*
X466300Y979067D01*
X465700Y978267D01*
X465000Y977733D01*
X464200Y977600D01*
G01X469900D02*
Y985600D01*
X474500Y977600D01*
Y985600D01*
G01X488200D02*
Y977600D01*
G01X485900Y985600D02*
X490500D01*
G01X498200Y977600D02*
X494200D01*
Y985600D01*
X498200D01*
G01X496600Y981733D02*
X494200D01*
G01X502100Y978666D02*
X502900Y978000D01*
X503800Y977600D01*
X504600D01*
X505400Y978000D01*
X506000Y978666D01*
X506300Y979600D01*
X506100Y980533D01*
X505600Y981333D01*
X504700Y981867D01*
X503500Y982133D01*
X502800Y982667D01*
X502500Y983600D01*
X502700Y984533D01*
X503200Y985200D01*
X503900Y985600D01*
X504600D01*
X505300Y985333D01*
X505900Y984667D01*
G01X512200Y985600D02*
Y977600D01*
G01X509900Y985600D02*
X514500D01*
G01X526200Y977600D02*
Y985600D01*
X528600D01*
X529400Y985200D01*
X530000Y984267D01*
X530200Y983200D01*
X530000Y982133D01*
X529500Y981333D01*
X528600Y980933D01*
X526200D01*
G01X533700Y977600D02*
X536200Y985600D01*
X538700Y977600D01*
G01X537800Y980400D02*
X534600D01*
G01X544200Y985600D02*
Y977600D01*
G01X541900Y985600D02*
X546500D01*
G01X552200D02*
Y977600D01*
G01X549900Y985600D02*
X554500D01*
G01X562200Y977600D02*
X558200D01*
Y985600D01*
X562200D01*
G01X560600Y981733D02*
X558200D01*
G01X566200Y977600D02*
Y985600D01*
X568700D01*
X569500Y985200D01*
X570000Y984667D01*
X570200Y983600D01*
X570000Y982533D01*
X569400Y981867D01*
X568700Y981467D01*
X566200D01*
G01X568700D02*
X570200Y977600D01*
G01X573900D02*
Y985600D01*
X578500Y977600D01*
Y985600D01*
G01X582100Y978666D02*
X582900Y978000D01*
X583800Y977600D01*
X584600D01*
X585400Y978000D01*
X586000Y978666D01*
X586300Y979600D01*
X586100Y980533D01*
X585600Y981333D01*
X584700Y981867D01*
X583500Y982133D01*
X582800Y982667D01*
X582500Y983600D01*
X582700Y984533D01*
X583200Y985200D01*
X583900Y985600D01*
X584600D01*
X585300Y985333D01*
X585900Y984667D01*
G01X592200Y977333D02*
X592000Y977467D01*
Y977733D01*
X592200Y977867D01*
X592400Y977733D01*
Y977467D01*
X592200Y977333D01*
G01X161400Y1067600D02*
Y1075600D01*
X157700Y1069867D01*
X162700D01*
G01X168200Y1067333D02*
X168000Y1067467D01*
Y1067733D01*
X168200Y1067867D01*
X168400Y1067733D01*
Y1067467D01*
X168200Y1067333D01*
G01X178400Y1074933D02*
X177800Y1075333D01*
X177100Y1075600D01*
X176300D01*
X175400Y1075200D01*
X174700Y1074533D01*
X174200Y1073733D01*
X173800Y1072400D01*
X173700Y1071200D01*
X173900Y1070000D01*
X174200Y1069200D01*
X174800Y1068400D01*
X175500Y1067867D01*
X176200Y1067600D01*
X176900D01*
X177600Y1067867D01*
X178200Y1068267D01*
X178700Y1068800D01*
G01X184200Y1067600D02*
X183400Y1067733D01*
X182700Y1068267D01*
X182100Y1069067D01*
X181700Y1070000D01*
X181500Y1071067D01*
Y1072133D01*
X181700Y1073200D01*
X182100Y1074133D01*
X182700Y1074933D01*
X183400Y1075467D01*
X184200Y1075600D01*
X185000Y1075467D01*
X185700Y1074933D01*
X186300Y1074133D01*
X186700Y1073200D01*
X186900Y1072133D01*
Y1071067D01*
X186700Y1070000D01*
X186300Y1069067D01*
X185700Y1068267D01*
X185000Y1067733D01*
X184200Y1067600D01*
G01X189900D02*
Y1075600D01*
X194500Y1067600D01*
Y1075600D01*
G01X200200D02*
Y1067600D01*
G01X197900Y1075600D02*
X202500D01*
G01X206200Y1067600D02*
Y1075600D01*
X208700D01*
X209500Y1075200D01*
X210000Y1074667D01*
X210200Y1073600D01*
X210000Y1072533D01*
X209400Y1071867D01*
X208700Y1071467D01*
X206200D01*
G01X208700D02*
X210200Y1067600D01*
G01X216200D02*
X215400Y1067733D01*
X214700Y1068267D01*
X214100Y1069067D01*
X213700Y1070000D01*
X213500Y1071067D01*
Y1072133D01*
X213700Y1073200D01*
X214100Y1074133D01*
X214700Y1074933D01*
X215400Y1075467D01*
X216200Y1075600D01*
X217000Y1075467D01*
X217700Y1074933D01*
X218300Y1074133D01*
X218700Y1073200D01*
X218900Y1072133D01*
Y1071067D01*
X218700Y1070000D01*
X218300Y1069067D01*
X217700Y1068267D01*
X217000Y1067733D01*
X216200Y1067600D01*
G01X222200Y1075600D02*
Y1067600D01*
X226200D01*
G01X230200Y1075600D02*
Y1067600D01*
X234200D01*
G01X242200D02*
X238200D01*
Y1075600D01*
X242200D01*
G01X240600Y1071733D02*
X238200D01*
G01X246000Y1067600D02*
Y1075600D01*
X248000D01*
X248800Y1075200D01*
X249400Y1074667D01*
X249900Y1073867D01*
X250300Y1072933D01*
X250400Y1071600D01*
X250300Y1070267D01*
X249900Y1069333D01*
X249400Y1068533D01*
X248800Y1068000D01*
X248000Y1067600D01*
X246000D01*
G01X263000Y1075600D02*
X265400D01*
G01X264200D02*
Y1067600D01*
G01X263000D02*
X265400D01*
G01X269600D02*
Y1075600D01*
X272200Y1068933D01*
X274800Y1075600D01*
Y1067600D01*
G01X278200D02*
Y1075600D01*
X280600D01*
X281400Y1075200D01*
X282000Y1074267D01*
X282200Y1073200D01*
X282000Y1072133D01*
X281500Y1071333D01*
X280600Y1070933D01*
X278200D01*
G01X290200Y1067600D02*
X286200D01*
Y1075600D01*
X290200D01*
G01X288600Y1071733D02*
X286200D01*
G01X294000Y1067600D02*
Y1075600D01*
X296000D01*
X296800Y1075200D01*
X297400Y1074667D01*
X297900Y1073867D01*
X298300Y1072933D01*
X298400Y1071600D01*
X298300Y1070267D01*
X297900Y1069333D01*
X297400Y1068533D01*
X296800Y1068000D01*
X296000Y1067600D01*
X294000D01*
G01X301700D02*
X304200Y1075600D01*
X306700Y1067600D01*
G01X305800Y1070400D02*
X302600D01*
G01X309900Y1067600D02*
Y1075600D01*
X314500Y1067600D01*
Y1075600D01*
G01X322400Y1074933D02*
X321800Y1075333D01*
X321100Y1075600D01*
X320300D01*
X319400Y1075200D01*
X318700Y1074533D01*
X318200Y1073733D01*
X317800Y1072400D01*
X317700Y1071200D01*
X317900Y1070000D01*
X318200Y1069200D01*
X318800Y1068400D01*
X319500Y1067867D01*
X320200Y1067600D01*
X320900D01*
X321600Y1067867D01*
X322200Y1068267D01*
X322700Y1068800D01*
G01X330200Y1067600D02*
X326200D01*
Y1075600D01*
X330200D01*
G01X328600Y1071733D02*
X326200D01*
G01X345000Y1071867D02*
X345400Y1072267D01*
X345700Y1072933D01*
X345900Y1073867D01*
X345700Y1074667D01*
X345300Y1075200D01*
X344600Y1075600D01*
X341900D01*
Y1067600D01*
X345200D01*
X345900Y1068133D01*
X346300Y1068933D01*
X346500Y1069867D01*
X346300Y1070800D01*
X345700Y1071600D01*
X345000Y1071867D01*
X341900D01*
G01X352200Y1067600D02*
X351400Y1067733D01*
X350700Y1068267D01*
X350100Y1069067D01*
X349700Y1070000D01*
X349500Y1071067D01*
Y1072133D01*
X349700Y1073200D01*
X350100Y1074133D01*
X350700Y1074933D01*
X351400Y1075467D01*
X352200Y1075600D01*
X353000Y1075467D01*
X353700Y1074933D01*
X354300Y1074133D01*
X354700Y1073200D01*
X354900Y1072133D01*
Y1071067D01*
X354700Y1070000D01*
X354300Y1069067D01*
X353700Y1068267D01*
X353000Y1067733D01*
X352200Y1067600D01*
G01X357700D02*
X360200Y1075600D01*
X362700Y1067600D01*
G01X361800Y1070400D02*
X358600D01*
G01X366200Y1067600D02*
Y1075600D01*
X368700D01*
X369500Y1075200D01*
X370000Y1074667D01*
X370200Y1073600D01*
X370000Y1072533D01*
X369400Y1071867D01*
X368700Y1071467D01*
X366200D01*
G01X368700D02*
X370200Y1067600D01*
G01X374000D02*
Y1075600D01*
X376000D01*
X376800Y1075200D01*
X377400Y1074667D01*
X377900Y1073867D01*
X378300Y1072933D01*
X378400Y1071600D01*
X378300Y1070267D01*
X377900Y1069333D01*
X377400Y1068533D01*
X376800Y1068000D01*
X376000Y1067600D01*
X374000D01*
G01X384200Y1067333D02*
X384000Y1067467D01*
Y1067733D01*
X384200Y1067867D01*
X384400Y1067733D01*
Y1067467D01*
X384200Y1067333D01*
G01X398100Y1068666D02*
X398900Y1068000D01*
X399800Y1067600D01*
X400600D01*
X401400Y1068000D01*
X402000Y1068666D01*
X402300Y1069600D01*
X402100Y1070533D01*
X401600Y1071333D01*
X400700Y1071867D01*
X399500Y1072133D01*
X398800Y1072667D01*
X398500Y1073600D01*
X398700Y1074533D01*
X399200Y1075200D01*
X399900Y1075600D01*
X400600D01*
X401300Y1075333D01*
X401900Y1074667D01*
G01X410200Y1067600D02*
X406200D01*
Y1075600D01*
X410200D01*
G01X408600Y1071733D02*
X406200D01*
G01X418200Y1067600D02*
X414200D01*
Y1075600D01*
X418200D01*
G01X416600Y1071733D02*
X414200D01*
G01X430200Y1075600D02*
Y1067600D01*
X434200D01*
G01X437700D02*
X440200Y1075600D01*
X442700Y1067600D01*
G01X441800Y1070400D02*
X438600D01*
G01X448200Y1067600D02*
Y1071200D01*
X446200Y1075600D01*
G01X450200D02*
X448200Y1071200D01*
G01X458200Y1067600D02*
X454200D01*
Y1075600D01*
X458200D01*
G01X456600Y1071733D02*
X454200D01*
G01X462200Y1067600D02*
Y1075600D01*
X464700D01*
X465500Y1075200D01*
X466000Y1074667D01*
X466200Y1073600D01*
X466000Y1072533D01*
X465400Y1071867D01*
X464700Y1071467D01*
X462200D01*
G01X464700D02*
X466200Y1067600D01*
G01X478100Y1068666D02*
X478900Y1068000D01*
X479800Y1067600D01*
X480600D01*
X481400Y1068000D01*
X482000Y1068666D01*
X482300Y1069600D01*
X482100Y1070533D01*
X481600Y1071333D01*
X480700Y1071867D01*
X479500Y1072133D01*
X478800Y1072667D01*
X478500Y1073600D01*
X478700Y1074533D01*
X479200Y1075200D01*
X479900Y1075600D01*
X480600D01*
X481300Y1075333D01*
X481900Y1074667D01*
G01X488200Y1075600D02*
Y1067600D01*
G01X485900Y1075600D02*
X490500D01*
G01X493700Y1067600D02*
X496200Y1075600D01*
X498700Y1067600D01*
G01X497800Y1070400D02*
X494600D01*
G01X506400Y1074933D02*
X505800Y1075333D01*
X505100Y1075600D01*
X504300D01*
X503400Y1075200D01*
X502700Y1074533D01*
X502200Y1073733D01*
X501800Y1072400D01*
X501700Y1071200D01*
X501900Y1070000D01*
X502200Y1069200D01*
X502800Y1068400D01*
X503500Y1067867D01*
X504200Y1067600D01*
X504900D01*
X505600Y1067867D01*
X506200Y1068267D01*
X506700Y1068800D01*
G01X510000Y1067600D02*
Y1075600D01*
G01X513800D02*
X510000Y1070666D01*
G01X514400Y1067600D02*
X511700Y1072933D01*
G01X518000Y1075600D02*
Y1069867D01*
X518400Y1068666D01*
X519200Y1067867D01*
X520200Y1067600D01*
X521200Y1067867D01*
X522000Y1068666D01*
X522400Y1069867D01*
Y1075600D01*
G01X526200Y1067600D02*
Y1075600D01*
X528600D01*
X529400Y1075200D01*
X530000Y1074267D01*
X530200Y1073200D01*
X530000Y1072133D01*
X529500Y1071333D01*
X528600Y1070933D01*
X526200D01*
G01X541700Y1067600D02*
X544200Y1075600D01*
X546700Y1067600D01*
G01X545800Y1070400D02*
X542600D01*
G01X549900Y1067600D02*
Y1075600D01*
X554500Y1067600D01*
Y1075600D01*
G01X558000Y1067600D02*
Y1075600D01*
X560000D01*
X560800Y1075200D01*
X561400Y1074667D01*
X561900Y1073867D01*
X562300Y1072933D01*
X562400Y1071600D01*
X562300Y1070267D01*
X561900Y1069333D01*
X561400Y1068533D01*
X560800Y1068000D01*
X560000Y1067600D01*
X558000D01*
G01X575000Y1075600D02*
X577400D01*
G01X576200D02*
Y1067600D01*
G01X575000D02*
X577400D01*
G01X581600D02*
Y1075600D01*
X584200Y1068933D01*
X586800Y1075600D01*
Y1067600D01*
G01X590200D02*
Y1075600D01*
X592600D01*
X593400Y1075200D01*
X594000Y1074267D01*
X594200Y1073200D01*
X594000Y1072133D01*
X593500Y1071333D01*
X592600Y1070933D01*
X590200D01*
G01X602200Y1067600D02*
X598200D01*
Y1075600D01*
X602200D01*
G01X600600Y1071733D02*
X598200D01*
G01X606000Y1067600D02*
Y1075600D01*
X608000D01*
X608800Y1075200D01*
X609400Y1074667D01*
X609900Y1073867D01*
X610300Y1072933D01*
X610400Y1071600D01*
X610300Y1070267D01*
X609900Y1069333D01*
X609400Y1068533D01*
X608800Y1068000D01*
X608000Y1067600D01*
X606000D01*
G01X613700D02*
X616200Y1075600D01*
X618700Y1067600D01*
G01X617800Y1070400D02*
X614600D01*
G01X621900Y1067600D02*
Y1075600D01*
X626500Y1067600D01*
Y1075600D01*
G01X634400Y1074933D02*
X633800Y1075333D01*
X633100Y1075600D01*
X632300D01*
X631400Y1075200D01*
X630700Y1074533D01*
X630200Y1073733D01*
X629800Y1072400D01*
X629700Y1071200D01*
X629900Y1070000D01*
X630200Y1069200D01*
X630800Y1068400D01*
X631500Y1067867D01*
X632200Y1067600D01*
X632900D01*
X633600Y1067867D01*
X634200Y1068267D01*
X634700Y1068800D01*
G01X642200Y1067600D02*
X638200D01*
Y1075600D01*
X642200D01*
G01X640600Y1071733D02*
X638200D01*
G01X160300Y1209267D02*
X160900Y1210067D01*
X161600Y1210467D01*
X162400Y1210600D01*
X163400Y1210333D01*
X164100Y1209667D01*
X164300Y1208867D01*
X164200Y1208066D01*
X163800Y1207400D01*
X161800Y1206067D01*
X160900Y1205133D01*
X160300Y1203800D01*
X160100Y1202600D01*
X164300D01*
G01X170200Y1202333D02*
X170000Y1202467D01*
Y1202733D01*
X170200Y1202867D01*
X170400Y1202733D01*
Y1202467D01*
X170200Y1202333D01*
G01X176300Y1202600D02*
Y1210600D01*
X180100D01*
G01X178700Y1206733D02*
X176300D01*
G01X183700Y1202600D02*
X186200Y1210600D01*
X188700Y1202600D01*
G01X187800Y1205400D02*
X184600D01*
G01X195000Y1206867D02*
X195400Y1207267D01*
X195700Y1207933D01*
X195900Y1208867D01*
X195700Y1209667D01*
X195300Y1210200D01*
X194600Y1210600D01*
X191900D01*
Y1202600D01*
X195200D01*
X195900Y1203133D01*
X196300Y1203933D01*
X196500Y1204867D01*
X196300Y1205800D01*
X195700Y1206600D01*
X195000Y1206867D01*
X191900D01*
G01X200200Y1202600D02*
Y1210600D01*
X202700D01*
X203500Y1210200D01*
X204000Y1209667D01*
X204200Y1208600D01*
X204000Y1207533D01*
X203400Y1206867D01*
X202700Y1206467D01*
X200200D01*
G01X202700D02*
X204200Y1202600D01*
G01X209000Y1210600D02*
X211400D01*
G01X210200D02*
Y1202600D01*
G01X209000D02*
X211400D01*
G01X220400Y1209933D02*
X219800Y1210333D01*
X219100Y1210600D01*
X218300D01*
X217400Y1210200D01*
X216700Y1209533D01*
X216200Y1208733D01*
X215800Y1207400D01*
X215700Y1206200D01*
X215900Y1205000D01*
X216200Y1204200D01*
X216800Y1203400D01*
X217500Y1202867D01*
X218200Y1202600D01*
X218900D01*
X219600Y1202867D01*
X220200Y1203267D01*
X220700Y1203800D01*
G01X223700Y1202600D02*
X226200Y1210600D01*
X228700Y1202600D01*
G01X227800Y1205400D02*
X224600D01*
G01X234200Y1210600D02*
Y1202600D01*
G01X231900Y1210600D02*
X236500D01*
G01X244200Y1202600D02*
X240200D01*
Y1210600D01*
X244200D01*
G01X242600Y1206733D02*
X240200D01*
G01X256200Y1202600D02*
Y1210600D01*
X258600D01*
X259400Y1210200D01*
X260000Y1209267D01*
X260200Y1208200D01*
X260000Y1207133D01*
X259500Y1206333D01*
X258600Y1205933D01*
X256200D01*
G01X268200Y1202600D02*
X264200D01*
Y1210600D01*
X268200D01*
G01X266600Y1206733D02*
X264200D01*
G01X272200Y1202600D02*
Y1210600D01*
X274700D01*
X275500Y1210200D01*
X276000Y1209667D01*
X276200Y1208600D01*
X276000Y1207533D01*
X275400Y1206867D01*
X274700Y1206467D01*
X272200D01*
G01X274700D02*
X276200Y1202600D01*
G01X290200D02*
X289400Y1202733D01*
X288700Y1203267D01*
X288100Y1204067D01*
X287700Y1205000D01*
X287500Y1206067D01*
Y1207133D01*
X287700Y1208200D01*
X288100Y1209133D01*
X288700Y1209933D01*
X289400Y1210467D01*
X290200Y1210600D01*
X291000Y1210467D01*
X291700Y1209933D01*
X292300Y1209133D01*
X292700Y1208200D01*
X292900Y1207133D01*
Y1206067D01*
X292700Y1205000D01*
X292300Y1204067D01*
X291700Y1203267D01*
X291000Y1202733D01*
X290200Y1202600D01*
G01X291000Y1204733D02*
X292200Y1202600D01*
G01X296000Y1210600D02*
Y1204867D01*
X296400Y1203666D01*
X297200Y1202867D01*
X298200Y1202600D01*
X299200Y1202867D01*
X300000Y1203666D01*
X300400Y1204867D01*
Y1210600D01*
G01X303700Y1202600D02*
X306200Y1210600D01*
X308700Y1202600D01*
G01X307800Y1205400D02*
X304600D01*
G01X311900Y1202600D02*
Y1210600D01*
X316500Y1202600D01*
Y1210600D01*
G01X322200D02*
Y1202600D01*
G01X319900Y1210600D02*
X324500D01*
G01X327700Y1202600D02*
X330200Y1210600D01*
X332700Y1202600D01*
G01X331800Y1205400D02*
X328600D01*
G01X344200Y1202600D02*
Y1210600D01*
X346600D01*
X347400Y1210200D01*
X348000Y1209267D01*
X348200Y1208200D01*
X348000Y1207133D01*
X347500Y1206333D01*
X346600Y1205933D01*
X344200D01*
G01X356400Y1209933D02*
X355800Y1210333D01*
X355100Y1210600D01*
X354300D01*
X353400Y1210200D01*
X352700Y1209533D01*
X352200Y1208733D01*
X351800Y1207400D01*
X351700Y1206200D01*
X351900Y1205000D01*
X352200Y1204200D01*
X352800Y1203400D01*
X353500Y1202867D01*
X354200Y1202600D01*
X354900D01*
X355600Y1202867D01*
X356200Y1203267D01*
X356700Y1203800D01*
G01X363000Y1206867D02*
X363400Y1207267D01*
X363700Y1207933D01*
X363900Y1208867D01*
X363700Y1209667D01*
X363300Y1210200D01*
X362600Y1210600D01*
X359900D01*
Y1202600D01*
X363200D01*
X363900Y1203133D01*
X364300Y1203933D01*
X364500Y1204867D01*
X364300Y1205800D01*
X363700Y1206600D01*
X363000Y1206867D01*
X359900D01*
G01X376100Y1203666D02*
X376900Y1203000D01*
X377800Y1202600D01*
X378600D01*
X379400Y1203000D01*
X380000Y1203666D01*
X380300Y1204600D01*
X380100Y1205533D01*
X379600Y1206333D01*
X378700Y1206867D01*
X377500Y1207133D01*
X376800Y1207667D01*
X376500Y1208600D01*
X376700Y1209533D01*
X377200Y1210200D01*
X377900Y1210600D01*
X378600D01*
X379300Y1210333D01*
X379900Y1209667D01*
G01X384200Y1202600D02*
Y1210600D01*
X386600D01*
X387400Y1210200D01*
X388000Y1209267D01*
X388200Y1208200D01*
X388000Y1207133D01*
X387500Y1206333D01*
X386600Y1205933D01*
X384200D01*
G01X396200Y1202600D02*
X392200D01*
Y1210600D01*
X396200D01*
G01X394600Y1206733D02*
X392200D01*
G01X404400Y1209933D02*
X403800Y1210333D01*
X403100Y1210600D01*
X402300D01*
X401400Y1210200D01*
X400700Y1209533D01*
X400200Y1208733D01*
X399800Y1207400D01*
X399700Y1206200D01*
X399900Y1205000D01*
X400200Y1204200D01*
X400800Y1203400D01*
X401500Y1202867D01*
X402200Y1202600D01*
X402900D01*
X403600Y1202867D01*
X404200Y1203267D01*
X404700Y1203800D01*
G01X409000Y1210600D02*
X411400D01*
G01X410200D02*
Y1202600D01*
G01X409000D02*
X411400D01*
G01X416300D02*
Y1210600D01*
X420100D01*
G01X418700Y1206733D02*
X416300D01*
G01X425000Y1210600D02*
X427400D01*
G01X426200D02*
Y1202600D01*
G01X425000D02*
X427400D01*
G01X436400Y1209933D02*
X435800Y1210333D01*
X435100Y1210600D01*
X434300D01*
X433400Y1210200D01*
X432700Y1209533D01*
X432200Y1208733D01*
X431800Y1207400D01*
X431700Y1206200D01*
X431900Y1205000D01*
X432200Y1204200D01*
X432800Y1203400D01*
X433500Y1202867D01*
X434200Y1202600D01*
X434900D01*
X435600Y1202867D01*
X436200Y1203267D01*
X436700Y1203800D01*
G01X439700Y1202600D02*
X442200Y1210600D01*
X444700Y1202600D01*
G01X443800Y1205400D02*
X440600D01*
G01X450200Y1210600D02*
Y1202600D01*
G01X447900Y1210600D02*
X452500D01*
G01X457000D02*
X459400D01*
G01X458200D02*
Y1202600D01*
G01X457000D02*
X459400D01*
G01X466200D02*
X465400Y1202733D01*
X464700Y1203267D01*
X464100Y1204067D01*
X463700Y1205000D01*
X463500Y1206067D01*
Y1207133D01*
X463700Y1208200D01*
X464100Y1209133D01*
X464700Y1209933D01*
X465400Y1210467D01*
X466200Y1210600D01*
X467000Y1210467D01*
X467700Y1209933D01*
X468300Y1209133D01*
X468700Y1208200D01*
X468900Y1207133D01*
Y1206067D01*
X468700Y1205000D01*
X468300Y1204067D01*
X467700Y1203267D01*
X467000Y1202733D01*
X466200Y1202600D01*
G01X471900D02*
Y1210600D01*
X476500Y1202600D01*
Y1210600D01*
G01X482200Y1202333D02*
X482000Y1202467D01*
Y1202733D01*
X482200Y1202867D01*
X482400Y1202733D01*
Y1202467D01*
X482200Y1202333D01*
G01X160000Y1189200D02*
X160600Y1188267D01*
X161400Y1187733D01*
X162300Y1187600D01*
X163100Y1187733D01*
X163900Y1188400D01*
X164400Y1189200D01*
X164500Y1190000D01*
X164300Y1190933D01*
X163600Y1191600D01*
X162900Y1191867D01*
X162000D01*
G01X162900D02*
X163500Y1192267D01*
X164000Y1192933D01*
X164200Y1193733D01*
X164000Y1194533D01*
X163500Y1195200D01*
X162600Y1195600D01*
X161700Y1195467D01*
X160800Y1194933D01*
G01X170200Y1187333D02*
X170000Y1187467D01*
Y1187733D01*
X170200Y1187867D01*
X170400Y1187733D01*
Y1187467D01*
X170200Y1187333D01*
G01X176200Y1187600D02*
Y1195600D01*
X178600D01*
X179400Y1195200D01*
X180000Y1194267D01*
X180200Y1193200D01*
X180000Y1192133D01*
X179500Y1191333D01*
X178600Y1190933D01*
X176200D01*
G01X188400Y1194933D02*
X187800Y1195333D01*
X187100Y1195600D01*
X186300D01*
X185400Y1195200D01*
X184700Y1194533D01*
X184200Y1193733D01*
X183800Y1192400D01*
X183700Y1191200D01*
X183900Y1190000D01*
X184200Y1189200D01*
X184800Y1188400D01*
X185500Y1187867D01*
X186200Y1187600D01*
X186900D01*
X187600Y1187867D01*
X188200Y1188267D01*
X188700Y1188800D01*
G01X195000Y1191867D02*
X195400Y1192267D01*
X195700Y1192933D01*
X195900Y1193867D01*
X195700Y1194667D01*
X195300Y1195200D01*
X194600Y1195600D01*
X191900D01*
Y1187600D01*
X195200D01*
X195900Y1188133D01*
X196300Y1188933D01*
X196500Y1189867D01*
X196300Y1190800D01*
X195700Y1191600D01*
X195000Y1191867D01*
X191900D01*
G01X208200Y1187600D02*
Y1195600D01*
X210600D01*
X211400Y1195200D01*
X212000Y1194267D01*
X212200Y1193200D01*
X212000Y1192133D01*
X211500Y1191333D01*
X210600Y1190933D01*
X208200D01*
G01X216200Y1187600D02*
Y1195600D01*
X218700D01*
X219500Y1195200D01*
X220000Y1194667D01*
X220200Y1193600D01*
X220000Y1192533D01*
X219400Y1191867D01*
X218700Y1191467D01*
X216200D01*
G01X218700D02*
X220200Y1187600D01*
G01X226200D02*
X225400Y1187733D01*
X224700Y1188267D01*
X224100Y1189067D01*
X223700Y1190000D01*
X223500Y1191067D01*
Y1192133D01*
X223700Y1193200D01*
X224100Y1194133D01*
X224700Y1194933D01*
X225400Y1195467D01*
X226200Y1195600D01*
X227000Y1195467D01*
X227700Y1194933D01*
X228300Y1194133D01*
X228700Y1193200D01*
X228900Y1192133D01*
Y1191067D01*
X228700Y1190000D01*
X228300Y1189067D01*
X227700Y1188267D01*
X227000Y1187733D01*
X226200Y1187600D01*
G01X236400Y1194933D02*
X235800Y1195333D01*
X235100Y1195600D01*
X234300D01*
X233400Y1195200D01*
X232700Y1194533D01*
X232200Y1193733D01*
X231800Y1192400D01*
X231700Y1191200D01*
X231900Y1190000D01*
X232200Y1189200D01*
X232800Y1188400D01*
X233500Y1187867D01*
X234200Y1187600D01*
X234900D01*
X235600Y1187867D01*
X236200Y1188267D01*
X236700Y1188800D01*
G01X244200Y1187600D02*
X240200D01*
Y1195600D01*
X244200D01*
G01X242600Y1191733D02*
X240200D01*
G01X248100Y1188666D02*
X248900Y1188000D01*
X249800Y1187600D01*
X250600D01*
X251400Y1188000D01*
X252000Y1188666D01*
X252300Y1189600D01*
X252100Y1190533D01*
X251600Y1191333D01*
X250700Y1191867D01*
X249500Y1192133D01*
X248800Y1192667D01*
X248500Y1193600D01*
X248700Y1194533D01*
X249200Y1195200D01*
X249900Y1195600D01*
X250600D01*
X251300Y1195333D01*
X251900Y1194667D01*
G01X256100Y1188666D02*
X256900Y1188000D01*
X257800Y1187600D01*
X258600D01*
X259400Y1188000D01*
X260000Y1188666D01*
X260300Y1189600D01*
X260100Y1190533D01*
X259600Y1191333D01*
X258700Y1191867D01*
X257500Y1192133D01*
X256800Y1192667D01*
X256500Y1193600D01*
X256700Y1194533D01*
X257200Y1195200D01*
X257900Y1195600D01*
X258600D01*
X259300Y1195333D01*
X259900Y1194667D01*
G01X266200Y1187333D02*
X266000Y1187467D01*
Y1187733D01*
X266200Y1187867D01*
X266400Y1187733D01*
Y1187467D01*
X266200Y1187333D01*
G01Y1190933D02*
X266000Y1191067D01*
Y1191333D01*
X266200Y1191467D01*
X266400Y1191333D01*
Y1191067D01*
X266200Y1190933D01*
G01X162200Y1217600D02*
Y1225600D01*
X161000Y1224000D01*
G01Y1217600D02*
X163400D01*
G01X170200Y1217333D02*
X170000Y1217467D01*
Y1217733D01*
X170200Y1217867D01*
X170400Y1217733D01*
Y1217467D01*
X170200Y1217333D01*
G01X176200Y1217600D02*
Y1225600D01*
X178600D01*
X179400Y1225200D01*
X180000Y1224267D01*
X180200Y1223200D01*
X180000Y1222133D01*
X179500Y1221333D01*
X178600Y1220933D01*
X176200D01*
G01X188400Y1224933D02*
X187800Y1225333D01*
X187100Y1225600D01*
X186300D01*
X185400Y1225200D01*
X184700Y1224533D01*
X184200Y1223733D01*
X183800Y1222400D01*
X183700Y1221200D01*
X183900Y1220000D01*
X184200Y1219200D01*
X184800Y1218400D01*
X185500Y1217867D01*
X186200Y1217600D01*
X186900D01*
X187600Y1217867D01*
X188200Y1218267D01*
X188700Y1218800D01*
G01X195000Y1221867D02*
X195400Y1222267D01*
X195700Y1222933D01*
X195900Y1223867D01*
X195700Y1224667D01*
X195300Y1225200D01*
X194600Y1225600D01*
X191900D01*
Y1217600D01*
X195200D01*
X195900Y1218133D01*
X196300Y1218933D01*
X196500Y1219867D01*
X196300Y1220800D01*
X195700Y1221600D01*
X195000Y1221867D01*
X191900D01*
G01X208100Y1218666D02*
X208900Y1218000D01*
X209800Y1217600D01*
X210600D01*
X211400Y1218000D01*
X212000Y1218666D01*
X212300Y1219600D01*
X212100Y1220533D01*
X211600Y1221333D01*
X210700Y1221867D01*
X209500Y1222133D01*
X208800Y1222667D01*
X208500Y1223600D01*
X208700Y1224533D01*
X209200Y1225200D01*
X209900Y1225600D01*
X210600D01*
X211300Y1225333D01*
X211900Y1224667D01*
G01X217000Y1225600D02*
X219400D01*
G01X218200D02*
Y1217600D01*
G01X217000D02*
X219400D01*
G01X224300Y1225600D02*
X228100D01*
X224300Y1217600D01*
X228100D01*
G01X236200D02*
X232200D01*
Y1225600D01*
X236200D01*
G01X234600Y1221733D02*
X232200D01*
G01X266200Y1217333D02*
X266000Y1217467D01*
Y1217733D01*
X266200Y1217867D01*
X266400Y1217733D01*
Y1217467D01*
X266200Y1217333D01*
G01Y1220933D02*
X266000Y1221067D01*
Y1221333D01*
X266200Y1221467D01*
X266400Y1221333D01*
Y1221067D01*
X266200Y1220933D01*
G01X280300Y1217600D02*
Y1225600D01*
X284100D01*
G01X282700Y1221733D02*
X280300D01*
G01X290200Y1217600D02*
X289400Y1217733D01*
X288700Y1218267D01*
X288100Y1219067D01*
X287700Y1220000D01*
X287500Y1221067D01*
Y1222133D01*
X287700Y1223200D01*
X288100Y1224133D01*
X288700Y1224933D01*
X289400Y1225467D01*
X290200Y1225600D01*
X291000Y1225467D01*
X291700Y1224933D01*
X292300Y1224133D01*
X292700Y1223200D01*
X292900Y1222133D01*
Y1221067D01*
X292700Y1220000D01*
X292300Y1219067D01*
X291700Y1218267D01*
X291000Y1217733D01*
X290200Y1217600D01*
G01X296200Y1225600D02*
Y1217600D01*
X300200D01*
G01X304200Y1225600D02*
Y1217600D01*
X308200D01*
G01X314200D02*
X313400Y1217733D01*
X312700Y1218267D01*
X312100Y1219067D01*
X311700Y1220000D01*
X311500Y1221067D01*
Y1222133D01*
X311700Y1223200D01*
X312100Y1224133D01*
X312700Y1224933D01*
X313400Y1225467D01*
X314200Y1225600D01*
X315000Y1225467D01*
X315700Y1224933D01*
X316300Y1224133D01*
X316700Y1223200D01*
X316900Y1222133D01*
Y1221067D01*
X316700Y1220000D01*
X316300Y1219067D01*
X315700Y1218267D01*
X315000Y1217733D01*
X314200Y1217600D01*
G01X319200Y1225600D02*
X320600Y1217600D01*
X322200Y1225600D01*
X323800Y1217600D01*
X325200Y1225600D01*
G01X338800Y1221600D02*
X340800D01*
Y1219200D01*
X340200Y1218400D01*
X339500Y1217867D01*
X338500Y1217600D01*
X337500Y1217867D01*
X336800Y1218400D01*
X336200Y1219200D01*
X335800Y1220133D01*
X335600Y1221200D01*
Y1222133D01*
X335800Y1222933D01*
X336200Y1223867D01*
X336800Y1224667D01*
X337400Y1225200D01*
X338200Y1225600D01*
X338900D01*
X339700Y1225333D01*
X340300Y1224800D01*
G01X348200Y1217600D02*
X344200D01*
Y1225600D01*
X348200D01*
G01X346600Y1221733D02*
X344200D01*
G01X352200Y1217600D02*
Y1225600D01*
X354700D01*
X355500Y1225200D01*
X356000Y1224667D01*
X356200Y1223600D01*
X356000Y1222533D01*
X355400Y1221867D01*
X354700Y1221467D01*
X352200D01*
G01X354700D02*
X356200Y1217600D01*
G01X363000Y1221867D02*
X363400Y1222267D01*
X363700Y1222933D01*
X363900Y1223867D01*
X363700Y1224667D01*
X363300Y1225200D01*
X362600Y1225600D01*
X359900D01*
Y1217600D01*
X363200D01*
X363900Y1218133D01*
X364300Y1218933D01*
X364500Y1219867D01*
X364300Y1220800D01*
X363700Y1221600D01*
X363000Y1221867D01*
X359900D01*
G01X372200Y1217600D02*
X368200D01*
Y1225600D01*
X372200D01*
G01X370600Y1221733D02*
X368200D01*
G01X376200Y1217600D02*
Y1225600D01*
X378700D01*
X379500Y1225200D01*
X380000Y1224667D01*
X380200Y1223600D01*
X380000Y1222533D01*
X379400Y1221867D01*
X378700Y1221467D01*
X376200D01*
G01X378700D02*
X380200Y1217600D01*
G01X392300D02*
Y1225600D01*
X396100D01*
G01X394700Y1221733D02*
X392300D01*
G01X401000Y1225600D02*
X403400D01*
G01X402200D02*
Y1217600D01*
G01X401000D02*
X403400D01*
G01X408200Y1225600D02*
Y1217600D01*
X412200D01*
G01X420200D02*
X416200D01*
Y1225600D01*
X420200D01*
G01X418600Y1221733D02*
X416200D01*
G01X425500Y1215200D02*
X426900Y1217067D01*
Y1218933D01*
X425500D01*
Y1217067D01*
X426900D01*
G01Y1220267D02*
Y1222133D01*
X425500D01*
Y1220267D01*
X426900D01*
G01X439200Y1225600D02*
X440600Y1217600D01*
X442200Y1225600D01*
X443800Y1217600D01*
X445200Y1225600D01*
G01X449000D02*
X451400D01*
G01X450200D02*
Y1217600D01*
G01X449000D02*
X451400D01*
G01X458200Y1225600D02*
Y1217600D01*
G01X455900Y1225600D02*
X460500D01*
G01X464100Y1217600D02*
Y1225600D01*
G01X468300D02*
Y1217600D01*
G01Y1221600D02*
X464100D01*
G01X482200Y1225600D02*
Y1217600D01*
G01X479900Y1225600D02*
X484500D01*
G01X490200Y1217600D02*
X489400Y1217733D01*
X488700Y1218267D01*
X488100Y1219067D01*
X487700Y1220000D01*
X487500Y1221067D01*
Y1222133D01*
X487700Y1223200D01*
X488100Y1224133D01*
X488700Y1224933D01*
X489400Y1225467D01*
X490200Y1225600D01*
X491000Y1225467D01*
X491700Y1224933D01*
X492300Y1224133D01*
X492700Y1223200D01*
X492900Y1222133D01*
Y1221067D01*
X492700Y1220000D01*
X492300Y1219067D01*
X491700Y1218267D01*
X491000Y1217733D01*
X490200Y1217600D01*
G01X496200Y1225600D02*
Y1217600D01*
X500200D01*
G01X508200D02*
X504200D01*
Y1225600D01*
X508200D01*
G01X506600Y1221733D02*
X504200D01*
G01X512200Y1217600D02*
Y1225600D01*
X514700D01*
X515500Y1225200D01*
X516000Y1224667D01*
X516200Y1223600D01*
X516000Y1222533D01*
X515400Y1221867D01*
X514700Y1221467D01*
X512200D01*
G01X514700D02*
X516200Y1217600D01*
G01X519700D02*
X522200Y1225600D01*
X524700Y1217600D01*
G01X523800Y1220400D02*
X520600D01*
G01X527900Y1217600D02*
Y1225600D01*
X532500Y1217600D01*
Y1225600D01*
G01X540400Y1224933D02*
X539800Y1225333D01*
X539100Y1225600D01*
X538300D01*
X537400Y1225200D01*
X536700Y1224533D01*
X536200Y1223733D01*
X535800Y1222400D01*
X535700Y1221200D01*
X535900Y1220000D01*
X536200Y1219200D01*
X536800Y1218400D01*
X537500Y1217867D01*
X538200Y1217600D01*
X538900D01*
X539600Y1217867D01*
X540200Y1218267D01*
X540700Y1218800D01*
G01X548200Y1217600D02*
X544200D01*
Y1225600D01*
X548200D01*
G01X546600Y1221733D02*
X544200D01*
G01X560900Y1219067D02*
X563500D01*
G01Y1221467D02*
X560900D01*
G01X569100Y1220267D02*
X571500D01*
G01X570200Y1222000D02*
Y1218533D01*
G01X576400Y1217333D02*
X580000Y1225600D01*
G01X584900Y1220267D02*
X587500D01*
G01X594200Y1225600D02*
X593400Y1225333D01*
X592800Y1224667D01*
X592400Y1223867D01*
X592100Y1222800D01*
X592000Y1221600D01*
X592100Y1220400D01*
X592400Y1219333D01*
X592800Y1218533D01*
X593400Y1217867D01*
X594200Y1217600D01*
X595000Y1217867D01*
X595600Y1218533D01*
X596000Y1219333D01*
X596300Y1220400D01*
X596400Y1221600D01*
X596300Y1222800D01*
X596000Y1223867D01*
X595600Y1224667D01*
X595000Y1225333D01*
X594200Y1225600D01*
G01X602200Y1217333D02*
X602000Y1217467D01*
Y1217733D01*
X602200Y1217867D01*
X602400Y1217733D01*
Y1217467D01*
X602200Y1217333D01*
G01X610200Y1217600D02*
Y1225600D01*
X609000Y1224000D01*
G01Y1217600D02*
X611400D01*
G01X616000Y1218800D02*
X616600Y1218133D01*
X617300Y1217733D01*
X618200Y1217600D01*
X619100Y1217867D01*
X619800Y1218400D01*
X620300Y1219333D01*
X620400Y1220400D01*
X620200Y1221467D01*
X619700Y1222133D01*
X619000Y1222667D01*
X618300Y1222800D01*
X617600Y1222667D01*
X616700Y1222133D01*
X617000Y1225600D01*
X619700D01*
G01X623600Y1217600D02*
Y1225600D01*
X626200Y1218933D01*
X628800Y1225600D01*
Y1217600D01*
G01X631600D02*
Y1225600D01*
X634200Y1218933D01*
X636800Y1225600D01*
Y1217600D01*
G01X159900Y1232600D02*
Y1240600D01*
X164500Y1232600D01*
Y1240600D01*
G01X170200Y1232600D02*
X169400Y1232733D01*
X168700Y1233267D01*
X168100Y1234067D01*
X167700Y1235000D01*
X167500Y1236067D01*
Y1237133D01*
X167700Y1238200D01*
X168100Y1239133D01*
X168700Y1239933D01*
X169400Y1240467D01*
X170200Y1240600D01*
X171000Y1240467D01*
X171700Y1239933D01*
X172300Y1239133D01*
X172700Y1238200D01*
X172900Y1237133D01*
Y1236067D01*
X172700Y1235000D01*
X172300Y1234067D01*
X171700Y1233267D01*
X171000Y1232733D01*
X170200Y1232600D01*
G01X178200Y1240600D02*
Y1232600D01*
G01X175900Y1240600D02*
X180500D01*
G01X188200Y1232600D02*
X184200D01*
Y1240600D01*
X188200D01*
G01X186600Y1236733D02*
X184200D01*
G01X192100Y1233666D02*
X192900Y1233000D01*
X193800Y1232600D01*
X194600D01*
X195400Y1233000D01*
X196000Y1233666D01*
X196300Y1234600D01*
X196100Y1235533D01*
X195600Y1236333D01*
X194700Y1236867D01*
X193500Y1237133D01*
X192800Y1237667D01*
X192500Y1238600D01*
X192700Y1239533D01*
X193200Y1240200D01*
X193900Y1240600D01*
X194600D01*
X195300Y1240333D01*
X195900Y1239667D01*
G01X202200Y1232333D02*
X202000Y1232467D01*
Y1232733D01*
X202200Y1232867D01*
X202400Y1232733D01*
Y1232467D01*
X202200Y1232333D01*
G01Y1235933D02*
X202000Y1236067D01*
Y1236333D01*
X202200Y1236467D01*
X202400Y1236333D01*
Y1236067D01*
X202200Y1235933D01*
G01X209700Y1229933D02*
X208700Y1231267D01*
X208200Y1232600D01*
Y1237933D01*
X208700Y1239267D01*
X209700Y1240600D01*
G01X216000D02*
Y1234867D01*
X216400Y1233666D01*
X217200Y1232867D01*
X218200Y1232600D01*
X219200Y1232867D01*
X220000Y1233666D01*
X220400Y1234867D01*
Y1240600D01*
G01X223900Y1232600D02*
Y1240600D01*
X228500Y1232600D01*
Y1240600D01*
G01X232200D02*
Y1232600D01*
X236200D01*
G01X244200D02*
X240200D01*
Y1240600D01*
X244200D01*
G01X242600Y1236733D02*
X240200D01*
G01X248100Y1233666D02*
X248900Y1233000D01*
X249800Y1232600D01*
X250600D01*
X251400Y1233000D01*
X252000Y1233666D01*
X252300Y1234600D01*
X252100Y1235533D01*
X251600Y1236333D01*
X250700Y1236867D01*
X249500Y1237133D01*
X248800Y1237667D01*
X248500Y1238600D01*
X248700Y1239533D01*
X249200Y1240200D01*
X249900Y1240600D01*
X250600D01*
X251300Y1240333D01*
X251900Y1239667D01*
G01X256100Y1233666D02*
X256900Y1233000D01*
X257800Y1232600D01*
X258600D01*
X259400Y1233000D01*
X260000Y1233666D01*
X260300Y1234600D01*
X260100Y1235533D01*
X259600Y1236333D01*
X258700Y1236867D01*
X257500Y1237133D01*
X256800Y1237667D01*
X256500Y1238600D01*
X256700Y1239533D01*
X257200Y1240200D01*
X257900Y1240600D01*
X258600D01*
X259300Y1240333D01*
X259900Y1239667D01*
G01X274200Y1232600D02*
X273400Y1232733D01*
X272700Y1233267D01*
X272100Y1234067D01*
X271700Y1235000D01*
X271500Y1236067D01*
Y1237133D01*
X271700Y1238200D01*
X272100Y1239133D01*
X272700Y1239933D01*
X273400Y1240467D01*
X274200Y1240600D01*
X275000Y1240467D01*
X275700Y1239933D01*
X276300Y1239133D01*
X276700Y1238200D01*
X276900Y1237133D01*
Y1236067D01*
X276700Y1235000D01*
X276300Y1234067D01*
X275700Y1233267D01*
X275000Y1232733D01*
X274200Y1232600D01*
G01X282200Y1240600D02*
Y1232600D01*
G01X279900Y1240600D02*
X284500D01*
G01X288100Y1232600D02*
Y1240600D01*
G01X292300D02*
Y1232600D01*
G01Y1236600D02*
X288100D01*
G01X300200Y1232600D02*
X296200D01*
Y1240600D01*
X300200D01*
G01X298600Y1236733D02*
X296200D01*
G01X304200Y1232600D02*
Y1240600D01*
X306700D01*
X307500Y1240200D01*
X308000Y1239667D01*
X308200Y1238600D01*
X308000Y1237533D01*
X307400Y1236867D01*
X306700Y1236467D01*
X304200D01*
G01X306700D02*
X308200Y1232600D01*
G01X311200Y1240600D02*
X312600Y1232600D01*
X314200Y1240600D01*
X315800Y1232600D01*
X317200Y1240600D01*
G01X321000D02*
X323400D01*
G01X322200D02*
Y1232600D01*
G01X321000D02*
X323400D01*
G01X328100Y1233666D02*
X328900Y1233000D01*
X329800Y1232600D01*
X330600D01*
X331400Y1233000D01*
X332000Y1233666D01*
X332300Y1234600D01*
X332100Y1235533D01*
X331600Y1236333D01*
X330700Y1236867D01*
X329500Y1237133D01*
X328800Y1237667D01*
X328500Y1238600D01*
X328700Y1239533D01*
X329200Y1240200D01*
X329900Y1240600D01*
X330600D01*
X331300Y1240333D01*
X331900Y1239667D01*
G01X340200Y1232600D02*
X336200D01*
Y1240600D01*
X340200D01*
G01X338600Y1236733D02*
X336200D01*
G01X352100Y1233666D02*
X352900Y1233000D01*
X353800Y1232600D01*
X354600D01*
X355400Y1233000D01*
X356000Y1233666D01*
X356300Y1234600D01*
X356100Y1235533D01*
X355600Y1236333D01*
X354700Y1236867D01*
X353500Y1237133D01*
X352800Y1237667D01*
X352500Y1238600D01*
X352700Y1239533D01*
X353200Y1240200D01*
X353900Y1240600D01*
X354600D01*
X355300Y1240333D01*
X355900Y1239667D01*
G01X360200Y1232600D02*
Y1240600D01*
X362600D01*
X363400Y1240200D01*
X364000Y1239267D01*
X364200Y1238200D01*
X364000Y1237133D01*
X363500Y1236333D01*
X362600Y1235933D01*
X360200D01*
G01X372200Y1232600D02*
X368200D01*
Y1240600D01*
X372200D01*
G01X370600Y1236733D02*
X368200D01*
G01X380400Y1239933D02*
X379800Y1240333D01*
X379100Y1240600D01*
X378300D01*
X377400Y1240200D01*
X376700Y1239533D01*
X376200Y1238733D01*
X375800Y1237400D01*
X375700Y1236200D01*
X375900Y1235000D01*
X376200Y1234200D01*
X376800Y1233400D01*
X377500Y1232867D01*
X378200Y1232600D01*
X378900D01*
X379600Y1232867D01*
X380200Y1233267D01*
X380700Y1233800D01*
G01X385000Y1240600D02*
X387400D01*
G01X386200D02*
Y1232600D01*
G01X385000D02*
X387400D01*
G01X392300D02*
Y1240600D01*
X396100D01*
G01X394700Y1236733D02*
X392300D01*
G01X401000Y1240600D02*
X403400D01*
G01X402200D02*
Y1232600D01*
G01X401000D02*
X403400D01*
G01X412200D02*
X408200D01*
Y1240600D01*
X412200D01*
G01X410600Y1236733D02*
X408200D01*
G01X416000Y1232600D02*
Y1240600D01*
X418000D01*
X418800Y1240200D01*
X419400Y1239667D01*
X419900Y1238867D01*
X420300Y1237933D01*
X420400Y1236600D01*
X420300Y1235267D01*
X419900Y1234333D01*
X419400Y1233533D01*
X418800Y1233000D01*
X418000Y1232600D01*
X416000D01*
G01X433000Y1240600D02*
X435400D01*
G01X434200D02*
Y1232600D01*
G01X433000D02*
X435400D01*
G01X439900D02*
Y1240600D01*
X444500Y1232600D01*
Y1240600D01*
G01X458200D02*
Y1232600D01*
G01X455900Y1240600D02*
X460500D01*
G01X464300Y1235933D02*
X465000Y1236867D01*
X465600Y1237400D01*
X466400Y1237667D01*
X467100Y1237400D01*
X467600Y1236867D01*
X468000Y1236067D01*
X468100Y1235133D01*
X468000Y1234333D01*
X467600Y1233533D01*
X467000Y1232867D01*
X466300Y1232600D01*
X465500Y1232867D01*
X464800Y1233666D01*
X464400Y1234867D01*
X464300Y1236200D01*
X464500Y1237933D01*
X464800Y1238867D01*
X465300Y1239800D01*
X466000Y1240467D01*
X466700Y1240600D01*
X467400Y1240333D01*
X467900Y1239667D01*
G01X471600Y1232600D02*
Y1240600D01*
X474200Y1233933D01*
X476800Y1240600D01*
Y1232600D01*
G01X479200Y1229933D02*
X485200D01*
G01X490200Y1240600D02*
Y1232600D01*
G01X487900Y1240600D02*
X492500D01*
G01X496800Y1232600D02*
Y1237933D01*
G01Y1236867D02*
X497300Y1237400D01*
X497800Y1237800D01*
X498500Y1237933D01*
X499000Y1237800D01*
X499600Y1237400D01*
G01X508000Y1232600D02*
Y1237933D01*
G01Y1237000D02*
X507600Y1237533D01*
X507000Y1237800D01*
X506300Y1237933D01*
X505600Y1237667D01*
X505000Y1237133D01*
X504600Y1236333D01*
X504400Y1235267D01*
X504600Y1234200D01*
X505000Y1233400D01*
X505600Y1232867D01*
X506300Y1232600D01*
X507000Y1232733D01*
X507600Y1233133D01*
X508000Y1233666D01*
G01X512100Y1230200D02*
X512700Y1229933D01*
X513500Y1230200D01*
X514000Y1230733D01*
X514400Y1231400D01*
X515000Y1233533D01*
X516300Y1237933D01*
G01X513100D02*
X515000Y1233533D01*
G01X519200Y1229933D02*
X525200D01*
G01X531000Y1236867D02*
X531400Y1237267D01*
X531700Y1237933D01*
X531900Y1238867D01*
X531700Y1239667D01*
X531300Y1240200D01*
X530600Y1240600D01*
X527900D01*
Y1232600D01*
X531200D01*
X531900Y1233133D01*
X532300Y1233933D01*
X532500Y1234867D01*
X532300Y1235800D01*
X531700Y1236600D01*
X531000Y1236867D01*
X527900D01*
G01X536200Y1232600D02*
Y1240600D01*
X538600D01*
X539400Y1240200D01*
X540000Y1239267D01*
X540200Y1238200D01*
X540000Y1237133D01*
X539500Y1236333D01*
X538600Y1235933D01*
X536200D01*
G01X543200Y1229933D02*
X549200D01*
G01X556400Y1239933D02*
X555800Y1240333D01*
X555100Y1240600D01*
X554300D01*
X553400Y1240200D01*
X552700Y1239533D01*
X552200Y1238733D01*
X551800Y1237400D01*
X551700Y1236200D01*
X551900Y1235000D01*
X552200Y1234200D01*
X552800Y1233400D01*
X553500Y1232867D01*
X554200Y1232600D01*
X554900D01*
X555600Y1232867D01*
X556200Y1233267D01*
X556700Y1233800D01*
G01X559200Y1229933D02*
X565200D01*
G01X568200Y1232600D02*
Y1240600D01*
X570600D01*
X571400Y1240200D01*
X572000Y1239267D01*
X572200Y1238200D01*
X572000Y1237133D01*
X571500Y1236333D01*
X570600Y1235933D01*
X568200D01*
G01X580400Y1239933D02*
X579800Y1240333D01*
X579100Y1240600D01*
X578300D01*
X577400Y1240200D01*
X576700Y1239533D01*
X576200Y1238733D01*
X575800Y1237400D01*
X575700Y1236200D01*
X575900Y1235000D01*
X576200Y1234200D01*
X576800Y1233400D01*
X577500Y1232867D01*
X578200Y1232600D01*
X578900D01*
X579600Y1232867D01*
X580200Y1233267D01*
X580700Y1233800D01*
G01X587000Y1236867D02*
X587400Y1237267D01*
X587700Y1237933D01*
X587900Y1238867D01*
X587700Y1239667D01*
X587300Y1240200D01*
X586600Y1240600D01*
X583900D01*
Y1232600D01*
X587200D01*
X587900Y1233133D01*
X588300Y1233933D01*
X588500Y1234867D01*
X588300Y1235800D01*
X587700Y1236600D01*
X587000Y1236867D01*
X583900D01*
G01X591200Y1229933D02*
X597200D01*
G01X600100Y1233666D02*
X600900Y1233000D01*
X601800Y1232600D01*
X602600D01*
X603400Y1233000D01*
X604000Y1233666D01*
X604300Y1234600D01*
X604100Y1235533D01*
X603600Y1236333D01*
X602700Y1236867D01*
X601500Y1237133D01*
X600800Y1237667D01*
X600500Y1238600D01*
X600700Y1239533D01*
X601200Y1240200D01*
X601900Y1240600D01*
X602600D01*
X603300Y1240333D01*
X603900Y1239667D01*
G01X608200Y1232600D02*
Y1240600D01*
X610600D01*
X611400Y1240200D01*
X612000Y1239267D01*
X612200Y1238200D01*
X612000Y1237133D01*
X611500Y1236333D01*
X610600Y1235933D01*
X608200D01*
G01X620200Y1232600D02*
X616200D01*
Y1240600D01*
X620200D01*
G01X618600Y1236733D02*
X616200D01*
G01X628400Y1239933D02*
X627800Y1240333D01*
X627100Y1240600D01*
X626300D01*
X625400Y1240200D01*
X624700Y1239533D01*
X624200Y1238733D01*
X623800Y1237400D01*
X623700Y1236200D01*
X623900Y1235000D01*
X624200Y1234200D01*
X624800Y1233400D01*
X625500Y1232867D01*
X626200Y1232600D01*
X626900D01*
X627600Y1232867D01*
X628200Y1233267D01*
X628700Y1233800D01*
G01X634200Y1232333D02*
X634000Y1232467D01*
Y1232733D01*
X634200Y1232867D01*
X634400Y1232733D01*
Y1232467D01*
X634200Y1232333D01*
G01X640000Y1232600D02*
Y1240600D01*
X642000D01*
X642800Y1240200D01*
X643400Y1239667D01*
X643900Y1238867D01*
X644300Y1237933D01*
X644400Y1236600D01*
X644300Y1235267D01*
X643900Y1234333D01*
X643400Y1233533D01*
X642800Y1233000D01*
X642000Y1232600D01*
X640000D01*
G01X650200D02*
X649400Y1232733D01*
X648700Y1233267D01*
X648100Y1234067D01*
X647700Y1235000D01*
X647500Y1236067D01*
Y1237133D01*
X647700Y1238200D01*
X648100Y1239133D01*
X648700Y1239933D01*
X649400Y1240467D01*
X650200Y1240600D01*
X651000Y1240467D01*
X651700Y1239933D01*
X652300Y1239133D01*
X652700Y1238200D01*
X652900Y1237133D01*
Y1236067D01*
X652700Y1235000D01*
X652300Y1234067D01*
X651700Y1233267D01*
X651000Y1232733D01*
X650200Y1232600D01*
G01X660400Y1239933D02*
X659800Y1240333D01*
X659100Y1240600D01*
X658300D01*
X657400Y1240200D01*
X656700Y1239533D01*
X656200Y1238733D01*
X655800Y1237400D01*
X655700Y1236200D01*
X655900Y1235000D01*
X656200Y1234200D01*
X656800Y1233400D01*
X657500Y1232867D01*
X658200Y1232600D01*
X658900D01*
X659600Y1232867D01*
X660200Y1233267D01*
X660700Y1233800D01*
G01X666700Y1229933D02*
X667700Y1231267D01*
X668200Y1232600D01*
Y1237933D01*
X667700Y1239267D01*
X666700Y1240600D01*
G01X220822Y764107D02*
X177515D01*
G01X185389D02*
Y817257D01*
G01X182500Y791660D02*
X170000D01*
X178958Y785925D01*
Y793675D01*
G01X182500Y798170D02*
X170000D01*
X180417Y802200D01*
X170000Y806230D01*
X182500D01*
G01Y810570D02*
X170000D01*
X180417Y814600D01*
X170000Y818630D01*
X182500D01*
G01X220822Y779856D02*
X177515D01*
G01X177200Y992600D02*
X176400Y992733D01*
X175700Y993267D01*
X175100Y994067D01*
X174700Y995000D01*
X174500Y996067D01*
Y997133D01*
X174700Y998200D01*
X175100Y999133D01*
X175700Y999933D01*
X176400Y1000467D01*
X177200Y1000600D01*
X178000Y1000467D01*
X178700Y999933D01*
X179300Y999133D01*
X179700Y998200D01*
X179900Y997133D01*
Y996067D01*
X179700Y995000D01*
X179300Y994067D01*
X178700Y993267D01*
X178000Y992733D01*
X177200Y992600D01*
G01X178000Y994733D02*
X179200Y992600D01*
G01X183000Y1000600D02*
Y994867D01*
X183400Y993666D01*
X184200Y992867D01*
X185200Y992600D01*
X186200Y992867D01*
X187000Y993666D01*
X187400Y994867D01*
Y1000600D01*
G01X190700Y992600D02*
X193200Y1000600D01*
X195700Y992600D01*
G01X194800Y995400D02*
X191600D01*
G01X198900Y992600D02*
Y1000600D01*
X203500Y992600D01*
Y1000600D01*
G01X209200D02*
Y992600D01*
G01X206900Y1000600D02*
X211500D01*
G01X214700Y992600D02*
X217200Y1000600D01*
X219700Y992600D01*
G01X218800Y995400D02*
X215600D01*
G01X231200Y992600D02*
Y1000600D01*
X233600D01*
X234400Y1000200D01*
X235000Y999267D01*
X235200Y998200D01*
X235000Y997133D01*
X234500Y996333D01*
X233600Y995933D01*
X231200D01*
G01X239200Y992600D02*
Y1000600D01*
X241700D01*
X242500Y1000200D01*
X243000Y999667D01*
X243200Y998600D01*
X243000Y997533D01*
X242400Y996867D01*
X241700Y996467D01*
X239200D01*
G01X241700D02*
X243200Y992600D01*
G01X248000Y1000600D02*
X250400D01*
G01X249200D02*
Y992600D01*
G01X248000D02*
X250400D01*
G01X257200D02*
X256400Y992733D01*
X255700Y993267D01*
X255100Y994067D01*
X254700Y995000D01*
X254500Y996067D01*
Y997133D01*
X254700Y998200D01*
X255100Y999133D01*
X255700Y999933D01*
X256400Y1000467D01*
X257200Y1000600D01*
X258000Y1000467D01*
X258700Y999933D01*
X259300Y999133D01*
X259700Y998200D01*
X259900Y997133D01*
Y996067D01*
X259700Y995000D01*
X259300Y994067D01*
X258700Y993267D01*
X258000Y992733D01*
X257200Y992600D01*
G01X263200D02*
Y1000600D01*
X265700D01*
X266500Y1000200D01*
X267000Y999667D01*
X267200Y998600D01*
X267000Y997533D01*
X266400Y996867D01*
X265700Y996467D01*
X263200D01*
G01X265700D02*
X267200Y992600D01*
G01X281200Y1000600D02*
Y992600D01*
G01X278900Y1000600D02*
X283500D01*
G01X289200Y992600D02*
X288400Y992733D01*
X287700Y993267D01*
X287100Y994067D01*
X286700Y995000D01*
X286500Y996067D01*
Y997133D01*
X286700Y998200D01*
X287100Y999133D01*
X287700Y999933D01*
X288400Y1000467D01*
X289200Y1000600D01*
X290000Y1000467D01*
X290700Y999933D01*
X291300Y999133D01*
X291700Y998200D01*
X291900Y997133D01*
Y996067D01*
X291700Y995000D01*
X291300Y994067D01*
X290700Y993267D01*
X290000Y992733D01*
X289200Y992600D01*
G01X304000Y1000600D02*
X306400D01*
G01X305200D02*
Y992600D01*
G01X304000D02*
X306400D01*
G01X313200Y1000600D02*
Y992600D01*
G01X310900Y1000600D02*
X315500D01*
G01X319100Y993666D02*
X319900Y993000D01*
X320800Y992600D01*
X321600D01*
X322400Y993000D01*
X323000Y993666D01*
X323300Y994600D01*
X323100Y995533D01*
X322600Y996333D01*
X321700Y996867D01*
X320500Y997133D01*
X319800Y997667D01*
X319500Y998600D01*
X319700Y999533D01*
X320200Y1000200D01*
X320900Y1000600D01*
X321600D01*
X322300Y1000333D01*
X322900Y999667D01*
G01X336000Y1000600D02*
X338400D01*
G01X337200D02*
Y992600D01*
G01X336000D02*
X338400D01*
G01X342600D02*
Y1000600D01*
X345200Y993933D01*
X347800Y1000600D01*
Y992600D01*
G01X351200D02*
Y1000600D01*
X353600D01*
X354400Y1000200D01*
X355000Y999267D01*
X355200Y998200D01*
X355000Y997133D01*
X354500Y996333D01*
X353600Y995933D01*
X351200D01*
G01X359200Y1000600D02*
Y992600D01*
X363200D01*
G01X371200D02*
X367200D01*
Y1000600D01*
X371200D01*
G01X369600Y996733D02*
X367200D01*
G01X374600Y992600D02*
Y1000600D01*
X377200Y993933D01*
X379800Y1000600D01*
Y992600D01*
G01X387200D02*
X383200D01*
Y1000600D01*
X387200D01*
G01X385600Y996733D02*
X383200D01*
G01X390900Y992600D02*
Y1000600D01*
X395500Y992600D01*
Y1000600D01*
G01X401200D02*
Y992600D01*
G01X398900Y1000600D02*
X403500D01*
G01X406700Y992600D02*
X409200Y1000600D01*
X411700Y992600D01*
G01X410800Y995400D02*
X407600D01*
G01X417200Y1000600D02*
Y992600D01*
G01X414900Y1000600D02*
X419500D01*
G01X424000D02*
X426400D01*
G01X425200D02*
Y992600D01*
G01X424000D02*
X426400D01*
G01X433200D02*
X432400Y992733D01*
X431700Y993267D01*
X431100Y994067D01*
X430700Y995000D01*
X430500Y996067D01*
Y997133D01*
X430700Y998200D01*
X431100Y999133D01*
X431700Y999933D01*
X432400Y1000467D01*
X433200Y1000600D01*
X434000Y1000467D01*
X434700Y999933D01*
X435300Y999133D01*
X435700Y998200D01*
X435900Y997133D01*
Y996067D01*
X435700Y995000D01*
X435300Y994067D01*
X434700Y993267D01*
X434000Y992733D01*
X433200Y992600D01*
G01X438900D02*
Y1000600D01*
X443500Y992600D01*
Y1000600D01*
G01X449200Y992333D02*
X449000Y992467D01*
Y992733D01*
X449200Y992867D01*
X449400Y992733D01*
Y992467D01*
X449200Y992333D01*
G01X176000Y1030600D02*
X178400D01*
G01X177200D02*
Y1022600D01*
G01X176000D02*
X178400D01*
G01X182600D02*
Y1030600D01*
X185200Y1023933D01*
X187800Y1030600D01*
Y1022600D01*
G01X191200D02*
Y1030600D01*
X193600D01*
X194400Y1030200D01*
X195000Y1029267D01*
X195200Y1028200D01*
X195000Y1027133D01*
X194500Y1026333D01*
X193600Y1025933D01*
X191200D01*
G01X203200Y1022600D02*
X199200D01*
Y1030600D01*
X203200D01*
G01X201600Y1026733D02*
X199200D01*
G01X207000Y1022600D02*
Y1030600D01*
X209000D01*
X209800Y1030200D01*
X210400Y1029667D01*
X210900Y1028867D01*
X211300Y1027933D01*
X211400Y1026600D01*
X211300Y1025267D01*
X210900Y1024333D01*
X210400Y1023533D01*
X209800Y1023000D01*
X209000Y1022600D01*
X207000D01*
G01X214700D02*
X217200Y1030600D01*
X219700Y1022600D01*
G01X218800Y1025400D02*
X215600D01*
G01X222900Y1022600D02*
Y1030600D01*
X227500Y1022600D01*
Y1030600D01*
G01X235400Y1029933D02*
X234800Y1030333D01*
X234100Y1030600D01*
X233300D01*
X232400Y1030200D01*
X231700Y1029533D01*
X231200Y1028733D01*
X230800Y1027400D01*
X230700Y1026200D01*
X230900Y1025000D01*
X231200Y1024200D01*
X231800Y1023400D01*
X232500Y1022867D01*
X233200Y1022600D01*
X233900D01*
X234600Y1022867D01*
X235200Y1023267D01*
X235700Y1023800D01*
G01X243200Y1022600D02*
X239200D01*
Y1030600D01*
X243200D01*
G01X241600Y1026733D02*
X239200D01*
G01X247100Y1023666D02*
X247900Y1023000D01*
X248800Y1022600D01*
X249600D01*
X250400Y1023000D01*
X251000Y1023666D01*
X251300Y1024600D01*
X251100Y1025533D01*
X250600Y1026333D01*
X249700Y1026867D01*
X248500Y1027133D01*
X247800Y1027667D01*
X247500Y1028600D01*
X247700Y1029533D01*
X248200Y1030200D01*
X248900Y1030600D01*
X249600D01*
X250300Y1030333D01*
X250900Y1029667D01*
G01X262700Y1022600D02*
X265200Y1030600D01*
X267700Y1022600D01*
G01X266800Y1025400D02*
X263600D01*
G01X270900Y1022600D02*
Y1030600D01*
X275500Y1022600D01*
Y1030600D01*
G01X279000Y1022600D02*
Y1030600D01*
X281000D01*
X281800Y1030200D01*
X282400Y1029667D01*
X282900Y1028867D01*
X283300Y1027933D01*
X283400Y1026600D01*
X283300Y1025267D01*
X282900Y1024333D01*
X282400Y1023533D01*
X281800Y1023000D01*
X281000Y1022600D01*
X279000D01*
G01X298000Y1026867D02*
X298400Y1027267D01*
X298700Y1027933D01*
X298900Y1028867D01*
X298700Y1029667D01*
X298300Y1030200D01*
X297600Y1030600D01*
X294900D01*
Y1022600D01*
X298200D01*
X298900Y1023133D01*
X299300Y1023933D01*
X299500Y1024867D01*
X299300Y1025800D01*
X298700Y1026600D01*
X298000Y1026867D01*
X294900D01*
G01X305200Y1022600D02*
X304400Y1022733D01*
X303700Y1023267D01*
X303100Y1024067D01*
X302700Y1025000D01*
X302500Y1026067D01*
Y1027133D01*
X302700Y1028200D01*
X303100Y1029133D01*
X303700Y1029933D01*
X304400Y1030467D01*
X305200Y1030600D01*
X306000Y1030467D01*
X306700Y1029933D01*
X307300Y1029133D01*
X307700Y1028200D01*
X307900Y1027133D01*
Y1026067D01*
X307700Y1025000D01*
X307300Y1024067D01*
X306700Y1023267D01*
X306000Y1022733D01*
X305200Y1022600D01*
G01X310700D02*
X313200Y1030600D01*
X315700Y1022600D01*
G01X314800Y1025400D02*
X311600D01*
G01X319200Y1022600D02*
Y1030600D01*
X321700D01*
X322500Y1030200D01*
X323000Y1029667D01*
X323200Y1028600D01*
X323000Y1027533D01*
X322400Y1026867D01*
X321700Y1026467D01*
X319200D01*
G01X321700D02*
X323200Y1022600D01*
G01X327000D02*
Y1030600D01*
X329000D01*
X329800Y1030200D01*
X330400Y1029667D01*
X330900Y1028867D01*
X331300Y1027933D01*
X331400Y1026600D01*
X331300Y1025267D01*
X330900Y1024333D01*
X330400Y1023533D01*
X329800Y1023000D01*
X329000Y1022600D01*
X327000D01*
G01X345200Y1030600D02*
Y1022600D01*
G01X342900Y1030600D02*
X347500D01*
G01X351100Y1022600D02*
Y1030600D01*
G01X355300D02*
Y1022600D01*
G01Y1026600D02*
X351100D01*
G01X360000Y1030600D02*
X362400D01*
G01X361200D02*
Y1022600D01*
G01X360000D02*
X362400D01*
G01X371400Y1029933D02*
X370800Y1030333D01*
X370100Y1030600D01*
X369300D01*
X368400Y1030200D01*
X367700Y1029533D01*
X367200Y1028733D01*
X366800Y1027400D01*
X366700Y1026200D01*
X366900Y1025000D01*
X367200Y1024200D01*
X367800Y1023400D01*
X368500Y1022867D01*
X369200Y1022600D01*
X369900D01*
X370600Y1022867D01*
X371200Y1023267D01*
X371700Y1023800D01*
G01X375000Y1022600D02*
Y1030600D01*
G01X378800D02*
X375000Y1025666D01*
G01X379400Y1022600D02*
X376700Y1027933D01*
G01X382900Y1022600D02*
Y1030600D01*
X387500Y1022600D01*
Y1030600D01*
G01X395200Y1022600D02*
X391200D01*
Y1030600D01*
X395200D01*
G01X393600Y1026733D02*
X391200D01*
G01X399100Y1023666D02*
X399900Y1023000D01*
X400800Y1022600D01*
X401600D01*
X402400Y1023000D01*
X403000Y1023666D01*
X403300Y1024600D01*
X403100Y1025533D01*
X402600Y1026333D01*
X401700Y1026867D01*
X400500Y1027133D01*
X399800Y1027667D01*
X399500Y1028600D01*
X399700Y1029533D01*
X400200Y1030200D01*
X400900Y1030600D01*
X401600D01*
X402300Y1030333D01*
X402900Y1029667D01*
G01X407100Y1023666D02*
X407900Y1023000D01*
X408800Y1022600D01*
X409600D01*
X410400Y1023000D01*
X411000Y1023666D01*
X411300Y1024600D01*
X411100Y1025533D01*
X410600Y1026333D01*
X409700Y1026867D01*
X408500Y1027133D01*
X407800Y1027667D01*
X407500Y1028600D01*
X407700Y1029533D01*
X408200Y1030200D01*
X408900Y1030600D01*
X409600D01*
X410300Y1030333D01*
X410900Y1029667D01*
G01X417200Y1022333D02*
X417000Y1022467D01*
Y1022733D01*
X417200Y1022867D01*
X417400Y1022733D01*
Y1022467D01*
X417200Y1022333D01*
G01X440000Y1030600D02*
X442400D01*
G01X441200D02*
Y1022600D01*
G01X440000D02*
X442400D01*
G01X446900D02*
Y1030600D01*
X451500Y1022600D01*
Y1030600D01*
G01X456000D02*
X458400D01*
G01X457200D02*
Y1022600D01*
G01X456000D02*
X458400D01*
G01X465200Y1030600D02*
Y1022600D01*
G01X462900Y1030600D02*
X467500D01*
G01X472000D02*
X474400D01*
G01X473200D02*
Y1022600D01*
G01X472000D02*
X474400D01*
G01X478700D02*
X481200Y1030600D01*
X483700Y1022600D01*
G01X482800Y1025400D02*
X479600D01*
G01X487200Y1030600D02*
Y1022600D01*
X491200D01*
G01X503000D02*
Y1030600D01*
X505000D01*
X505800Y1030200D01*
X506400Y1029667D01*
X506900Y1028867D01*
X507300Y1027933D01*
X507400Y1026600D01*
X507300Y1025267D01*
X506900Y1024333D01*
X506400Y1023533D01*
X505800Y1023000D01*
X505000Y1022600D01*
X503000D01*
G01X515200D02*
X511200D01*
Y1030600D01*
X515200D01*
G01X513600Y1026733D02*
X511200D01*
G01X521200Y1030600D02*
Y1022600D01*
G01X518900Y1030600D02*
X523500D01*
G01X526700Y1022600D02*
X529200Y1030600D01*
X531700Y1022600D01*
G01X530800Y1025400D02*
X527600D01*
G01X536000Y1030600D02*
X538400D01*
G01X537200D02*
Y1022600D01*
G01X536000D02*
X538400D01*
G01X543200Y1030600D02*
Y1022600D01*
X547200D01*
G01X559200Y1030600D02*
Y1022600D01*
X563200D01*
G01X566700D02*
X569200Y1030600D01*
X571700Y1022600D01*
G01X570800Y1025400D02*
X567600D01*
G01X577200Y1022600D02*
Y1026200D01*
X575200Y1030600D01*
G01X579200D02*
X577200Y1026200D01*
G01X587200Y1022600D02*
X583200D01*
Y1030600D01*
X587200D01*
G01X585600Y1026733D02*
X583200D01*
G01X591200Y1022600D02*
Y1030600D01*
X593700D01*
X594500Y1030200D01*
X595000Y1029667D01*
X595200Y1028600D01*
X595000Y1027533D01*
X594400Y1026867D01*
X593700Y1026467D01*
X591200D01*
G01X593700D02*
X595200Y1022600D01*
G01X175100Y1008666D02*
X175900Y1008000D01*
X176800Y1007600D01*
X177600D01*
X178400Y1008000D01*
X179000Y1008666D01*
X179300Y1009600D01*
X179100Y1010533D01*
X178600Y1011333D01*
X177700Y1011867D01*
X176500Y1012133D01*
X175800Y1012667D01*
X175500Y1013600D01*
X175700Y1014533D01*
X176200Y1015200D01*
X176900Y1015600D01*
X177600D01*
X178300Y1015333D01*
X178900Y1014667D01*
G01X185200Y1015600D02*
Y1007600D01*
G01X182900Y1015600D02*
X187500D01*
G01X190700Y1007600D02*
X193200Y1015600D01*
X195700Y1007600D01*
G01X194800Y1010400D02*
X191600D01*
G01X203400Y1014933D02*
X202800Y1015333D01*
X202100Y1015600D01*
X201300D01*
X200400Y1015200D01*
X199700Y1014533D01*
X199200Y1013733D01*
X198800Y1012400D01*
X198700Y1011200D01*
X198900Y1010000D01*
X199200Y1009200D01*
X199800Y1008400D01*
X200500Y1007867D01*
X201200Y1007600D01*
X201900D01*
X202600Y1007867D01*
X203200Y1008267D01*
X203700Y1008800D01*
G01X207000Y1007600D02*
Y1015600D01*
G01X210800D02*
X207000Y1010666D01*
G01X211400Y1007600D02*
X208700Y1012933D01*
G01X216000Y1015600D02*
X218400D01*
G01X217200D02*
Y1007600D01*
G01X216000D02*
X218400D01*
G01X222900D02*
Y1015600D01*
X227500Y1007600D01*
Y1015600D01*
G01X233800Y1011600D02*
X235800D01*
Y1009200D01*
X235200Y1008400D01*
X234500Y1007867D01*
X233500Y1007600D01*
X232500Y1007867D01*
X231800Y1008400D01*
X231200Y1009200D01*
X230800Y1010133D01*
X230600Y1011200D01*
Y1012133D01*
X230800Y1012933D01*
X231200Y1013867D01*
X231800Y1014667D01*
X232400Y1015200D01*
X233200Y1015600D01*
X233900D01*
X234700Y1015333D01*
X235300Y1014800D01*
G01X246700Y1007600D02*
X249200Y1015600D01*
X251700Y1007600D01*
G01X250800Y1010400D02*
X247600D01*
G01X254900Y1007600D02*
Y1015600D01*
X259500Y1007600D01*
Y1015600D01*
G01X263000Y1007600D02*
Y1015600D01*
X265000D01*
X265800Y1015200D01*
X266400Y1014667D01*
X266900Y1013867D01*
X267300Y1012933D01*
X267400Y1011600D01*
X267300Y1010267D01*
X266900Y1009333D01*
X266400Y1008533D01*
X265800Y1008000D01*
X265000Y1007600D01*
X263000D01*
G01X281200D02*
X280400Y1007733D01*
X279700Y1008267D01*
X279100Y1009067D01*
X278700Y1010000D01*
X278500Y1011067D01*
Y1012133D01*
X278700Y1013200D01*
X279100Y1014133D01*
X279700Y1014933D01*
X280400Y1015467D01*
X281200Y1015600D01*
X282000Y1015467D01*
X282700Y1014933D01*
X283300Y1014133D01*
X283700Y1013200D01*
X283900Y1012133D01*
Y1011067D01*
X283700Y1010000D01*
X283300Y1009067D01*
X282700Y1008267D01*
X282000Y1007733D01*
X281200Y1007600D01*
G01X289200Y1015600D02*
Y1007600D01*
G01X286900Y1015600D02*
X291500D01*
G01X295100Y1007600D02*
Y1015600D01*
G01X299300D02*
Y1007600D01*
G01Y1011600D02*
X295100D01*
G01X307200Y1007600D02*
X303200D01*
Y1015600D01*
X307200D01*
G01X305600Y1011733D02*
X303200D01*
G01X311200Y1007600D02*
Y1015600D01*
X313700D01*
X314500Y1015200D01*
X315000Y1014667D01*
X315200Y1013600D01*
X315000Y1012533D01*
X314400Y1011867D01*
X313700Y1011467D01*
X311200D01*
G01X313700D02*
X315200Y1007600D01*
G01X327100Y1008666D02*
X327900Y1008000D01*
X328800Y1007600D01*
X329600D01*
X330400Y1008000D01*
X331000Y1008666D01*
X331300Y1009600D01*
X331100Y1010533D01*
X330600Y1011333D01*
X329700Y1011867D01*
X328500Y1012133D01*
X327800Y1012667D01*
X327500Y1013600D01*
X327700Y1014533D01*
X328200Y1015200D01*
X328900Y1015600D01*
X329600D01*
X330300Y1015333D01*
X330900Y1014667D01*
G01X335000Y1015600D02*
Y1009867D01*
X335400Y1008666D01*
X336200Y1007867D01*
X337200Y1007600D01*
X338200Y1007867D01*
X339000Y1008666D01*
X339400Y1009867D01*
Y1015600D01*
G01X346000Y1011867D02*
X346400Y1012267D01*
X346700Y1012933D01*
X346900Y1013867D01*
X346700Y1014667D01*
X346300Y1015200D01*
X345600Y1015600D01*
X342900D01*
Y1007600D01*
X346200D01*
X346900Y1008133D01*
X347300Y1008933D01*
X347500Y1009867D01*
X347300Y1010800D01*
X346700Y1011600D01*
X346000Y1011867D01*
X342900D01*
G01X351100Y1008666D02*
X351900Y1008000D01*
X352800Y1007600D01*
X353600D01*
X354400Y1008000D01*
X355000Y1008666D01*
X355300Y1009600D01*
X355100Y1010533D01*
X354600Y1011333D01*
X353700Y1011867D01*
X352500Y1012133D01*
X351800Y1012667D01*
X351500Y1013600D01*
X351700Y1014533D01*
X352200Y1015200D01*
X352900Y1015600D01*
X353600D01*
X354300Y1015333D01*
X354900Y1014667D01*
G01X363200Y1007600D02*
X359200D01*
Y1015600D01*
X363200D01*
G01X361600Y1011733D02*
X359200D01*
G01X369200Y1007600D02*
X368400Y1007733D01*
X367700Y1008267D01*
X367100Y1009067D01*
X366700Y1010000D01*
X366500Y1011067D01*
Y1012133D01*
X366700Y1013200D01*
X367100Y1014133D01*
X367700Y1014933D01*
X368400Y1015467D01*
X369200Y1015600D01*
X370000Y1015467D01*
X370700Y1014933D01*
X371300Y1014133D01*
X371700Y1013200D01*
X371900Y1012133D01*
Y1011067D01*
X371700Y1010000D01*
X371300Y1009067D01*
X370700Y1008267D01*
X370000Y1007733D01*
X369200Y1007600D01*
G01X370000Y1009733D02*
X371200Y1007600D01*
G01X375000Y1015600D02*
Y1009867D01*
X375400Y1008666D01*
X376200Y1007867D01*
X377200Y1007600D01*
X378200Y1007867D01*
X379000Y1008666D01*
X379400Y1009867D01*
Y1015600D01*
G01X387200Y1007600D02*
X383200D01*
Y1015600D01*
X387200D01*
G01X385600Y1011733D02*
X383200D01*
G01X390900Y1007600D02*
Y1015600D01*
X395500Y1007600D01*
Y1015600D01*
G01X401200D02*
Y1007600D01*
G01X398900Y1015600D02*
X403500D01*
G01X419400Y1014933D02*
X418800Y1015333D01*
X418100Y1015600D01*
X417300D01*
X416400Y1015200D01*
X415700Y1014533D01*
X415200Y1013733D01*
X414800Y1012400D01*
X414700Y1011200D01*
X414900Y1010000D01*
X415200Y1009200D01*
X415800Y1008400D01*
X416500Y1007867D01*
X417200Y1007600D01*
X417900D01*
X418600Y1007867D01*
X419200Y1008267D01*
X419700Y1008800D01*
G01X423100Y1007600D02*
Y1015600D01*
G01X427300D02*
Y1007600D01*
G01Y1011600D02*
X423100D01*
G01X430700Y1007600D02*
X433200Y1015600D01*
X435700Y1007600D01*
G01X434800Y1010400D02*
X431600D01*
G01X438900Y1007600D02*
Y1015600D01*
X443500Y1007600D01*
Y1015600D01*
G01X449800Y1011600D02*
X451800D01*
Y1009200D01*
X451200Y1008400D01*
X450500Y1007867D01*
X449500Y1007600D01*
X448500Y1007867D01*
X447800Y1008400D01*
X447200Y1009200D01*
X446800Y1010133D01*
X446600Y1011200D01*
Y1012133D01*
X446800Y1012933D01*
X447200Y1013867D01*
X447800Y1014667D01*
X448400Y1015200D01*
X449200Y1015600D01*
X449900D01*
X450700Y1015333D01*
X451300Y1014800D01*
G01X459200Y1007600D02*
X455200D01*
Y1015600D01*
X459200D01*
G01X457600Y1011733D02*
X455200D01*
G01X463100Y1008666D02*
X463900Y1008000D01*
X464800Y1007600D01*
X465600D01*
X466400Y1008000D01*
X467000Y1008666D01*
X467300Y1009600D01*
X467100Y1010533D01*
X466600Y1011333D01*
X465700Y1011867D01*
X464500Y1012133D01*
X463800Y1012667D01*
X463500Y1013600D01*
X463700Y1014533D01*
X464200Y1015200D01*
X464900Y1015600D01*
X465600D01*
X466300Y1015333D01*
X466900Y1014667D01*
G01X478600Y1007600D02*
Y1015600D01*
X481200Y1008933D01*
X483800Y1015600D01*
Y1007600D01*
G01X487000Y1015600D02*
Y1009867D01*
X487400Y1008666D01*
X488200Y1007867D01*
X489200Y1007600D01*
X490200Y1007867D01*
X491000Y1008666D01*
X491400Y1009867D01*
Y1015600D01*
G01X495100Y1008666D02*
X495900Y1008000D01*
X496800Y1007600D01*
X497600D01*
X498400Y1008000D01*
X499000Y1008666D01*
X499300Y1009600D01*
X499100Y1010533D01*
X498600Y1011333D01*
X497700Y1011867D01*
X496500Y1012133D01*
X495800Y1012667D01*
X495500Y1013600D01*
X495700Y1014533D01*
X496200Y1015200D01*
X496900Y1015600D01*
X497600D01*
X498300Y1015333D01*
X498900Y1014667D01*
G01X505200Y1015600D02*
Y1007600D01*
G01X502900Y1015600D02*
X507500D01*
G01X522000Y1011867D02*
X522400Y1012267D01*
X522700Y1012933D01*
X522900Y1013867D01*
X522700Y1014667D01*
X522300Y1015200D01*
X521600Y1015600D01*
X518900D01*
Y1007600D01*
X522200D01*
X522900Y1008133D01*
X523300Y1008933D01*
X523500Y1009867D01*
X523300Y1010800D01*
X522700Y1011600D01*
X522000Y1011867D01*
X518900D01*
G01X531200Y1007600D02*
X527200D01*
Y1015600D01*
X531200D01*
G01X529600Y1011733D02*
X527200D01*
G01X542700Y1007600D02*
X545200Y1015600D01*
X547700Y1007600D01*
G01X546800Y1010400D02*
X543600D01*
G01X551200Y1007600D02*
Y1015600D01*
X553600D01*
X554400Y1015200D01*
X555000Y1014267D01*
X555200Y1013200D01*
X555000Y1012133D01*
X554500Y1011333D01*
X553600Y1010933D01*
X551200D01*
G01X559200Y1007600D02*
Y1015600D01*
X561600D01*
X562400Y1015200D01*
X563000Y1014267D01*
X563200Y1013200D01*
X563000Y1012133D01*
X562500Y1011333D01*
X561600Y1010933D01*
X559200D01*
G01X567200Y1007600D02*
Y1015600D01*
X569700D01*
X570500Y1015200D01*
X571000Y1014667D01*
X571200Y1013600D01*
X571000Y1012533D01*
X570400Y1011867D01*
X569700Y1011467D01*
X567200D01*
G01X569700D02*
X571200Y1007600D01*
G01X577200D02*
X576400Y1007733D01*
X575700Y1008267D01*
X575100Y1009067D01*
X574700Y1010000D01*
X574500Y1011067D01*
Y1012133D01*
X574700Y1013200D01*
X575100Y1014133D01*
X575700Y1014933D01*
X576400Y1015467D01*
X577200Y1015600D01*
X578000Y1015467D01*
X578700Y1014933D01*
X579300Y1014133D01*
X579700Y1013200D01*
X579900Y1012133D01*
Y1011067D01*
X579700Y1010000D01*
X579300Y1009067D01*
X578700Y1008267D01*
X578000Y1007733D01*
X577200Y1007600D01*
G01X582700Y1015600D02*
X585200Y1007600D01*
X587700Y1015600D01*
G01X595200Y1007600D02*
X591200D01*
Y1015600D01*
X595200D01*
G01X593600Y1011733D02*
X591200D01*
G01X599000Y1007600D02*
Y1015600D01*
X601000D01*
X601800Y1015200D01*
X602400Y1014667D01*
X602900Y1013867D01*
X603300Y1012933D01*
X603400Y1011600D01*
X603300Y1010267D01*
X602900Y1009333D01*
X602400Y1008533D01*
X601800Y1008000D01*
X601000Y1007600D01*
X599000D01*
G01X618000Y1011867D02*
X618400Y1012267D01*
X618700Y1012933D01*
X618900Y1013867D01*
X618700Y1014667D01*
X618300Y1015200D01*
X617600Y1015600D01*
X614900D01*
Y1007600D01*
X618200D01*
X618900Y1008133D01*
X619300Y1008933D01*
X619500Y1009867D01*
X619300Y1010800D01*
X618700Y1011600D01*
X618000Y1011867D01*
X614900D01*
G01X625200Y1007600D02*
Y1011200D01*
X623200Y1015600D01*
G01X627200D02*
X625200Y1011200D01*
G01X175100Y1038666D02*
X175900Y1038000D01*
X176800Y1037600D01*
X177600D01*
X178400Y1038000D01*
X179000Y1038666D01*
X179300Y1039600D01*
X179100Y1040533D01*
X178600Y1041333D01*
X177700Y1041867D01*
X176500Y1042133D01*
X175800Y1042667D01*
X175500Y1043600D01*
X175700Y1044533D01*
X176200Y1045200D01*
X176900Y1045600D01*
X177600D01*
X178300Y1045333D01*
X178900Y1044667D01*
G01X183200Y1037600D02*
Y1045600D01*
X185600D01*
X186400Y1045200D01*
X187000Y1044267D01*
X187200Y1043200D01*
X187000Y1042133D01*
X186500Y1041333D01*
X185600Y1040933D01*
X183200D01*
G01X190700Y1037600D02*
X193200Y1045600D01*
X195700Y1037600D01*
G01X194800Y1040400D02*
X191600D01*
G01X203400Y1044933D02*
X202800Y1045333D01*
X202100Y1045600D01*
X201300D01*
X200400Y1045200D01*
X199700Y1044533D01*
X199200Y1043733D01*
X198800Y1042400D01*
X198700Y1041200D01*
X198900Y1040000D01*
X199200Y1039200D01*
X199800Y1038400D01*
X200500Y1037867D01*
X201200Y1037600D01*
X201900D01*
X202600Y1037867D01*
X203200Y1038267D01*
X203700Y1038800D01*
G01X208000Y1045600D02*
X210400D01*
G01X209200D02*
Y1037600D01*
G01X208000D02*
X210400D01*
G01X214900D02*
Y1045600D01*
X219500Y1037600D01*
Y1045600D01*
G01X225800Y1041600D02*
X227800D01*
Y1039200D01*
X227200Y1038400D01*
X226500Y1037867D01*
X225500Y1037600D01*
X224500Y1037867D01*
X223800Y1038400D01*
X223200Y1039200D01*
X222800Y1040133D01*
X222600Y1041200D01*
Y1042133D01*
X222800Y1042933D01*
X223200Y1043867D01*
X223800Y1044667D01*
X224400Y1045200D01*
X225200Y1045600D01*
X225900D01*
X226700Y1045333D01*
X227300Y1044800D01*
G01X238700Y1037600D02*
X241200Y1045600D01*
X243700Y1037600D01*
G01X242800Y1040400D02*
X239600D01*
G01X246900Y1037600D02*
Y1045600D01*
X251500Y1037600D01*
Y1045600D01*
G01X255000Y1037600D02*
Y1045600D01*
X257000D01*
X257800Y1045200D01*
X258400Y1044667D01*
X258900Y1043867D01*
X259300Y1042933D01*
X259400Y1041600D01*
X259300Y1040267D01*
X258900Y1039333D01*
X258400Y1038533D01*
X257800Y1038000D01*
X257000Y1037600D01*
X255000D01*
G01X270600D02*
Y1045600D01*
X273200Y1038933D01*
X275800Y1045600D01*
Y1037600D01*
G01X278700D02*
X281200Y1045600D01*
X283700Y1037600D01*
G01X282800Y1040400D02*
X279600D01*
G01X289200Y1045600D02*
Y1037600D01*
G01X286900Y1045600D02*
X291500D01*
G01X299200Y1037600D02*
X295200D01*
Y1045600D01*
X299200D01*
G01X297600Y1041733D02*
X295200D01*
G01X303200Y1037600D02*
Y1045600D01*
X305700D01*
X306500Y1045200D01*
X307000Y1044667D01*
X307200Y1043600D01*
X307000Y1042533D01*
X306400Y1041867D01*
X305700Y1041467D01*
X303200D01*
G01X305700D02*
X307200Y1037600D01*
G01X312000Y1045600D02*
X314400D01*
G01X313200D02*
Y1037600D01*
G01X312000D02*
X314400D01*
G01X318700D02*
X321200Y1045600D01*
X323700Y1037600D01*
G01X322800Y1040400D02*
X319600D01*
G01X327200Y1045600D02*
Y1037600D01*
X331200D01*
G01X343000D02*
Y1045600D01*
X345000D01*
X345800Y1045200D01*
X346400Y1044667D01*
X346900Y1043867D01*
X347300Y1042933D01*
X347400Y1041600D01*
X347300Y1040267D01*
X346900Y1039333D01*
X346400Y1038533D01*
X345800Y1038000D01*
X345000Y1037600D01*
X343000D01*
G01X352000Y1045600D02*
X354400D01*
G01X353200D02*
Y1037600D01*
G01X352000D02*
X354400D01*
G01X363200D02*
X359200D01*
Y1045600D01*
X363200D01*
G01X361600Y1041733D02*
X359200D01*
G01X367200Y1045600D02*
Y1037600D01*
X371200D01*
G01X379200D02*
X375200D01*
Y1045600D01*
X379200D01*
G01X377600Y1041733D02*
X375200D01*
G01X387400Y1044933D02*
X386800Y1045333D01*
X386100Y1045600D01*
X385300D01*
X384400Y1045200D01*
X383700Y1044533D01*
X383200Y1043733D01*
X382800Y1042400D01*
X382700Y1041200D01*
X382900Y1040000D01*
X383200Y1039200D01*
X383800Y1038400D01*
X384500Y1037867D01*
X385200Y1037600D01*
X385900D01*
X386600Y1037867D01*
X387200Y1038267D01*
X387700Y1038800D01*
G01X393200Y1045600D02*
Y1037600D01*
G01X390900Y1045600D02*
X395500D01*
G01X399200Y1037600D02*
Y1045600D01*
X401700D01*
X402500Y1045200D01*
X403000Y1044667D01*
X403200Y1043600D01*
X403000Y1042533D01*
X402400Y1041867D01*
X401700Y1041467D01*
X399200D01*
G01X401700D02*
X403200Y1037600D01*
G01X408000Y1045600D02*
X410400D01*
G01X409200D02*
Y1037600D01*
G01X408000D02*
X410400D01*
G01X419400Y1044933D02*
X418800Y1045333D01*
X418100Y1045600D01*
X417300D01*
X416400Y1045200D01*
X415700Y1044533D01*
X415200Y1043733D01*
X414800Y1042400D01*
X414700Y1041200D01*
X414900Y1040000D01*
X415200Y1039200D01*
X415800Y1038400D01*
X416500Y1037867D01*
X417200Y1037600D01*
X417900D01*
X418600Y1037867D01*
X419200Y1038267D01*
X419700Y1038800D01*
G01X435400Y1044933D02*
X434800Y1045333D01*
X434100Y1045600D01*
X433300D01*
X432400Y1045200D01*
X431700Y1044533D01*
X431200Y1043733D01*
X430800Y1042400D01*
X430700Y1041200D01*
X430900Y1040000D01*
X431200Y1039200D01*
X431800Y1038400D01*
X432500Y1037867D01*
X433200Y1037600D01*
X433900D01*
X434600Y1037867D01*
X435200Y1038267D01*
X435700Y1038800D01*
G01X441200Y1037600D02*
X440400Y1037733D01*
X439700Y1038267D01*
X439100Y1039067D01*
X438700Y1040000D01*
X438500Y1041067D01*
Y1042133D01*
X438700Y1043200D01*
X439100Y1044133D01*
X439700Y1044933D01*
X440400Y1045467D01*
X441200Y1045600D01*
X442000Y1045467D01*
X442700Y1044933D01*
X443300Y1044133D01*
X443700Y1043200D01*
X443900Y1042133D01*
Y1041067D01*
X443700Y1040000D01*
X443300Y1039067D01*
X442700Y1038267D01*
X442000Y1037733D01*
X441200Y1037600D01*
G01X446900D02*
Y1045600D01*
X451500Y1037600D01*
Y1045600D01*
G01X455100Y1038666D02*
X455900Y1038000D01*
X456800Y1037600D01*
X457600D01*
X458400Y1038000D01*
X459000Y1038666D01*
X459300Y1039600D01*
X459100Y1040533D01*
X458600Y1041333D01*
X457700Y1041867D01*
X456500Y1042133D01*
X455800Y1042667D01*
X455500Y1043600D01*
X455700Y1044533D01*
X456200Y1045200D01*
X456900Y1045600D01*
X457600D01*
X458300Y1045333D01*
X458900Y1044667D01*
G01X465200Y1045600D02*
Y1037600D01*
G01X462900Y1045600D02*
X467500D01*
G01X470700Y1037600D02*
X473200Y1045600D01*
X475700Y1037600D01*
G01X474800Y1040400D02*
X471600D01*
G01X478900Y1037600D02*
Y1045600D01*
X483500Y1037600D01*
Y1045600D01*
G01X489200D02*
Y1037600D01*
G01X486900Y1045600D02*
X491500D01*
G01X505200D02*
Y1037600D01*
G01X502900Y1045600D02*
X507500D01*
G01X513200Y1037600D02*
X512400Y1037733D01*
X511700Y1038267D01*
X511100Y1039067D01*
X510700Y1040000D01*
X510500Y1041067D01*
Y1042133D01*
X510700Y1043200D01*
X511100Y1044133D01*
X511700Y1044933D01*
X512400Y1045467D01*
X513200Y1045600D01*
X514000Y1045467D01*
X514700Y1044933D01*
X515300Y1044133D01*
X515700Y1043200D01*
X515900Y1042133D01*
Y1041067D01*
X515700Y1040000D01*
X515300Y1039067D01*
X514700Y1038267D01*
X514000Y1037733D01*
X513200Y1037600D01*
G01X526700D02*
X529200Y1045600D01*
X531700Y1037600D01*
G01X530800Y1040400D02*
X527600D01*
G01X539400Y1044933D02*
X538800Y1045333D01*
X538100Y1045600D01*
X537300D01*
X536400Y1045200D01*
X535700Y1044533D01*
X535200Y1043733D01*
X534800Y1042400D01*
X534700Y1041200D01*
X534900Y1040000D01*
X535200Y1039200D01*
X535800Y1038400D01*
X536500Y1037867D01*
X537200Y1037600D01*
X537900D01*
X538600Y1037867D01*
X539200Y1038267D01*
X539700Y1038800D01*
G01X543100Y1037600D02*
Y1045600D01*
G01X547300D02*
Y1037600D01*
G01Y1041600D02*
X543100D01*
G01X552000Y1045600D02*
X554400D01*
G01X553200D02*
Y1037600D01*
G01X552000D02*
X554400D01*
G01X563200D02*
X559200D01*
Y1045600D01*
X563200D01*
G01X561600Y1041733D02*
X559200D01*
G01X566700Y1045600D02*
X569200Y1037600D01*
X571700Y1045600D01*
G01X579200Y1037600D02*
X575200D01*
Y1045600D01*
X579200D01*
G01X577600Y1041733D02*
X575200D01*
G01X591200Y1037600D02*
Y1045600D01*
X593700D01*
X594500Y1045200D01*
X595000Y1044667D01*
X595200Y1043600D01*
X595000Y1042533D01*
X594400Y1041867D01*
X593700Y1041467D01*
X591200D01*
G01X593700D02*
X595200Y1037600D01*
G01X603200D02*
X599200D01*
Y1045600D01*
X603200D01*
G01X601600Y1041733D02*
X599200D01*
G01X609200Y1037600D02*
X608400Y1037733D01*
X607700Y1038267D01*
X607100Y1039067D01*
X606700Y1040000D01*
X606500Y1041067D01*
Y1042133D01*
X606700Y1043200D01*
X607100Y1044133D01*
X607700Y1044933D01*
X608400Y1045467D01*
X609200Y1045600D01*
X610000Y1045467D01*
X610700Y1044933D01*
X611300Y1044133D01*
X611700Y1043200D01*
X611900Y1042133D01*
Y1041067D01*
X611700Y1040000D01*
X611300Y1039067D01*
X610700Y1038267D01*
X610000Y1037733D01*
X609200Y1037600D01*
G01X610000Y1039733D02*
X611200Y1037600D01*
G01X615000Y1045600D02*
Y1039867D01*
X615400Y1038666D01*
X616200Y1037867D01*
X617200Y1037600D01*
X618200Y1037867D01*
X619000Y1038666D01*
X619400Y1039867D01*
Y1045600D01*
G01X624000D02*
X626400D01*
G01X625200D02*
Y1037600D01*
G01X624000D02*
X626400D01*
G01X631200D02*
Y1045600D01*
X633700D01*
X634500Y1045200D01*
X635000Y1044667D01*
X635200Y1043600D01*
X635000Y1042533D01*
X634400Y1041867D01*
X633700Y1041467D01*
X631200D01*
G01X633700D02*
X635200Y1037600D01*
G01X643200D02*
X639200D01*
Y1045600D01*
X643200D01*
G01X641600Y1041733D02*
X639200D01*
G01X647000Y1037600D02*
Y1045600D01*
X649000D01*
X649800Y1045200D01*
X650400Y1044667D01*
X650900Y1043867D01*
X651300Y1042933D01*
X651400Y1041600D01*
X651300Y1040267D01*
X650900Y1039333D01*
X650400Y1038533D01*
X649800Y1038000D01*
X649000Y1037600D01*
X647000D01*
G01X179400Y1059933D02*
X178800Y1060333D01*
X178100Y1060600D01*
X177300D01*
X176400Y1060200D01*
X175700Y1059533D01*
X175200Y1058733D01*
X174800Y1057400D01*
X174700Y1056200D01*
X174900Y1055000D01*
X175200Y1054200D01*
X175800Y1053400D01*
X176500Y1052867D01*
X177200Y1052600D01*
X177900D01*
X178600Y1052867D01*
X179200Y1053267D01*
X179700Y1053800D01*
G01X183100Y1052600D02*
Y1060600D01*
G01X187300D02*
Y1052600D01*
G01Y1056600D02*
X183100D01*
G01X190700Y1052600D02*
X193200Y1060600D01*
X195700Y1052600D01*
G01X194800Y1055400D02*
X191600D01*
G01X199200Y1052600D02*
Y1060600D01*
X201700D01*
X202500Y1060200D01*
X203000Y1059667D01*
X203200Y1058600D01*
X203000Y1057533D01*
X202400Y1056867D01*
X201700Y1056467D01*
X199200D01*
G01X201700D02*
X203200Y1052600D01*
G01X209200Y1060600D02*
Y1052600D01*
G01X206900Y1060600D02*
X211500D01*
G01X217200Y1052333D02*
X217000Y1052467D01*
Y1052733D01*
X217200Y1052867D01*
X217400Y1052733D01*
Y1052467D01*
X217200Y1052333D01*
G01X230600Y1052600D02*
Y1060600D01*
X233200Y1053933D01*
X235800Y1060600D01*
Y1052600D01*
G01X238700D02*
X241200Y1060600D01*
X243700Y1052600D01*
G01X242800Y1055400D02*
X239600D01*
G01X246900Y1052600D02*
Y1060600D01*
X251500Y1052600D01*
Y1060600D01*
G01X255000D02*
Y1054867D01*
X255400Y1053666D01*
X256200Y1052867D01*
X257200Y1052600D01*
X258200Y1052867D01*
X259000Y1053666D01*
X259400Y1054867D01*
Y1060600D01*
G01X263300Y1052600D02*
Y1060600D01*
X267100D01*
G01X265700Y1056733D02*
X263300D01*
G01X270700Y1052600D02*
X273200Y1060600D01*
X275700Y1052600D01*
G01X274800Y1055400D02*
X271600D01*
G01X283400Y1059933D02*
X282800Y1060333D01*
X282100Y1060600D01*
X281300D01*
X280400Y1060200D01*
X279700Y1059533D01*
X279200Y1058733D01*
X278800Y1057400D01*
X278700Y1056200D01*
X278900Y1055000D01*
X279200Y1054200D01*
X279800Y1053400D01*
X280500Y1052867D01*
X281200Y1052600D01*
X281900D01*
X282600Y1052867D01*
X283200Y1053267D01*
X283700Y1053800D01*
G01X289200Y1060600D02*
Y1052600D01*
G01X286900Y1060600D02*
X291500D01*
G01X295000D02*
Y1054867D01*
X295400Y1053666D01*
X296200Y1052867D01*
X297200Y1052600D01*
X298200Y1052867D01*
X299000Y1053666D01*
X299400Y1054867D01*
Y1060600D01*
G01X303200Y1052600D02*
Y1060600D01*
X305700D01*
X306500Y1060200D01*
X307000Y1059667D01*
X307200Y1058600D01*
X307000Y1057533D01*
X306400Y1056867D01*
X305700Y1056467D01*
X303200D01*
G01X305700D02*
X307200Y1052600D01*
G01X315200D02*
X311200D01*
Y1060600D01*
X315200D01*
G01X313600Y1056733D02*
X311200D01*
G01X319200Y1052600D02*
Y1060600D01*
X321700D01*
X322500Y1060200D01*
X323000Y1059667D01*
X323200Y1058600D01*
X323000Y1057533D01*
X322400Y1056867D01*
X321700Y1056467D01*
X319200D01*
G01X321700D02*
X323200Y1052600D01*
G01X336000Y1060600D02*
X338400D01*
G01X337200D02*
Y1052600D01*
G01X336000D02*
X338400D01*
G01X343100Y1053666D02*
X343900Y1053000D01*
X344800Y1052600D01*
X345600D01*
X346400Y1053000D01*
X347000Y1053666D01*
X347300Y1054600D01*
X347100Y1055533D01*
X346600Y1056333D01*
X345700Y1056867D01*
X344500Y1057133D01*
X343800Y1057667D01*
X343500Y1058600D01*
X343700Y1059533D01*
X344200Y1060200D01*
X344900Y1060600D01*
X345600D01*
X346300Y1060333D01*
X346900Y1059667D01*
G01X359300Y1052600D02*
Y1060600D01*
X363100D01*
G01X361700Y1056733D02*
X359300D01*
G01X367200Y1052600D02*
Y1060600D01*
X369700D01*
X370500Y1060200D01*
X371000Y1059667D01*
X371200Y1058600D01*
X371000Y1057533D01*
X370400Y1056867D01*
X369700Y1056467D01*
X367200D01*
G01X369700D02*
X371200Y1052600D01*
G01X379200D02*
X375200D01*
Y1060600D01*
X379200D01*
G01X377600Y1056733D02*
X375200D01*
G01X387200Y1052600D02*
X383200D01*
Y1060600D01*
X387200D01*
G01X385600Y1056733D02*
X383200D01*
G01X401200Y1060600D02*
Y1052600D01*
G01X398900Y1060600D02*
X403500D01*
G01X409200Y1052600D02*
X408400Y1052733D01*
X407700Y1053267D01*
X407100Y1054067D01*
X406700Y1055000D01*
X406500Y1056067D01*
Y1057133D01*
X406700Y1058200D01*
X407100Y1059133D01*
X407700Y1059933D01*
X408400Y1060467D01*
X409200Y1060600D01*
X410000Y1060467D01*
X410700Y1059933D01*
X411300Y1059133D01*
X411700Y1058200D01*
X411900Y1057133D01*
Y1056067D01*
X411700Y1055000D01*
X411300Y1054067D01*
X410700Y1053267D01*
X410000Y1052733D01*
X409200Y1052600D01*
G01X422700D02*
X425200Y1060600D01*
X427700Y1052600D01*
G01X426800Y1055400D02*
X423600D01*
G01X431000Y1052600D02*
Y1060600D01*
X433000D01*
X433800Y1060200D01*
X434400Y1059667D01*
X434900Y1058867D01*
X435300Y1057933D01*
X435400Y1056600D01*
X435300Y1055267D01*
X434900Y1054333D01*
X434400Y1053533D01*
X433800Y1053000D01*
X433000Y1052600D01*
X431000D01*
G01X439200Y1054200D02*
X439700Y1053400D01*
X440300Y1052867D01*
X441000Y1052600D01*
X441800Y1052867D01*
X442400Y1053400D01*
X443000Y1054200D01*
X443200Y1055267D01*
Y1060600D01*
G01X447000D02*
Y1054867D01*
X447400Y1053666D01*
X448200Y1052867D01*
X449200Y1052600D01*
X450200Y1052867D01*
X451000Y1053666D01*
X451400Y1054867D01*
Y1060600D01*
G01X455100Y1053666D02*
X455900Y1053000D01*
X456800Y1052600D01*
X457600D01*
X458400Y1053000D01*
X459000Y1053666D01*
X459300Y1054600D01*
X459100Y1055533D01*
X458600Y1056333D01*
X457700Y1056867D01*
X456500Y1057133D01*
X455800Y1057667D01*
X455500Y1058600D01*
X455700Y1059533D01*
X456200Y1060200D01*
X456900Y1060600D01*
X457600D01*
X458300Y1060333D01*
X458900Y1059667D01*
G01X465200Y1060600D02*
Y1052600D01*
G01X462900Y1060600D02*
X467500D01*
G01X481200D02*
Y1052600D01*
G01X478900Y1060600D02*
X483500D01*
G01X487200Y1052600D02*
Y1060600D01*
X489700D01*
X490500Y1060200D01*
X491000Y1059667D01*
X491200Y1058600D01*
X491000Y1057533D01*
X490400Y1056867D01*
X489700Y1056467D01*
X487200D01*
G01X489700D02*
X491200Y1052600D01*
G01X494700D02*
X497200Y1060600D01*
X499700Y1052600D01*
G01X498800Y1055400D02*
X495600D01*
G01X507400Y1059933D02*
X506800Y1060333D01*
X506100Y1060600D01*
X505300D01*
X504400Y1060200D01*
X503700Y1059533D01*
X503200Y1058733D01*
X502800Y1057400D01*
X502700Y1056200D01*
X502900Y1055000D01*
X503200Y1054200D01*
X503800Y1053400D01*
X504500Y1052867D01*
X505200Y1052600D01*
X505900D01*
X506600Y1052867D01*
X507200Y1053267D01*
X507700Y1053800D01*
G01X515200Y1052600D02*
X511200D01*
Y1060600D01*
X515200D01*
G01X513600Y1056733D02*
X511200D01*
G01X526200Y1060600D02*
X527600Y1052600D01*
X529200Y1060600D01*
X530800Y1052600D01*
X532200Y1060600D01*
G01X536000D02*
X538400D01*
G01X537200D02*
Y1052600D01*
G01X536000D02*
X538400D01*
G01X543000D02*
Y1060600D01*
X545000D01*
X545800Y1060200D01*
X546400Y1059667D01*
X546900Y1058867D01*
X547300Y1057933D01*
X547400Y1056600D01*
X547300Y1055267D01*
X546900Y1054333D01*
X546400Y1053533D01*
X545800Y1053000D01*
X545000Y1052600D01*
X543000D01*
G01X553200Y1060600D02*
Y1052600D01*
G01X550900Y1060600D02*
X555500D01*
G01X559100Y1052600D02*
Y1060600D01*
G01X563300D02*
Y1052600D01*
G01Y1056600D02*
X559100D01*
G01X567100Y1053666D02*
X567900Y1053000D01*
X568800Y1052600D01*
X569600D01*
X570400Y1053000D01*
X571000Y1053666D01*
X571300Y1054600D01*
X571100Y1055533D01*
X570600Y1056333D01*
X569700Y1056867D01*
X568500Y1057133D01*
X567800Y1057667D01*
X567500Y1058600D01*
X567700Y1059533D01*
X568200Y1060200D01*
X568900Y1060600D01*
X569600D01*
X570300Y1060333D01*
X570900Y1059667D01*
G01X577000Y1051133D02*
X577400Y1052867D01*
G01X599000Y1052600D02*
Y1060600D01*
X601000D01*
X601800Y1060200D01*
X602400Y1059667D01*
X602900Y1058867D01*
X603300Y1057933D01*
X603400Y1056600D01*
X603300Y1055267D01*
X602900Y1054333D01*
X602400Y1053533D01*
X601800Y1053000D01*
X601000Y1052600D01*
X599000D01*
G01X608000Y1060600D02*
X610400D01*
G01X609200D02*
Y1052600D01*
G01X608000D02*
X610400D01*
G01X619200D02*
X615200D01*
Y1060600D01*
X619200D01*
G01X617600Y1056733D02*
X615200D01*
G01X623200Y1060600D02*
Y1052600D01*
X627200D01*
G01X635200D02*
X631200D01*
Y1060600D01*
X635200D01*
G01X633600Y1056733D02*
X631200D01*
G01X643400Y1059933D02*
X642800Y1060333D01*
X642100Y1060600D01*
X641300D01*
X640400Y1060200D01*
X639700Y1059533D01*
X639200Y1058733D01*
X638800Y1057400D01*
X638700Y1056200D01*
X638900Y1055000D01*
X639200Y1054200D01*
X639800Y1053400D01*
X640500Y1052867D01*
X641200Y1052600D01*
X641900D01*
X642600Y1052867D01*
X643200Y1053267D01*
X643700Y1053800D01*
G01X649200Y1060600D02*
Y1052600D01*
G01X646900Y1060600D02*
X651500D01*
G01X655200Y1052600D02*
Y1060600D01*
X657700D01*
X658500Y1060200D01*
X659000Y1059667D01*
X659200Y1058600D01*
X659000Y1057533D01*
X658400Y1056867D01*
X657700Y1056467D01*
X655200D01*
G01X657700D02*
X659200Y1052600D01*
G01X664000Y1060600D02*
X666400D01*
G01X665200D02*
Y1052600D01*
G01X664000D02*
X666400D01*
G01X675400Y1059933D02*
X674800Y1060333D01*
X674100Y1060600D01*
X673300D01*
X672400Y1060200D01*
X671700Y1059533D01*
X671200Y1058733D01*
X670800Y1057400D01*
X670700Y1056200D01*
X670900Y1055000D01*
X671200Y1054200D01*
X671800Y1053400D01*
X672500Y1052867D01*
X673200Y1052600D01*
X673900D01*
X674600Y1052867D01*
X675200Y1053267D01*
X675700Y1053800D01*
G01X180800Y1086600D02*
X182800D01*
Y1084200D01*
X182200Y1083400D01*
X181500Y1082867D01*
X180500Y1082600D01*
X179500Y1082867D01*
X178800Y1083400D01*
X178200Y1084200D01*
X177800Y1085133D01*
X177600Y1086200D01*
Y1087133D01*
X177800Y1087933D01*
X178200Y1088867D01*
X178800Y1089667D01*
X179400Y1090200D01*
X180200Y1090600D01*
X180900D01*
X181700Y1090333D01*
X182300Y1089800D01*
G01X188200Y1082333D02*
X188000Y1082467D01*
Y1082733D01*
X188200Y1082867D01*
X188400Y1082733D01*
Y1082467D01*
X188200Y1082333D01*
G01X193900Y1082600D02*
Y1090600D01*
X198500Y1082600D01*
Y1090600D01*
G01X206200Y1082600D02*
X202200D01*
Y1090600D01*
X206200D01*
G01X204600Y1086733D02*
X202200D01*
G01X214200Y1082600D02*
X210200D01*
Y1090600D01*
X214200D01*
G01X212600Y1086733D02*
X210200D01*
G01X218000Y1082600D02*
Y1090600D01*
X220000D01*
X220800Y1090200D01*
X221400Y1089667D01*
X221900Y1088867D01*
X222300Y1087933D01*
X222400Y1086600D01*
X222300Y1085267D01*
X221900Y1084333D01*
X221400Y1083533D01*
X220800Y1083000D01*
X220000Y1082600D01*
X218000D01*
G01X234000Y1090600D02*
Y1084867D01*
X234400Y1083666D01*
X235200Y1082867D01*
X236200Y1082600D01*
X237200Y1082867D01*
X238000Y1083666D01*
X238400Y1084867D01*
Y1090600D01*
G01X242200D02*
Y1082600D01*
X246200D01*
G01X257600D02*
Y1090600D01*
X260200Y1083933D01*
X262800Y1090600D01*
Y1082600D01*
G01X265700D02*
X268200Y1090600D01*
X270700Y1082600D01*
G01X269800Y1085400D02*
X266600D01*
G01X274200Y1082600D02*
Y1090600D01*
X276700D01*
X277500Y1090200D01*
X278000Y1089667D01*
X278200Y1088600D01*
X278000Y1087533D01*
X277400Y1086867D01*
X276700Y1086467D01*
X274200D01*
G01X276700D02*
X278200Y1082600D01*
G01X282000D02*
Y1090600D01*
G01X285800D02*
X282000Y1085666D01*
G01X286400Y1082600D02*
X283700Y1087933D01*
G01X297700Y1082600D02*
X300200Y1090600D01*
X302700Y1082600D01*
G01X301800Y1085400D02*
X298600D01*
G01X305900Y1082600D02*
Y1090600D01*
X310500Y1082600D01*
Y1090600D01*
G01X314000Y1082600D02*
Y1090600D01*
X316000D01*
X316800Y1090200D01*
X317400Y1089667D01*
X317900Y1088867D01*
X318300Y1087933D01*
X318400Y1086600D01*
X318300Y1085267D01*
X317900Y1084333D01*
X317400Y1083533D01*
X316800Y1083000D01*
X316000Y1082600D01*
X314000D01*
G01X330000D02*
Y1090600D01*
X332000D01*
X332800Y1090200D01*
X333400Y1089667D01*
X333900Y1088867D01*
X334300Y1087933D01*
X334400Y1086600D01*
X334300Y1085267D01*
X333900Y1084333D01*
X333400Y1083533D01*
X332800Y1083000D01*
X332000Y1082600D01*
X330000D01*
G01X337700D02*
X340200Y1090600D01*
X342700Y1082600D01*
G01X341800Y1085400D02*
X338600D01*
G01X348200Y1090600D02*
Y1082600D01*
G01X345900Y1090600D02*
X350500D01*
G01X358200Y1082600D02*
X354200D01*
Y1090600D01*
X358200D01*
G01X356600Y1086733D02*
X354200D01*
G01X374400Y1089933D02*
X373800Y1090333D01*
X373100Y1090600D01*
X372300D01*
X371400Y1090200D01*
X370700Y1089533D01*
X370200Y1088733D01*
X369800Y1087400D01*
X369700Y1086200D01*
X369900Y1085000D01*
X370200Y1084200D01*
X370800Y1083400D01*
X371500Y1082867D01*
X372200Y1082600D01*
X372900D01*
X373600Y1082867D01*
X374200Y1083267D01*
X374700Y1083800D01*
G01X380200Y1082600D02*
X379400Y1082733D01*
X378700Y1083267D01*
X378100Y1084067D01*
X377700Y1085000D01*
X377500Y1086067D01*
Y1087133D01*
X377700Y1088200D01*
X378100Y1089133D01*
X378700Y1089933D01*
X379400Y1090467D01*
X380200Y1090600D01*
X381000Y1090467D01*
X381700Y1089933D01*
X382300Y1089133D01*
X382700Y1088200D01*
X382900Y1087133D01*
Y1086067D01*
X382700Y1085000D01*
X382300Y1084067D01*
X381700Y1083267D01*
X381000Y1082733D01*
X380200Y1082600D01*
G01X386000D02*
Y1090600D01*
X388000D01*
X388800Y1090200D01*
X389400Y1089667D01*
X389900Y1088867D01*
X390300Y1087933D01*
X390400Y1086600D01*
X390300Y1085267D01*
X389900Y1084333D01*
X389400Y1083533D01*
X388800Y1083000D01*
X388000Y1082600D01*
X386000D01*
G01X398200D02*
X394200D01*
Y1090600D01*
X398200D01*
G01X396600Y1086733D02*
X394200D01*
G01X411700Y1079933D02*
X410700Y1081267D01*
X410200Y1082600D01*
Y1087933D01*
X410700Y1089267D01*
X411700Y1090600D01*
G01X418100Y1083666D02*
X418900Y1083000D01*
X419800Y1082600D01*
X420600D01*
X421400Y1083000D01*
X422000Y1083666D01*
X422300Y1084600D01*
X422100Y1085533D01*
X421600Y1086333D01*
X420700Y1086867D01*
X419500Y1087133D01*
X418800Y1087667D01*
X418500Y1088600D01*
X418700Y1089533D01*
X419200Y1090200D01*
X419900Y1090600D01*
X420600D01*
X421300Y1090333D01*
X421900Y1089667D01*
G01X427000Y1090600D02*
X429400D01*
G01X428200D02*
Y1082600D01*
G01X427000D02*
X429400D01*
G01X434200Y1090600D02*
Y1082600D01*
X438200D01*
G01X442000D02*
Y1090600D01*
G01X445800D02*
X442000Y1085666D01*
G01X446400Y1082600D02*
X443700Y1087933D01*
G01X450100Y1083666D02*
X450900Y1083000D01*
X451800Y1082600D01*
X452600D01*
X453400Y1083000D01*
X454000Y1083666D01*
X454300Y1084600D01*
X454100Y1085533D01*
X453600Y1086333D01*
X452700Y1086867D01*
X451500Y1087133D01*
X450800Y1087667D01*
X450500Y1088600D01*
X450700Y1089533D01*
X451200Y1090200D01*
X451900Y1090600D01*
X452600D01*
X453300Y1090333D01*
X453900Y1089667D01*
G01X462400Y1089933D02*
X461800Y1090333D01*
X461100Y1090600D01*
X460300D01*
X459400Y1090200D01*
X458700Y1089533D01*
X458200Y1088733D01*
X457800Y1087400D01*
X457700Y1086200D01*
X457900Y1085000D01*
X458200Y1084200D01*
X458800Y1083400D01*
X459500Y1082867D01*
X460200Y1082600D01*
X460900D01*
X461600Y1082867D01*
X462200Y1083267D01*
X462700Y1083800D01*
G01X466200Y1082600D02*
Y1090600D01*
X468700D01*
X469500Y1090200D01*
X470000Y1089667D01*
X470200Y1088600D01*
X470000Y1087533D01*
X469400Y1086867D01*
X468700Y1086467D01*
X466200D01*
G01X468700D02*
X470200Y1082600D01*
G01X478200D02*
X474200D01*
Y1090600D01*
X478200D01*
G01X476600Y1086733D02*
X474200D01*
G01X486200Y1082600D02*
X482200D01*
Y1090600D01*
X486200D01*
G01X484600Y1086733D02*
X482200D01*
G01X489900Y1082600D02*
Y1090600D01*
X494500Y1082600D01*
Y1090600D01*
G01X500000Y1081133D02*
X500400Y1082867D01*
G01X508200Y1090600D02*
Y1082600D01*
G01X505900Y1090600D02*
X510500D01*
G01X516200Y1082600D02*
X515400Y1082733D01*
X514700Y1083267D01*
X514100Y1084067D01*
X513700Y1085000D01*
X513500Y1086067D01*
Y1087133D01*
X513700Y1088200D01*
X514100Y1089133D01*
X514700Y1089933D01*
X515400Y1090467D01*
X516200Y1090600D01*
X517000Y1090467D01*
X517700Y1089933D01*
X518300Y1089133D01*
X518700Y1088200D01*
X518900Y1087133D01*
Y1086067D01*
X518700Y1085000D01*
X518300Y1084067D01*
X517700Y1083267D01*
X517000Y1082733D01*
X516200Y1082600D01*
G01X522200D02*
Y1090600D01*
X524600D01*
X525400Y1090200D01*
X526000Y1089267D01*
X526200Y1088200D01*
X526000Y1087133D01*
X525500Y1086333D01*
X524600Y1085933D01*
X522200D01*
G01X538100Y1083666D02*
X538900Y1083000D01*
X539800Y1082600D01*
X540600D01*
X541400Y1083000D01*
X542000Y1083666D01*
X542300Y1084600D01*
X542100Y1085533D01*
X541600Y1086333D01*
X540700Y1086867D01*
X539500Y1087133D01*
X538800Y1087667D01*
X538500Y1088600D01*
X538700Y1089533D01*
X539200Y1090200D01*
X539900Y1090600D01*
X540600D01*
X541300Y1090333D01*
X541900Y1089667D01*
G01X547000Y1090600D02*
X549400D01*
G01X548200D02*
Y1082600D01*
G01X547000D02*
X549400D01*
G01X554000D02*
Y1090600D01*
X556000D01*
X556800Y1090200D01*
X557400Y1089667D01*
X557900Y1088867D01*
X558300Y1087933D01*
X558400Y1086600D01*
X558300Y1085267D01*
X557900Y1084333D01*
X557400Y1083533D01*
X556800Y1083000D01*
X556000Y1082600D01*
X554000D01*
G01X566200D02*
X562200D01*
Y1090600D01*
X566200D01*
G01X564600Y1086733D02*
X562200D01*
G01X572000Y1081133D02*
X572400Y1082867D01*
G01X585200Y1090600D02*
X586600Y1082600D01*
X588200Y1090600D01*
X589800Y1082600D01*
X591200Y1090600D01*
G01X593200D02*
X594600Y1082600D01*
X596200Y1090600D01*
X597800Y1082600D01*
X599200Y1090600D01*
G01X604200Y1082600D02*
Y1086200D01*
X602200Y1090600D01*
G01X606200D02*
X604200Y1086200D01*
G01X612200Y1082600D02*
Y1086200D01*
X610200Y1090600D01*
G01X614200D02*
X612200Y1086200D01*
G01X620700Y1079933D02*
X621700Y1081267D01*
X622200Y1082600D01*
Y1087933D01*
X621700Y1089267D01*
X620700Y1090600D01*
G01X182200Y1112600D02*
X178200D01*
Y1120600D01*
X182200D01*
G01X180600Y1116733D02*
X178200D01*
G01X188200Y1112333D02*
X188000Y1112467D01*
Y1112733D01*
X188200Y1112867D01*
X188400Y1112733D01*
Y1112467D01*
X188200Y1112333D01*
G01X194200Y1112600D02*
Y1120600D01*
X196600D01*
X197400Y1120200D01*
X198000Y1119267D01*
X198200Y1118200D01*
X198000Y1117133D01*
X197500Y1116333D01*
X196600Y1115933D01*
X194200D01*
G01X202200Y1112600D02*
Y1120600D01*
X204700D01*
X205500Y1120200D01*
X206000Y1119667D01*
X206200Y1118600D01*
X206000Y1117533D01*
X205400Y1116867D01*
X204700Y1116467D01*
X202200D01*
G01X204700D02*
X206200Y1112600D01*
G01X212200D02*
X211400Y1112733D01*
X210700Y1113267D01*
X210100Y1114067D01*
X209700Y1115000D01*
X209500Y1116067D01*
Y1117133D01*
X209700Y1118200D01*
X210100Y1119133D01*
X210700Y1119933D01*
X211400Y1120467D01*
X212200Y1120600D01*
X213000Y1120467D01*
X213700Y1119933D01*
X214300Y1119133D01*
X214700Y1118200D01*
X214900Y1117133D01*
Y1116067D01*
X214700Y1115000D01*
X214300Y1114067D01*
X213700Y1113267D01*
X213000Y1112733D01*
X212200Y1112600D01*
G01X217700Y1120600D02*
X220200Y1112600D01*
X222700Y1120600D01*
G01X227000D02*
X229400D01*
G01X228200D02*
Y1112600D01*
G01X227000D02*
X229400D01*
G01X234000D02*
Y1120600D01*
X236000D01*
X236800Y1120200D01*
X237400Y1119667D01*
X237900Y1118867D01*
X238300Y1117933D01*
X238400Y1116600D01*
X238300Y1115267D01*
X237900Y1114333D01*
X237400Y1113533D01*
X236800Y1113000D01*
X236000Y1112600D01*
X234000D01*
G01X246200D02*
X242200D01*
Y1120600D01*
X246200D01*
G01X244600Y1116733D02*
X242200D01*
G01X258200Y1112600D02*
Y1120600D01*
X260600D01*
X261400Y1120200D01*
X262000Y1119267D01*
X262200Y1118200D01*
X262000Y1117133D01*
X261500Y1116333D01*
X260600Y1115933D01*
X258200D01*
G01X270400Y1119933D02*
X269800Y1120333D01*
X269100Y1120600D01*
X268300D01*
X267400Y1120200D01*
X266700Y1119533D01*
X266200Y1118733D01*
X265800Y1117400D01*
X265700Y1116200D01*
X265900Y1115000D01*
X266200Y1114200D01*
X266800Y1113400D01*
X267500Y1112867D01*
X268200Y1112600D01*
X268900D01*
X269600Y1112867D01*
X270200Y1113267D01*
X270700Y1113800D01*
G01X277000Y1116867D02*
X277400Y1117267D01*
X277700Y1117933D01*
X277900Y1118867D01*
X277700Y1119667D01*
X277300Y1120200D01*
X276600Y1120600D01*
X273900D01*
Y1112600D01*
X277200D01*
X277900Y1113133D01*
X278300Y1113933D01*
X278500Y1114867D01*
X278300Y1115800D01*
X277700Y1116600D01*
X277000Y1116867D01*
X273900D01*
G01X290300Y1112600D02*
Y1120600D01*
X294100D01*
G01X292700Y1116733D02*
X290300D01*
G01X299000Y1120600D02*
X301400D01*
G01X300200D02*
Y1112600D01*
G01X299000D02*
X301400D01*
G01X306200Y1120600D02*
Y1112600D01*
X310200D01*
G01X313600D02*
Y1120600D01*
X316200Y1113933D01*
X318800Y1120600D01*
Y1112600D01*
G01X178300Y1097600D02*
Y1105600D01*
X182100D01*
G01X180700Y1101733D02*
X178300D01*
G01X188200Y1097333D02*
X188000Y1097467D01*
Y1097733D01*
X188200Y1097867D01*
X188400Y1097733D01*
Y1097467D01*
X188200Y1097333D01*
G01X193900Y1097600D02*
Y1105600D01*
X198500Y1097600D01*
Y1105600D01*
G01X206200Y1097600D02*
X202200D01*
Y1105600D01*
X206200D01*
G01X204600Y1101733D02*
X202200D01*
G01X214200Y1097600D02*
X210200D01*
Y1105600D01*
X214200D01*
G01X212600Y1101733D02*
X210200D01*
G01X218000Y1097600D02*
Y1105600D01*
X220000D01*
X220800Y1105200D01*
X221400Y1104667D01*
X221900Y1103867D01*
X222300Y1102933D01*
X222400Y1101600D01*
X222300Y1100267D01*
X221900Y1099333D01*
X221400Y1098533D01*
X220800Y1098000D01*
X220000Y1097600D01*
X218000D01*
G01X234200D02*
Y1105600D01*
X236600D01*
X237400Y1105200D01*
X238000Y1104267D01*
X238200Y1103200D01*
X238000Y1102133D01*
X237500Y1101333D01*
X236600Y1100933D01*
X234200D01*
G01X246400Y1104933D02*
X245800Y1105333D01*
X245100Y1105600D01*
X244300D01*
X243400Y1105200D01*
X242700Y1104533D01*
X242200Y1103733D01*
X241800Y1102400D01*
X241700Y1101200D01*
X241900Y1100000D01*
X242200Y1099200D01*
X242800Y1098400D01*
X243500Y1097867D01*
X244200Y1097600D01*
X244900D01*
X245600Y1097867D01*
X246200Y1098267D01*
X246700Y1098800D01*
G01X253000Y1101867D02*
X253400Y1102267D01*
X253700Y1102933D01*
X253900Y1103867D01*
X253700Y1104667D01*
X253300Y1105200D01*
X252600Y1105600D01*
X249900D01*
Y1097600D01*
X253200D01*
X253900Y1098133D01*
X254300Y1098933D01*
X254500Y1099867D01*
X254300Y1100800D01*
X253700Y1101600D01*
X253000Y1101867D01*
X249900D01*
G01X265600Y1097600D02*
Y1105600D01*
X268200Y1098933D01*
X270800Y1105600D01*
Y1097600D01*
G01X273700D02*
X276200Y1105600D01*
X278700Y1097600D01*
G01X277800Y1100400D02*
X274600D01*
G01X282000Y1097600D02*
Y1105600D01*
G01X285800D02*
X282000Y1100666D01*
G01X286400Y1097600D02*
X283700Y1102933D01*
G01X294200Y1097600D02*
X290200D01*
Y1105600D01*
X294200D01*
G01X292600Y1101733D02*
X290200D01*
G01X298200Y1097600D02*
Y1105600D01*
X300700D01*
X301500Y1105200D01*
X302000Y1104667D01*
X302200Y1103600D01*
X302000Y1102533D01*
X301400Y1101867D01*
X300700Y1101467D01*
X298200D01*
G01X300700D02*
X302200Y1097600D01*
G01X306100Y1098666D02*
X306900Y1098000D01*
X307800Y1097600D01*
X308600D01*
X309400Y1098000D01*
X310000Y1098666D01*
X310300Y1099600D01*
X310100Y1100533D01*
X309600Y1101333D01*
X308700Y1101867D01*
X307500Y1102133D01*
X306800Y1102667D01*
X306500Y1103600D01*
X306700Y1104533D01*
X307200Y1105200D01*
X307900Y1105600D01*
X308600D01*
X309300Y1105333D01*
X309900Y1104667D01*
G01X323700Y1094933D02*
X322700Y1096267D01*
X322200Y1097600D01*
Y1102933D01*
X322700Y1104267D01*
X323700Y1105600D01*
G01X330100Y1098666D02*
X330900Y1098000D01*
X331800Y1097600D01*
X332600D01*
X333400Y1098000D01*
X334000Y1098666D01*
X334300Y1099600D01*
X334100Y1100533D01*
X333600Y1101333D01*
X332700Y1101867D01*
X331500Y1102133D01*
X330800Y1102667D01*
X330500Y1103600D01*
X330700Y1104533D01*
X331200Y1105200D01*
X331900Y1105600D01*
X332600D01*
X333300Y1105333D01*
X333900Y1104667D01*
G01X339000Y1105600D02*
X341400D01*
G01X340200D02*
Y1097600D01*
G01X339000D02*
X341400D01*
G01X346200Y1105600D02*
Y1097600D01*
X350200D01*
G01X354000D02*
Y1105600D01*
G01X357800D02*
X354000Y1100666D01*
G01X358400Y1097600D02*
X355700Y1102933D01*
G01X362100Y1098666D02*
X362900Y1098000D01*
X363800Y1097600D01*
X364600D01*
X365400Y1098000D01*
X366000Y1098666D01*
X366300Y1099600D01*
X366100Y1100533D01*
X365600Y1101333D01*
X364700Y1101867D01*
X363500Y1102133D01*
X362800Y1102667D01*
X362500Y1103600D01*
X362700Y1104533D01*
X363200Y1105200D01*
X363900Y1105600D01*
X364600D01*
X365300Y1105333D01*
X365900Y1104667D01*
G01X374400Y1104933D02*
X373800Y1105333D01*
X373100Y1105600D01*
X372300D01*
X371400Y1105200D01*
X370700Y1104533D01*
X370200Y1103733D01*
X369800Y1102400D01*
X369700Y1101200D01*
X369900Y1100000D01*
X370200Y1099200D01*
X370800Y1098400D01*
X371500Y1097867D01*
X372200Y1097600D01*
X372900D01*
X373600Y1097867D01*
X374200Y1098267D01*
X374700Y1098800D01*
G01X378200Y1097600D02*
Y1105600D01*
X380700D01*
X381500Y1105200D01*
X382000Y1104667D01*
X382200Y1103600D01*
X382000Y1102533D01*
X381400Y1101867D01*
X380700Y1101467D01*
X378200D01*
G01X380700D02*
X382200Y1097600D01*
G01X390200D02*
X386200D01*
Y1105600D01*
X390200D01*
G01X388600Y1101733D02*
X386200D01*
G01X398200Y1097600D02*
X394200D01*
Y1105600D01*
X398200D01*
G01X396600Y1101733D02*
X394200D01*
G01X401900Y1097600D02*
Y1105600D01*
X406500Y1097600D01*
Y1105600D01*
G01X412200Y1097333D02*
X412000Y1097467D01*
Y1097733D01*
X412200Y1097867D01*
X412400Y1097733D01*
Y1097467D01*
X412200Y1097333D01*
G01X420200Y1105600D02*
Y1097600D01*
G01X417900Y1105600D02*
X422500D01*
G01X428200Y1097600D02*
X427400Y1097733D01*
X426700Y1098267D01*
X426100Y1099067D01*
X425700Y1100000D01*
X425500Y1101067D01*
Y1102133D01*
X425700Y1103200D01*
X426100Y1104133D01*
X426700Y1104933D01*
X427400Y1105467D01*
X428200Y1105600D01*
X429000Y1105467D01*
X429700Y1104933D01*
X430300Y1104133D01*
X430700Y1103200D01*
X430900Y1102133D01*
Y1101067D01*
X430700Y1100000D01*
X430300Y1099067D01*
X429700Y1098267D01*
X429000Y1097733D01*
X428200Y1097600D01*
G01X434200D02*
Y1105600D01*
X436600D01*
X437400Y1105200D01*
X438000Y1104267D01*
X438200Y1103200D01*
X438000Y1102133D01*
X437500Y1101333D01*
X436600Y1100933D01*
X434200D01*
G01X450100Y1098666D02*
X450900Y1098000D01*
X451800Y1097600D01*
X452600D01*
X453400Y1098000D01*
X454000Y1098666D01*
X454300Y1099600D01*
X454100Y1100533D01*
X453600Y1101333D01*
X452700Y1101867D01*
X451500Y1102133D01*
X450800Y1102667D01*
X450500Y1103600D01*
X450700Y1104533D01*
X451200Y1105200D01*
X451900Y1105600D01*
X452600D01*
X453300Y1105333D01*
X453900Y1104667D01*
G01X459000Y1105600D02*
X461400D01*
G01X460200D02*
Y1097600D01*
G01X459000D02*
X461400D01*
G01X466000D02*
Y1105600D01*
X468000D01*
X468800Y1105200D01*
X469400Y1104667D01*
X469900Y1103867D01*
X470300Y1102933D01*
X470400Y1101600D01*
X470300Y1100267D01*
X469900Y1099333D01*
X469400Y1098533D01*
X468800Y1098000D01*
X468000Y1097600D01*
X466000D01*
G01X478200D02*
X474200D01*
Y1105600D01*
X478200D01*
G01X476600Y1101733D02*
X474200D01*
G01X484700Y1094933D02*
X485700Y1096267D01*
X486200Y1097600D01*
Y1102933D01*
X485700Y1104267D01*
X484700Y1105600D01*
G01X178000Y1127600D02*
Y1135600D01*
X180000D01*
X180800Y1135200D01*
X181400Y1134667D01*
X181900Y1133867D01*
X182300Y1132933D01*
X182400Y1131600D01*
X182300Y1130267D01*
X181900Y1129333D01*
X181400Y1128533D01*
X180800Y1128000D01*
X180000Y1127600D01*
X178000D01*
G01X188200Y1127333D02*
X188000Y1127467D01*
Y1127733D01*
X188200Y1127867D01*
X188400Y1127733D01*
Y1127467D01*
X188200Y1127333D01*
G01X194200Y1127600D02*
Y1135600D01*
X196600D01*
X197400Y1135200D01*
X198000Y1134267D01*
X198200Y1133200D01*
X198000Y1132133D01*
X197500Y1131333D01*
X196600Y1130933D01*
X194200D01*
G01X202200Y1127600D02*
Y1135600D01*
X204700D01*
X205500Y1135200D01*
X206000Y1134667D01*
X206200Y1133600D01*
X206000Y1132533D01*
X205400Y1131867D01*
X204700Y1131467D01*
X202200D01*
G01X204700D02*
X206200Y1127600D01*
G01X212200D02*
X211400Y1127733D01*
X210700Y1128267D01*
X210100Y1129067D01*
X209700Y1130000D01*
X209500Y1131067D01*
Y1132133D01*
X209700Y1133200D01*
X210100Y1134133D01*
X210700Y1134933D01*
X211400Y1135467D01*
X212200Y1135600D01*
X213000Y1135467D01*
X213700Y1134933D01*
X214300Y1134133D01*
X214700Y1133200D01*
X214900Y1132133D01*
Y1131067D01*
X214700Y1130000D01*
X214300Y1129067D01*
X213700Y1128267D01*
X213000Y1127733D01*
X212200Y1127600D01*
G01X217700Y1135600D02*
X220200Y1127600D01*
X222700Y1135600D01*
G01X227000D02*
X229400D01*
G01X228200D02*
Y1127600D01*
G01X227000D02*
X229400D01*
G01X234000D02*
Y1135600D01*
X236000D01*
X236800Y1135200D01*
X237400Y1134667D01*
X237900Y1133867D01*
X238300Y1132933D01*
X238400Y1131600D01*
X238300Y1130267D01*
X237900Y1129333D01*
X237400Y1128533D01*
X236800Y1128000D01*
X236000Y1127600D01*
X234000D01*
G01X246200D02*
X242200D01*
Y1135600D01*
X246200D01*
G01X244600Y1131733D02*
X242200D01*
G01X259000Y1135600D02*
X261400D01*
G01X260200D02*
Y1127600D01*
G01X259000D02*
X261400D01*
G01X265600D02*
Y1135600D01*
X268200Y1128933D01*
X270800Y1135600D01*
Y1127600D01*
G01X274200D02*
Y1135600D01*
X276600D01*
X277400Y1135200D01*
X278000Y1134267D01*
X278200Y1133200D01*
X278000Y1132133D01*
X277500Y1131333D01*
X276600Y1130933D01*
X274200D01*
G01X286200Y1127600D02*
X282200D01*
Y1135600D01*
X286200D01*
G01X284600Y1131733D02*
X282200D01*
G01X290000Y1127600D02*
Y1135600D01*
X292000D01*
X292800Y1135200D01*
X293400Y1134667D01*
X293900Y1133867D01*
X294300Y1132933D01*
X294400Y1131600D01*
X294300Y1130267D01*
X293900Y1129333D01*
X293400Y1128533D01*
X292800Y1128000D01*
X292000Y1127600D01*
X290000D01*
G01X297700D02*
X300200Y1135600D01*
X302700Y1127600D01*
G01X301800Y1130400D02*
X298600D01*
G01X305900Y1127600D02*
Y1135600D01*
X310500Y1127600D01*
Y1135600D01*
G01X318400Y1134933D02*
X317800Y1135333D01*
X317100Y1135600D01*
X316300D01*
X315400Y1135200D01*
X314700Y1134533D01*
X314200Y1133733D01*
X313800Y1132400D01*
X313700Y1131200D01*
X313900Y1130000D01*
X314200Y1129200D01*
X314800Y1128400D01*
X315500Y1127867D01*
X316200Y1127600D01*
X316900D01*
X317600Y1127867D01*
X318200Y1128267D01*
X318700Y1128800D01*
G01X326200Y1127600D02*
X322200D01*
Y1135600D01*
X326200D01*
G01X324600Y1131733D02*
X322200D01*
G01X342400Y1134933D02*
X341800Y1135333D01*
X341100Y1135600D01*
X340300D01*
X339400Y1135200D01*
X338700Y1134533D01*
X338200Y1133733D01*
X337800Y1132400D01*
X337700Y1131200D01*
X337900Y1130000D01*
X338200Y1129200D01*
X338800Y1128400D01*
X339500Y1127867D01*
X340200Y1127600D01*
X340900D01*
X341600Y1127867D01*
X342200Y1128267D01*
X342700Y1128800D01*
G01X348200Y1127600D02*
X347400Y1127733D01*
X346700Y1128267D01*
X346100Y1129067D01*
X345700Y1130000D01*
X345500Y1131067D01*
Y1132133D01*
X345700Y1133200D01*
X346100Y1134133D01*
X346700Y1134933D01*
X347400Y1135467D01*
X348200Y1135600D01*
X349000Y1135467D01*
X349700Y1134933D01*
X350300Y1134133D01*
X350700Y1133200D01*
X350900Y1132133D01*
Y1131067D01*
X350700Y1130000D01*
X350300Y1129067D01*
X349700Y1128267D01*
X349000Y1127733D01*
X348200Y1127600D01*
G01X354000Y1135600D02*
Y1129867D01*
X354400Y1128666D01*
X355200Y1127867D01*
X356200Y1127600D01*
X357200Y1127867D01*
X358000Y1128666D01*
X358400Y1129867D01*
Y1135600D01*
G01X362200Y1127600D02*
Y1135600D01*
X364600D01*
X365400Y1135200D01*
X366000Y1134267D01*
X366200Y1133200D01*
X366000Y1132133D01*
X365500Y1131333D01*
X364600Y1130933D01*
X362200D01*
G01X372200Y1127600D02*
X371400Y1127733D01*
X370700Y1128267D01*
X370100Y1129067D01*
X369700Y1130000D01*
X369500Y1131067D01*
Y1132133D01*
X369700Y1133200D01*
X370100Y1134133D01*
X370700Y1134933D01*
X371400Y1135467D01*
X372200Y1135600D01*
X373000Y1135467D01*
X373700Y1134933D01*
X374300Y1134133D01*
X374700Y1133200D01*
X374900Y1132133D01*
Y1131067D01*
X374700Y1130000D01*
X374300Y1129067D01*
X373700Y1128267D01*
X373000Y1127733D01*
X372200Y1127600D01*
G01X377900D02*
Y1135600D01*
X382500Y1127600D01*
Y1135600D01*
G01X393700Y1127600D02*
X396200Y1135600D01*
X398700Y1127600D01*
G01X397800Y1130400D02*
X394600D01*
G01X401900Y1127600D02*
Y1135600D01*
X406500Y1127600D01*
Y1135600D01*
G01X410000Y1127600D02*
Y1135600D01*
X412000D01*
X412800Y1135200D01*
X413400Y1134667D01*
X413900Y1133867D01*
X414300Y1132933D01*
X414400Y1131600D01*
X414300Y1130267D01*
X413900Y1129333D01*
X413400Y1128533D01*
X412800Y1128000D01*
X412000Y1127600D01*
X410000D01*
G01X425600D02*
Y1135600D01*
X428200Y1128933D01*
X430800Y1135600D01*
Y1127600D01*
G01X438200D02*
X434200D01*
Y1135600D01*
X438200D01*
G01X436600Y1131733D02*
X434200D01*
G01X441700Y1127600D02*
X444200Y1135600D01*
X446700Y1127600D01*
G01X445800Y1130400D02*
X442600D01*
G01X450100Y1128666D02*
X450900Y1128000D01*
X451800Y1127600D01*
X452600D01*
X453400Y1128000D01*
X454000Y1128666D01*
X454300Y1129600D01*
X454100Y1130533D01*
X453600Y1131333D01*
X452700Y1131867D01*
X451500Y1132133D01*
X450800Y1132667D01*
X450500Y1133600D01*
X450700Y1134533D01*
X451200Y1135200D01*
X451900Y1135600D01*
X452600D01*
X453300Y1135333D01*
X453900Y1134667D01*
G01X458000Y1135600D02*
Y1129867D01*
X458400Y1128666D01*
X459200Y1127867D01*
X460200Y1127600D01*
X461200Y1127867D01*
X462000Y1128666D01*
X462400Y1129867D01*
Y1135600D01*
G01X466200Y1127600D02*
Y1135600D01*
X468700D01*
X469500Y1135200D01*
X470000Y1134667D01*
X470200Y1133600D01*
X470000Y1132533D01*
X469400Y1131867D01*
X468700Y1131467D01*
X466200D01*
G01X468700D02*
X470200Y1127600D01*
G01X478200D02*
X474200D01*
Y1135600D01*
X478200D01*
G01X476600Y1131733D02*
X474200D01*
G01X481600Y1127600D02*
Y1135600D01*
X484200Y1128933D01*
X486800Y1135600D01*
Y1127600D01*
G01X494200D02*
X490200D01*
Y1135600D01*
X494200D01*
G01X492600Y1131733D02*
X490200D01*
G01X497900Y1127600D02*
Y1135600D01*
X502500Y1127600D01*
Y1135600D01*
G01X508200D02*
Y1127600D01*
G01X505900Y1135600D02*
X510500D01*
G01X522200Y1127600D02*
Y1135600D01*
X524700D01*
X525500Y1135200D01*
X526000Y1134667D01*
X526200Y1133600D01*
X526000Y1132533D01*
X525400Y1131867D01*
X524700Y1131467D01*
X522200D01*
G01X524700D02*
X526200Y1127600D01*
G01X534200D02*
X530200D01*
Y1135600D01*
X534200D01*
G01X532600Y1131733D02*
X530200D01*
G01X538200Y1127600D02*
Y1135600D01*
X540600D01*
X541400Y1135200D01*
X542000Y1134267D01*
X542200Y1133200D01*
X542000Y1132133D01*
X541500Y1131333D01*
X540600Y1130933D01*
X538200D01*
G01X548200Y1127600D02*
X547400Y1127733D01*
X546700Y1128267D01*
X546100Y1129067D01*
X545700Y1130000D01*
X545500Y1131067D01*
Y1132133D01*
X545700Y1133200D01*
X546100Y1134133D01*
X546700Y1134933D01*
X547400Y1135467D01*
X548200Y1135600D01*
X549000Y1135467D01*
X549700Y1134933D01*
X550300Y1134133D01*
X550700Y1133200D01*
X550900Y1132133D01*
Y1131067D01*
X550700Y1130000D01*
X550300Y1129067D01*
X549700Y1128267D01*
X549000Y1127733D01*
X548200Y1127600D01*
G01X554200D02*
Y1135600D01*
X556700D01*
X557500Y1135200D01*
X558000Y1134667D01*
X558200Y1133600D01*
X558000Y1132533D01*
X557400Y1131867D01*
X556700Y1131467D01*
X554200D01*
G01X556700D02*
X558200Y1127600D01*
G01X564200Y1135600D02*
Y1127600D01*
G01X561900Y1135600D02*
X566500D01*
G01X181000Y1161867D02*
X181400Y1162267D01*
X181700Y1162933D01*
X181900Y1163867D01*
X181700Y1164667D01*
X181300Y1165200D01*
X180600Y1165600D01*
X177900D01*
Y1157600D01*
X181200D01*
X181900Y1158133D01*
X182300Y1158933D01*
X182500Y1159867D01*
X182300Y1160800D01*
X181700Y1161600D01*
X181000Y1161867D01*
X177900D01*
G01X188200Y1157333D02*
X188000Y1157467D01*
Y1157733D01*
X188200Y1157867D01*
X188400Y1157733D01*
Y1157467D01*
X188200Y1157333D01*
G01X193700Y1157600D02*
X196200Y1165600D01*
X198700Y1157600D01*
G01X197800Y1160400D02*
X194600D01*
G01X202200Y1165600D02*
Y1157600D01*
X206200D01*
G01X210200Y1165600D02*
Y1157600D01*
X214200D01*
G01X225700Y1165600D02*
X228200Y1157600D01*
X230700Y1165600D01*
G01X235000D02*
X237400D01*
G01X236200D02*
Y1157600D01*
G01X235000D02*
X237400D01*
G01X241700D02*
X244200Y1165600D01*
X246700Y1157600D01*
G01X245800Y1160400D02*
X242600D01*
G01X250100Y1158666D02*
X250900Y1158000D01*
X251800Y1157600D01*
X252600D01*
X253400Y1158000D01*
X254000Y1158666D01*
X254300Y1159600D01*
X254100Y1160533D01*
X253600Y1161333D01*
X252700Y1161867D01*
X251500Y1162133D01*
X250800Y1162667D01*
X250500Y1163600D01*
X250700Y1164533D01*
X251200Y1165200D01*
X251900Y1165600D01*
X252600D01*
X253300Y1165333D01*
X253900Y1164667D01*
G01X266200Y1157600D02*
Y1165600D01*
X268600D01*
X269400Y1165200D01*
X270000Y1164267D01*
X270200Y1163200D01*
X270000Y1162133D01*
X269500Y1161333D01*
X268600Y1160933D01*
X266200D01*
G01X274200Y1165600D02*
Y1157600D01*
X278200D01*
G01X282000Y1165600D02*
Y1159867D01*
X282400Y1158666D01*
X283200Y1157867D01*
X284200Y1157600D01*
X285200Y1157867D01*
X286000Y1158666D01*
X286400Y1159867D01*
Y1165600D01*
G01X292800Y1161600D02*
X294800D01*
Y1159200D01*
X294200Y1158400D01*
X293500Y1157867D01*
X292500Y1157600D01*
X291500Y1157867D01*
X290800Y1158400D01*
X290200Y1159200D01*
X289800Y1160133D01*
X289600Y1161200D01*
Y1162133D01*
X289800Y1162933D01*
X290200Y1163867D01*
X290800Y1164667D01*
X291400Y1165200D01*
X292200Y1165600D01*
X292900D01*
X293700Y1165333D01*
X294300Y1164800D01*
G01X300800Y1161600D02*
X302800D01*
Y1159200D01*
X302200Y1158400D01*
X301500Y1157867D01*
X300500Y1157600D01*
X299500Y1157867D01*
X298800Y1158400D01*
X298200Y1159200D01*
X297800Y1160133D01*
X297600Y1161200D01*
Y1162133D01*
X297800Y1162933D01*
X298200Y1163867D01*
X298800Y1164667D01*
X299400Y1165200D01*
X300200Y1165600D01*
X300900D01*
X301700Y1165333D01*
X302300Y1164800D01*
G01X310200Y1157600D02*
X306200D01*
Y1165600D01*
X310200D01*
G01X308600Y1161733D02*
X306200D01*
G01X314000Y1157600D02*
Y1165600D01*
X316000D01*
X316800Y1165200D01*
X317400Y1164667D01*
X317900Y1163867D01*
X318300Y1162933D01*
X318400Y1161600D01*
X318300Y1160267D01*
X317900Y1159333D01*
X317400Y1158533D01*
X316800Y1158000D01*
X316000Y1157600D01*
X314000D01*
G01X334200D02*
X330200D01*
Y1165600D01*
X334200D01*
G01X332600Y1161733D02*
X330200D01*
G01X338100Y1157600D02*
X342300Y1165600D01*
G01X338100D02*
X342300Y1157600D01*
G01X350400Y1164933D02*
X349800Y1165333D01*
X349100Y1165600D01*
X348300D01*
X347400Y1165200D01*
X346700Y1164533D01*
X346200Y1163733D01*
X345800Y1162400D01*
X345700Y1161200D01*
X345900Y1160000D01*
X346200Y1159200D01*
X346800Y1158400D01*
X347500Y1157867D01*
X348200Y1157600D01*
X348900D01*
X349600Y1157867D01*
X350200Y1158267D01*
X350700Y1158800D01*
G01X358200Y1157600D02*
X354200D01*
Y1165600D01*
X358200D01*
G01X356600Y1161733D02*
X354200D01*
G01X362200Y1157600D02*
Y1165600D01*
X364600D01*
X365400Y1165200D01*
X366000Y1164267D01*
X366200Y1163200D01*
X366000Y1162133D01*
X365500Y1161333D01*
X364600Y1160933D01*
X362200D01*
G01X372200Y1165600D02*
Y1157600D01*
G01X369900Y1165600D02*
X374500D01*
G01X386300Y1157600D02*
Y1165600D01*
X390100D01*
G01X388700Y1161733D02*
X386300D01*
G01X396200Y1157600D02*
X395400Y1157733D01*
X394700Y1158267D01*
X394100Y1159067D01*
X393700Y1160000D01*
X393500Y1161067D01*
Y1162133D01*
X393700Y1163200D01*
X394100Y1164133D01*
X394700Y1164933D01*
X395400Y1165467D01*
X396200Y1165600D01*
X397000Y1165467D01*
X397700Y1164933D01*
X398300Y1164133D01*
X398700Y1163200D01*
X398900Y1162133D01*
Y1161067D01*
X398700Y1160000D01*
X398300Y1159067D01*
X397700Y1158267D01*
X397000Y1157733D01*
X396200Y1157600D01*
G01X402200D02*
Y1165600D01*
X404700D01*
X405500Y1165200D01*
X406000Y1164667D01*
X406200Y1163600D01*
X406000Y1162533D01*
X405400Y1161867D01*
X404700Y1161467D01*
X402200D01*
G01X404700D02*
X406200Y1157600D01*
G01X182400Y1149933D02*
X181800Y1150333D01*
X181100Y1150600D01*
X180300D01*
X179400Y1150200D01*
X178700Y1149533D01*
X178200Y1148733D01*
X177800Y1147400D01*
X177700Y1146200D01*
X177900Y1145000D01*
X178200Y1144200D01*
X178800Y1143400D01*
X179500Y1142867D01*
X180200Y1142600D01*
X180900D01*
X181600Y1142867D01*
X182200Y1143267D01*
X182700Y1143800D01*
G01X188200Y1142333D02*
X188000Y1142467D01*
Y1142733D01*
X188200Y1142867D01*
X188400Y1142733D01*
Y1142467D01*
X188200Y1142333D01*
G01X193900Y1142600D02*
Y1150600D01*
X198500Y1142600D01*
Y1150600D01*
G01X204200Y1142600D02*
X203400Y1142733D01*
X202700Y1143267D01*
X202100Y1144067D01*
X201700Y1145000D01*
X201500Y1146067D01*
Y1147133D01*
X201700Y1148200D01*
X202100Y1149133D01*
X202700Y1149933D01*
X203400Y1150467D01*
X204200Y1150600D01*
X205000Y1150467D01*
X205700Y1149933D01*
X206300Y1149133D01*
X206700Y1148200D01*
X206900Y1147133D01*
Y1146067D01*
X206700Y1145000D01*
X206300Y1144067D01*
X205700Y1143267D01*
X205000Y1142733D01*
X204200Y1142600D01*
G01X217900D02*
Y1150600D01*
X222500Y1142600D01*
Y1150600D01*
G01X230200Y1142600D02*
X226200D01*
Y1150600D01*
X230200D01*
G01X228600Y1146733D02*
X226200D01*
G01X238200Y1142600D02*
X234200D01*
Y1150600D01*
X238200D01*
G01X236600Y1146733D02*
X234200D01*
G01X242000Y1142600D02*
Y1150600D01*
X244000D01*
X244800Y1150200D01*
X245400Y1149667D01*
X245900Y1148867D01*
X246300Y1147933D01*
X246400Y1146600D01*
X246300Y1145267D01*
X245900Y1144333D01*
X245400Y1143533D01*
X244800Y1143000D01*
X244000Y1142600D01*
X242000D01*
G01X260200Y1150600D02*
Y1142600D01*
G01X257900Y1150600D02*
X262500D01*
G01X268200Y1142600D02*
X267400Y1142733D01*
X266700Y1143267D01*
X266100Y1144067D01*
X265700Y1145000D01*
X265500Y1146067D01*
Y1147133D01*
X265700Y1148200D01*
X266100Y1149133D01*
X266700Y1149933D01*
X267400Y1150467D01*
X268200Y1150600D01*
X269000Y1150467D01*
X269700Y1149933D01*
X270300Y1149133D01*
X270700Y1148200D01*
X270900Y1147133D01*
Y1146067D01*
X270700Y1145000D01*
X270300Y1144067D01*
X269700Y1143267D01*
X269000Y1142733D01*
X268200Y1142600D01*
G01X282200D02*
Y1150600D01*
X284600D01*
X285400Y1150200D01*
X286000Y1149267D01*
X286200Y1148200D01*
X286000Y1147133D01*
X285500Y1146333D01*
X284600Y1145933D01*
X282200D01*
G01X290200Y1150600D02*
Y1142600D01*
X294200D01*
G01X298000Y1150600D02*
Y1144867D01*
X298400Y1143666D01*
X299200Y1142867D01*
X300200Y1142600D01*
X301200Y1142867D01*
X302000Y1143666D01*
X302400Y1144867D01*
Y1150600D01*
G01X308800Y1146600D02*
X310800D01*
Y1144200D01*
X310200Y1143400D01*
X309500Y1142867D01*
X308500Y1142600D01*
X307500Y1142867D01*
X306800Y1143400D01*
X306200Y1144200D01*
X305800Y1145133D01*
X305600Y1146200D01*
Y1147133D01*
X305800Y1147933D01*
X306200Y1148867D01*
X306800Y1149667D01*
X307400Y1150200D01*
X308200Y1150600D01*
X308900D01*
X309700Y1150333D01*
X310300Y1149800D01*
G01X324200Y1142600D02*
X324900Y1142733D01*
X325700Y1143133D01*
X326200Y1143800D01*
X326400Y1144733D01*
X326200Y1145666D01*
X325600Y1146467D01*
X324700Y1146867D01*
X323700D01*
X323100Y1147133D01*
X322600Y1147800D01*
X322400Y1148733D01*
X322700Y1149667D01*
X323400Y1150333D01*
X324200Y1150600D01*
X325000Y1150333D01*
X325700Y1149667D01*
X326000Y1148733D01*
X325800Y1147800D01*
X325300Y1147133D01*
X324700Y1146867D01*
X323700D01*
X322800Y1146467D01*
X322200Y1145666D01*
X322000Y1144733D01*
X322200Y1143800D01*
X322700Y1143133D01*
X323500Y1142733D01*
X324200Y1142600D01*
G01X338100D02*
Y1150600D01*
G01X342300D02*
Y1142600D01*
G01Y1146600D02*
X338100D01*
G01X348200Y1142600D02*
X347400Y1142733D01*
X346700Y1143267D01*
X346100Y1144067D01*
X345700Y1145000D01*
X345500Y1146067D01*
Y1147133D01*
X345700Y1148200D01*
X346100Y1149133D01*
X346700Y1149933D01*
X347400Y1150467D01*
X348200Y1150600D01*
X349000Y1150467D01*
X349700Y1149933D01*
X350300Y1149133D01*
X350700Y1148200D01*
X350900Y1147133D01*
Y1146067D01*
X350700Y1145000D01*
X350300Y1144067D01*
X349700Y1143267D01*
X349000Y1142733D01*
X348200Y1142600D01*
G01X354200Y1150600D02*
Y1142600D01*
X358200D01*
G01X366200D02*
X362200D01*
Y1150600D01*
X366200D01*
G01X364600Y1146733D02*
X362200D01*
G01X370100Y1143666D02*
X370900Y1143000D01*
X371800Y1142600D01*
X372600D01*
X373400Y1143000D01*
X374000Y1143666D01*
X374300Y1144600D01*
X374100Y1145533D01*
X373600Y1146333D01*
X372700Y1146867D01*
X371500Y1147133D01*
X370800Y1147667D01*
X370500Y1148600D01*
X370700Y1149533D01*
X371200Y1150200D01*
X371900Y1150600D01*
X372600D01*
X373300Y1150333D01*
X373900Y1149667D01*
G01X386100Y1143666D02*
X386900Y1143000D01*
X387800Y1142600D01*
X388600D01*
X389400Y1143000D01*
X390000Y1143666D01*
X390300Y1144600D01*
X390100Y1145533D01*
X389600Y1146333D01*
X388700Y1146867D01*
X387500Y1147133D01*
X386800Y1147667D01*
X386500Y1148600D01*
X386700Y1149533D01*
X387200Y1150200D01*
X387900Y1150600D01*
X388600D01*
X389300Y1150333D01*
X389900Y1149667D01*
G01X394000Y1150600D02*
Y1144867D01*
X394400Y1143666D01*
X395200Y1142867D01*
X396200Y1142600D01*
X397200Y1142867D01*
X398000Y1143666D01*
X398400Y1144867D01*
Y1150600D01*
G01X402200Y1142600D02*
Y1150600D01*
X404700D01*
X405500Y1150200D01*
X406000Y1149667D01*
X406200Y1148600D01*
X406000Y1147533D01*
X405400Y1146867D01*
X404700Y1146467D01*
X402200D01*
G01X404700D02*
X406200Y1142600D01*
G01X410200D02*
Y1150600D01*
X412700D01*
X413500Y1150200D01*
X414000Y1149667D01*
X414200Y1148600D01*
X414000Y1147533D01*
X413400Y1146867D01*
X412700Y1146467D01*
X410200D01*
G01X412700D02*
X414200Y1142600D01*
G01X420200D02*
X419400Y1142733D01*
X418700Y1143267D01*
X418100Y1144067D01*
X417700Y1145000D01*
X417500Y1146067D01*
Y1147133D01*
X417700Y1148200D01*
X418100Y1149133D01*
X418700Y1149933D01*
X419400Y1150467D01*
X420200Y1150600D01*
X421000Y1150467D01*
X421700Y1149933D01*
X422300Y1149133D01*
X422700Y1148200D01*
X422900Y1147133D01*
Y1146067D01*
X422700Y1145000D01*
X422300Y1144067D01*
X421700Y1143267D01*
X421000Y1142733D01*
X420200Y1142600D01*
G01X426000Y1150600D02*
Y1144867D01*
X426400Y1143666D01*
X427200Y1142867D01*
X428200Y1142600D01*
X429200Y1142867D01*
X430000Y1143666D01*
X430400Y1144867D01*
Y1150600D01*
G01X433900Y1142600D02*
Y1150600D01*
X438500Y1142600D01*
Y1150600D01*
G01X442000Y1142600D02*
Y1150600D01*
X444000D01*
X444800Y1150200D01*
X445400Y1149667D01*
X445900Y1148867D01*
X446300Y1147933D01*
X446400Y1146600D01*
X446300Y1145267D01*
X445900Y1144333D01*
X445400Y1143533D01*
X444800Y1143000D01*
X444000Y1142600D01*
X442000D01*
G01X451000Y1150600D02*
X453400D01*
G01X452200D02*
Y1142600D01*
G01X451000D02*
X453400D01*
G01X457900D02*
Y1150600D01*
X462500Y1142600D01*
Y1150600D01*
G01X468800Y1146600D02*
X470800D01*
Y1144200D01*
X470200Y1143400D01*
X469500Y1142867D01*
X468500Y1142600D01*
X467500Y1142867D01*
X466800Y1143400D01*
X466200Y1144200D01*
X465800Y1145133D01*
X465600Y1146200D01*
Y1147133D01*
X465800Y1147933D01*
X466200Y1148867D01*
X466800Y1149667D01*
X467400Y1150200D01*
X468200Y1150600D01*
X468900D01*
X469700Y1150333D01*
X470300Y1149800D01*
G01X482100Y1143666D02*
X482900Y1143000D01*
X483800Y1142600D01*
X484600D01*
X485400Y1143000D01*
X486000Y1143666D01*
X486300Y1144600D01*
X486100Y1145533D01*
X485600Y1146333D01*
X484700Y1146867D01*
X483500Y1147133D01*
X482800Y1147667D01*
X482500Y1148600D01*
X482700Y1149533D01*
X483200Y1150200D01*
X483900Y1150600D01*
X484600D01*
X485300Y1150333D01*
X485900Y1149667D01*
G01X494400Y1149933D02*
X493800Y1150333D01*
X493100Y1150600D01*
X492300D01*
X491400Y1150200D01*
X490700Y1149533D01*
X490200Y1148733D01*
X489800Y1147400D01*
X489700Y1146200D01*
X489900Y1145000D01*
X490200Y1144200D01*
X490800Y1143400D01*
X491500Y1142867D01*
X492200Y1142600D01*
X492900D01*
X493600Y1142867D01*
X494200Y1143267D01*
X494700Y1143800D01*
G01X498200Y1142600D02*
Y1150600D01*
X500700D01*
X501500Y1150200D01*
X502000Y1149667D01*
X502200Y1148600D01*
X502000Y1147533D01*
X501400Y1146867D01*
X500700Y1146467D01*
X498200D01*
G01X500700D02*
X502200Y1142600D01*
G01X510200D02*
X506200D01*
Y1150600D01*
X510200D01*
G01X508600Y1146733D02*
X506200D01*
G01X513200Y1150600D02*
X514600Y1142600D01*
X516200Y1150600D01*
X517800Y1142600D01*
X519200Y1150600D01*
G01X524200Y1142333D02*
X524000Y1142467D01*
Y1142733D01*
X524200Y1142867D01*
X524400Y1142733D01*
Y1142467D01*
X524200Y1142333D01*
G01X531700Y1139933D02*
X530700Y1141267D01*
X530200Y1142600D01*
Y1147933D01*
X530700Y1149267D01*
X531700Y1150600D01*
G01X538200Y1142600D02*
Y1150600D01*
X540600D01*
X541400Y1150200D01*
X542000Y1149267D01*
X542200Y1148200D01*
X542000Y1147133D01*
X541500Y1146333D01*
X540600Y1145933D01*
X538200D01*
G01X546200Y1150600D02*
Y1142600D01*
X550200D01*
G01X558200D02*
X554200D01*
Y1150600D01*
X558200D01*
G01X556600Y1146733D02*
X554200D01*
G01X561700Y1142600D02*
X564200Y1150600D01*
X566700Y1142600D01*
G01X565800Y1145400D02*
X562600D01*
G01X570100Y1143666D02*
X570900Y1143000D01*
X571800Y1142600D01*
X572600D01*
X573400Y1143000D01*
X574000Y1143666D01*
X574300Y1144600D01*
X574100Y1145533D01*
X573600Y1146333D01*
X572700Y1146867D01*
X571500Y1147133D01*
X570800Y1147667D01*
X570500Y1148600D01*
X570700Y1149533D01*
X571200Y1150200D01*
X571900Y1150600D01*
X572600D01*
X573300Y1150333D01*
X573900Y1149667D01*
G01X582200Y1142600D02*
X578200D01*
Y1150600D01*
X582200D01*
G01X580600Y1146733D02*
X578200D01*
G01X595000Y1150600D02*
X597400D01*
G01X596200D02*
Y1142600D01*
G01X595000D02*
X597400D01*
G01X604800Y1146600D02*
X606800D01*
Y1144200D01*
X606200Y1143400D01*
X605500Y1142867D01*
X604500Y1142600D01*
X603500Y1142867D01*
X602800Y1143400D01*
X602200Y1144200D01*
X601800Y1145133D01*
X601600Y1146200D01*
Y1147133D01*
X601800Y1147933D01*
X602200Y1148867D01*
X602800Y1149667D01*
X603400Y1150200D01*
X604200Y1150600D01*
X604900D01*
X605700Y1150333D01*
X606300Y1149800D01*
G01X609900Y1142600D02*
Y1150600D01*
X614500Y1142600D01*
Y1150600D01*
G01X620200Y1142600D02*
X619400Y1142733D01*
X618700Y1143267D01*
X618100Y1144067D01*
X617700Y1145000D01*
X617500Y1146067D01*
Y1147133D01*
X617700Y1148200D01*
X618100Y1149133D01*
X618700Y1149933D01*
X619400Y1150467D01*
X620200Y1150600D01*
X621000Y1150467D01*
X621700Y1149933D01*
X622300Y1149133D01*
X622700Y1148200D01*
X622900Y1147133D01*
Y1146067D01*
X622700Y1145000D01*
X622300Y1144067D01*
X621700Y1143267D01*
X621000Y1142733D01*
X620200Y1142600D01*
G01X626200D02*
Y1150600D01*
X628700D01*
X629500Y1150200D01*
X630000Y1149667D01*
X630200Y1148600D01*
X630000Y1147533D01*
X629400Y1146867D01*
X628700Y1146467D01*
X626200D01*
G01X628700D02*
X630200Y1142600D01*
G01X638200D02*
X634200D01*
Y1150600D01*
X638200D01*
G01X636600Y1146733D02*
X634200D01*
G01X652200Y1150600D02*
Y1142600D01*
G01X649900Y1150600D02*
X654500D01*
G01X658100Y1142600D02*
Y1150600D01*
G01X662300D02*
Y1142600D01*
G01Y1146600D02*
X658100D01*
G01X667000Y1150600D02*
X669400D01*
G01X668200D02*
Y1142600D01*
G01X667000D02*
X669400D01*
G01X674100Y1143666D02*
X674900Y1143000D01*
X675800Y1142600D01*
X676600D01*
X677400Y1143000D01*
X678000Y1143666D01*
X678300Y1144600D01*
X678100Y1145533D01*
X677600Y1146333D01*
X676700Y1146867D01*
X675500Y1147133D01*
X674800Y1147667D01*
X674500Y1148600D01*
X674700Y1149533D01*
X675200Y1150200D01*
X675900Y1150600D01*
X676600D01*
X677300Y1150333D01*
X677900Y1149667D01*
G01X691000Y1150600D02*
X693400D01*
G01X692200D02*
Y1142600D01*
G01X691000D02*
X693400D01*
G01X698300D02*
Y1150600D01*
X702100D01*
G01X700700Y1146733D02*
X698300D01*
G01X713900Y1142600D02*
Y1150600D01*
X718500Y1142600D01*
Y1150600D01*
G01X724200Y1142600D02*
X723400Y1142733D01*
X722700Y1143267D01*
X722100Y1144067D01*
X721700Y1145000D01*
X721500Y1146067D01*
Y1147133D01*
X721700Y1148200D01*
X722100Y1149133D01*
X722700Y1149933D01*
X723400Y1150467D01*
X724200Y1150600D01*
X725000Y1150467D01*
X725700Y1149933D01*
X726300Y1149133D01*
X726700Y1148200D01*
X726900Y1147133D01*
Y1146067D01*
X726700Y1145000D01*
X726300Y1144067D01*
X725700Y1143267D01*
X725000Y1142733D01*
X724200Y1142600D01*
G01X740200Y1150600D02*
Y1142600D01*
G01X737900Y1150600D02*
X742500D01*
G01X746100Y1142600D02*
Y1150600D01*
G01X750300D02*
Y1142600D01*
G01Y1146600D02*
X746100D01*
G01X755000Y1150600D02*
X757400D01*
G01X756200D02*
Y1142600D01*
G01X755000D02*
X757400D01*
G01X762100Y1143666D02*
X762900Y1143000D01*
X763800Y1142600D01*
X764600D01*
X765400Y1143000D01*
X766000Y1143666D01*
X766300Y1144600D01*
X766100Y1145533D01*
X765600Y1146333D01*
X764700Y1146867D01*
X763500Y1147133D01*
X762800Y1147667D01*
X762500Y1148600D01*
X762700Y1149533D01*
X763200Y1150200D01*
X763900Y1150600D01*
X764600D01*
X765300Y1150333D01*
X765900Y1149667D01*
G01X779000Y1150600D02*
X781400D01*
G01X780200D02*
Y1142600D01*
G01X779000D02*
X781400D01*
G01X788200Y1150600D02*
Y1142600D01*
G01X785900Y1150600D02*
X790500D01*
G01X798200Y1142600D02*
X794200D01*
Y1150600D01*
X798200D01*
G01X796600Y1146733D02*
X794200D01*
G01X801600Y1142600D02*
Y1150600D01*
X804200Y1143933D01*
X806800Y1150600D01*
Y1142600D01*
G01X819000Y1150600D02*
X821400D01*
G01X820200D02*
Y1142600D01*
G01X819000D02*
X821400D01*
G01X825900D02*
Y1150600D01*
X830500Y1142600D01*
Y1150600D01*
G01X845000Y1146867D02*
X845400Y1147267D01*
X845700Y1147933D01*
X845900Y1148867D01*
X845700Y1149667D01*
X845300Y1150200D01*
X844600Y1150600D01*
X841900D01*
Y1142600D01*
X845200D01*
X845900Y1143133D01*
X846300Y1143933D01*
X846500Y1144867D01*
X846300Y1145800D01*
X845700Y1146600D01*
X845000Y1146867D01*
X841900D01*
G01X852200Y1142600D02*
X851400Y1142733D01*
X850700Y1143267D01*
X850100Y1144067D01*
X849700Y1145000D01*
X849500Y1146067D01*
Y1147133D01*
X849700Y1148200D01*
X850100Y1149133D01*
X850700Y1149933D01*
X851400Y1150467D01*
X852200Y1150600D01*
X853000Y1150467D01*
X853700Y1149933D01*
X854300Y1149133D01*
X854700Y1148200D01*
X854900Y1147133D01*
Y1146067D01*
X854700Y1145000D01*
X854300Y1144067D01*
X853700Y1143267D01*
X853000Y1142733D01*
X852200Y1142600D01*
G01X857700D02*
X860200Y1150600D01*
X862700Y1142600D01*
G01X861800Y1145400D02*
X858600D01*
G01X866200Y1142600D02*
Y1150600D01*
X868700D01*
X869500Y1150200D01*
X870000Y1149667D01*
X870200Y1148600D01*
X870000Y1147533D01*
X869400Y1146867D01*
X868700Y1146467D01*
X866200D01*
G01X868700D02*
X870200Y1142600D01*
G01X874000D02*
Y1150600D01*
X876000D01*
X876800Y1150200D01*
X877400Y1149667D01*
X877900Y1148867D01*
X878300Y1147933D01*
X878400Y1146600D01*
X878300Y1145267D01*
X877900Y1144333D01*
X877400Y1143533D01*
X876800Y1143000D01*
X876000Y1142600D01*
X874000D01*
G01X890300D02*
Y1150600D01*
X894100D01*
G01X892700Y1146733D02*
X890300D01*
G01X899000Y1150600D02*
X901400D01*
G01X900200D02*
Y1142600D01*
G01X899000D02*
X901400D01*
G01X906200Y1150600D02*
Y1142600D01*
X910200D01*
G01X918200D02*
X914200D01*
Y1150600D01*
X918200D01*
G01X916600Y1146733D02*
X914200D01*
G01X924700Y1139933D02*
X925700Y1141267D01*
X926200Y1142600D01*
Y1147933D01*
X925700Y1149267D01*
X924700Y1150600D01*
G01X177700Y1172600D02*
X180200Y1180600D01*
X182700Y1172600D01*
G01X181800Y1175400D02*
X178600D01*
G01X188200Y1172333D02*
X188000Y1172467D01*
Y1172733D01*
X188200Y1172867D01*
X188400Y1172733D01*
Y1172467D01*
X188200Y1172333D01*
G01X193700Y1180600D02*
X196200Y1172600D01*
X198700Y1180600D01*
G01X203000D02*
X205400D01*
G01X204200D02*
Y1172600D01*
G01X203000D02*
X205400D01*
G01X209700D02*
X212200Y1180600D01*
X214700Y1172600D01*
G01X213800Y1175400D02*
X210600D01*
G01X228200Y1180600D02*
Y1172600D01*
G01X225900Y1180600D02*
X230500D01*
G01X238200Y1172600D02*
X234200D01*
Y1180600D01*
X238200D01*
G01X236600Y1176733D02*
X234200D01*
G01X241700Y1172600D02*
X244200Y1180600D01*
X246700Y1172600D01*
G01X245800Y1175400D02*
X242600D01*
G01X250200Y1172600D02*
Y1180600D01*
X252700D01*
X253500Y1180200D01*
X254000Y1179667D01*
X254200Y1178600D01*
X254000Y1177533D01*
X253400Y1176867D01*
X252700Y1176467D01*
X250200D01*
G01X252700D02*
X254200Y1172600D01*
G01X266000D02*
Y1180600D01*
X268000D01*
X268800Y1180200D01*
X269400Y1179667D01*
X269900Y1178867D01*
X270300Y1177933D01*
X270400Y1176600D01*
X270300Y1175267D01*
X269900Y1174333D01*
X269400Y1173533D01*
X268800Y1173000D01*
X268000Y1172600D01*
X266000D01*
G01X274200D02*
Y1180600D01*
X276700D01*
X277500Y1180200D01*
X278000Y1179667D01*
X278200Y1178600D01*
X278000Y1177533D01*
X277400Y1176867D01*
X276700Y1176467D01*
X274200D01*
G01X276700D02*
X278200Y1172600D01*
G01X284200D02*
X283400Y1172733D01*
X282700Y1173267D01*
X282100Y1174067D01*
X281700Y1175000D01*
X281500Y1176067D01*
Y1177133D01*
X281700Y1178200D01*
X282100Y1179133D01*
X282700Y1179933D01*
X283400Y1180467D01*
X284200Y1180600D01*
X285000Y1180467D01*
X285700Y1179933D01*
X286300Y1179133D01*
X286700Y1178200D01*
X286900Y1177133D01*
Y1176067D01*
X286700Y1175000D01*
X286300Y1174067D01*
X285700Y1173267D01*
X285000Y1172733D01*
X284200Y1172600D01*
G01X290200D02*
Y1180600D01*
X292600D01*
X293400Y1180200D01*
X294000Y1179267D01*
X294200Y1178200D01*
X294000Y1177133D01*
X293500Y1176333D01*
X292600Y1175933D01*
X290200D01*
G01X307700Y1169933D02*
X306700Y1171267D01*
X306200Y1172600D01*
Y1177933D01*
X306700Y1179267D01*
X307700Y1180600D01*
G01X314300Y1172600D02*
Y1180600D01*
X318100D01*
G01X316700Y1176733D02*
X314300D01*
G01X324200Y1172600D02*
X323400Y1172733D01*
X322700Y1173267D01*
X322100Y1174067D01*
X321700Y1175000D01*
X321500Y1176067D01*
Y1177133D01*
X321700Y1178200D01*
X322100Y1179133D01*
X322700Y1179933D01*
X323400Y1180467D01*
X324200Y1180600D01*
X325000Y1180467D01*
X325700Y1179933D01*
X326300Y1179133D01*
X326700Y1178200D01*
X326900Y1177133D01*
Y1176067D01*
X326700Y1175000D01*
X326300Y1174067D01*
X325700Y1173267D01*
X325000Y1172733D01*
X324200Y1172600D01*
G01X330200D02*
Y1180600D01*
X332700D01*
X333500Y1180200D01*
X334000Y1179667D01*
X334200Y1178600D01*
X334000Y1177533D01*
X333400Y1176867D01*
X332700Y1176467D01*
X330200D01*
G01X332700D02*
X334200Y1172600D01*
G01X345700D02*
X348200Y1180600D01*
X350700Y1172600D01*
G01X349800Y1175400D02*
X346600D01*
G01X354200Y1180600D02*
Y1172600D01*
X358200D01*
G01X362200Y1180600D02*
Y1172600D01*
X366200D01*
G01X377700Y1180600D02*
X380200Y1172600D01*
X382700Y1180600D01*
G01X387000D02*
X389400D01*
G01X388200D02*
Y1172600D01*
G01X387000D02*
X389400D01*
G01X393700D02*
X396200Y1180600D01*
X398700Y1172600D01*
G01X397800Y1175400D02*
X394600D01*
G01X402100Y1173666D02*
X402900Y1173000D01*
X403800Y1172600D01*
X404600D01*
X405400Y1173000D01*
X406000Y1173666D01*
X406300Y1174600D01*
X406100Y1175533D01*
X405600Y1176333D01*
X404700Y1176867D01*
X403500Y1177133D01*
X402800Y1177667D01*
X402500Y1178600D01*
X402700Y1179533D01*
X403200Y1180200D01*
X403900Y1180600D01*
X404600D01*
X405300Y1180333D01*
X405900Y1179667D01*
G01X417700Y1172600D02*
X420200Y1180600D01*
X422700Y1172600D01*
G01X421800Y1175400D02*
X418600D01*
G01X425900Y1172600D02*
Y1180600D01*
X430500Y1172600D01*
Y1180600D01*
G01X434000Y1172600D02*
Y1180600D01*
X436000D01*
X436800Y1180200D01*
X437400Y1179667D01*
X437900Y1178867D01*
X438300Y1177933D01*
X438400Y1176600D01*
X438300Y1175267D01*
X437900Y1174333D01*
X437400Y1173533D01*
X436800Y1173000D01*
X436000Y1172600D01*
X434000D01*
G01X450200D02*
Y1180600D01*
X452600D01*
X453400Y1180200D01*
X454000Y1179267D01*
X454200Y1178200D01*
X454000Y1177133D01*
X453500Y1176333D01*
X452600Y1175933D01*
X450200D01*
G01X459000Y1180600D02*
X461400D01*
G01X460200D02*
Y1172600D01*
G01X459000D02*
X461400D01*
G01X465900D02*
Y1180600D01*
X470500Y1172600D01*
Y1180600D01*
G01X474100Y1173666D02*
X474900Y1173000D01*
X475800Y1172600D01*
X476600D01*
X477400Y1173000D01*
X478000Y1173666D01*
X478300Y1174600D01*
X478100Y1175533D01*
X477600Y1176333D01*
X476700Y1176867D01*
X475500Y1177133D01*
X474800Y1177667D01*
X474500Y1178600D01*
X474700Y1179533D01*
X475200Y1180200D01*
X475900Y1180600D01*
X476600D01*
X477300Y1180333D01*
X477900Y1179667D01*
G01X484700Y1169933D02*
X485700Y1171267D01*
X486200Y1172600D01*
Y1177933D01*
X485700Y1179267D01*
X484700Y1180600D01*
G01X492200Y1172333D02*
X492000Y1172467D01*
Y1172733D01*
X492200Y1172867D01*
X492400Y1172733D01*
Y1172467D01*
X492200Y1172333D01*
G01X205039Y206937D02*
Y224525D01*
G01X220787Y201110D02*
Y218225D01*
G01X228661Y201109D02*
Y221825D01*
G01X230664Y682415D02*
G03I-2953J0D01*
G01Y702100D02*
G03I-2953J0D01*
G01X224759Y764107D02*
X799562D01*
G01Y760170D02*
X224759D01*
G01Y744422D02*
X799562D01*
G01X224759Y760170D02*
Y744422D01*
G01Y779856D02*
Y764107D01*
G01X799562Y779856D02*
X224759D01*
G01Y783793D02*
Y854659D01*
G01Y846785D02*
X520034D01*
G01X270034Y612533D02*
X238538D01*
G01D02*
X279877D01*
G01X250349Y682415D02*
G03I-2953J0D01*
G01Y702100D02*
G03I-2953J0D01*
G01X262390Y593775D02*
X263320Y592733D01*
X264405Y592108D01*
X265800Y591900D01*
X267195Y592317D01*
X268280Y593150D01*
X269055Y594608D01*
X269210Y596275D01*
X268900Y597942D01*
X268125Y598983D01*
X267040Y599817D01*
X265955Y600025D01*
X264870Y599817D01*
X263475Y598983D01*
X263940Y604400D01*
X268125D01*
G01X274170Y591900D02*
Y604400D01*
X278200Y593983D01*
X282230Y604400D01*
Y591900D01*
G01X286570D02*
Y604400D01*
X290600Y593983D01*
X294630Y604400D01*
Y591900D01*
G01X270034Y674913D02*
Y604659D01*
G01X321215Y612533D02*
X279877D01*
G01X270034Y682415D02*
G03I-2953J0D01*
G01Y702100D02*
G03I-2953J0D01*
G01X306929Y163386D02*
Y177710D01*
G02X321496I7283J9298D01*
G01Y163386D01*
G02X306929I-7283J0D01*
G01X289719Y675263D02*
Y604659D01*
G01X321215Y584974D02*
X289719D01*
G01D02*
X331058D01*
G01X289719Y612533D02*
X321215D01*
G01X289719Y685367D02*
X295625D01*
G01Y679462D02*
X289719D01*
G01X295625Y685367D02*
Y679462D01*
G01X289719D02*
Y685367D01*
G01Y705052D02*
X295625D01*
G01Y699147D02*
X289719D01*
G01X295625Y705052D02*
Y699147D01*
G01X289719D02*
Y705052D01*
G01X314213Y166386D02*
Y222825D01*
G01X315390Y562375D02*
X316320Y561333D01*
X317405Y560708D01*
X318800Y560500D01*
X320195Y560917D01*
X321280Y561750D01*
X322055Y563208D01*
X322210Y564875D01*
X321900Y566542D01*
X321125Y567583D01*
X320040Y568417D01*
X318955Y568625D01*
X317870Y568417D01*
X316475Y567583D01*
X316940Y573000D01*
X321125D01*
G01X327170Y560500D02*
Y573000D01*
X331200Y562583D01*
X335230Y573000D01*
Y560500D01*
G01X339570D02*
Y573000D01*
X343600Y562583D01*
X347630Y573000D01*
Y560500D01*
G01X321215Y675525D02*
Y577100D01*
G01X340900Y636675D02*
X309404D01*
G01D02*
X343853D01*
G01X315310Y685367D02*
X321215D01*
G01Y679462D02*
X315310D01*
G01X321215Y685367D02*
Y679462D01*
G01X315310D02*
Y685367D01*
G01Y705052D02*
X321215D01*
G01Y699147D02*
X315310D01*
G01X321215Y705052D02*
Y699147D01*
G01X315310D02*
Y705052D01*
G01X340900Y675525D02*
Y577100D01*
G01Y584974D02*
X372396D01*
G01D02*
X331058D01*
G01X346806Y674840D02*
Y628801D01*
G01X340900Y671341D02*
Y628801D01*
G01X346806Y636675D02*
X413332D01*
G01D02*
X343853D01*
G01X340900Y685367D02*
X346806D01*
G01Y679462D02*
X340900D01*
G01X346806Y685367D02*
Y679462D01*
G01X340900D02*
Y685367D01*
G01Y705052D02*
X346806D01*
G01Y699147D02*
X340900D01*
G01X346806Y705052D02*
Y699147D01*
G01X340900D02*
Y705052D01*
G01X350743Y699147D02*
X470473D01*
G01X350743Y705052D02*
X470473D01*
G01X370815Y639628D02*
Y652128D01*
X368955Y649628D01*
G01Y639628D02*
X372675D01*
G01X383215Y639211D02*
X382905Y639420D01*
Y639836D01*
X383215Y640045D01*
X383525Y639836D01*
Y639420D01*
X383215Y639211D01*
G01X392205Y641503D02*
X393135Y640461D01*
X394220Y639836D01*
X395615Y639628D01*
X397010Y640045D01*
X398095Y640878D01*
X398870Y642336D01*
X399025Y644003D01*
X398715Y645670D01*
X397940Y646711D01*
X396855Y647545D01*
X395770Y647753D01*
X394685Y647545D01*
X393290Y646711D01*
X393755Y652128D01*
X397940D01*
G01X403985Y639628D02*
Y652128D01*
X408015Y641711D01*
X412045Y652128D01*
Y639628D01*
G01X416385D02*
Y652128D01*
X420415Y641711D01*
X424445Y652128D01*
Y639628D01*
G01X378228Y203000D02*
Y221025D01*
G01X415100Y1158666D02*
X415900Y1158000D01*
X416800Y1157600D01*
X417600D01*
X418400Y1158000D01*
X419000Y1158666D01*
X419300Y1159600D01*
X419100Y1160533D01*
X418600Y1161333D01*
X417700Y1161867D01*
X416500Y1162133D01*
X415800Y1162667D01*
X415500Y1163600D01*
X415700Y1164533D01*
X416200Y1165200D01*
X416900Y1165600D01*
X417600D01*
X418300Y1165333D01*
X418900Y1164667D01*
G01X425200Y1157600D02*
X424400Y1157733D01*
X423700Y1158267D01*
X423100Y1159067D01*
X422700Y1160000D01*
X422500Y1161067D01*
Y1162133D01*
X422700Y1163200D01*
X423100Y1164133D01*
X423700Y1164933D01*
X424400Y1165467D01*
X425200Y1165600D01*
X426000Y1165467D01*
X426700Y1164933D01*
X427300Y1164133D01*
X427700Y1163200D01*
X427900Y1162133D01*
Y1161067D01*
X427700Y1160000D01*
X427300Y1159067D01*
X426700Y1158267D01*
X426000Y1157733D01*
X425200Y1157600D01*
G01X431200Y1165600D02*
Y1157600D01*
X435200D01*
G01X439000D02*
Y1165600D01*
X441000D01*
X441800Y1165200D01*
X442400Y1164667D01*
X442900Y1163867D01*
X443300Y1162933D01*
X443400Y1161600D01*
X443300Y1160267D01*
X442900Y1159333D01*
X442400Y1158533D01*
X441800Y1158000D01*
X441000Y1157600D01*
X439000D01*
G01X451200D02*
X447200D01*
Y1165600D01*
X451200D01*
G01X449600Y1161733D02*
X447200D01*
G01X455200Y1157600D02*
Y1165600D01*
X457700D01*
X458500Y1165200D01*
X459000Y1164667D01*
X459200Y1163600D01*
X459000Y1162533D01*
X458400Y1161867D01*
X457700Y1161467D01*
X455200D01*
G01X457700D02*
X459200Y1157600D01*
G01X462600D02*
Y1165600D01*
X465200Y1158933D01*
X467800Y1165600D01*
Y1157600D01*
G01X470700D02*
X473200Y1165600D01*
X475700Y1157600D01*
G01X474800Y1160400D02*
X471600D01*
G01X479100Y1158666D02*
X479900Y1158000D01*
X480800Y1157600D01*
X481600D01*
X482400Y1158000D01*
X483000Y1158666D01*
X483300Y1159600D01*
X483100Y1160533D01*
X482600Y1161333D01*
X481700Y1161867D01*
X480500Y1162133D01*
X479800Y1162667D01*
X479500Y1163600D01*
X479700Y1164533D01*
X480200Y1165200D01*
X480900Y1165600D01*
X481600D01*
X482300Y1165333D01*
X482900Y1164667D01*
G01X487000Y1157600D02*
Y1165600D01*
G01X490800D02*
X487000Y1160666D01*
G01X491400Y1157600D02*
X488700Y1162933D01*
G01X505200Y1157600D02*
X504400Y1157733D01*
X503700Y1158267D01*
X503100Y1159067D01*
X502700Y1160000D01*
X502500Y1161067D01*
Y1162133D01*
X502700Y1163200D01*
X503100Y1164133D01*
X503700Y1164933D01*
X504400Y1165467D01*
X505200Y1165600D01*
X506000Y1165467D01*
X506700Y1164933D01*
X507300Y1164133D01*
X507700Y1163200D01*
X507900Y1162133D01*
Y1161067D01*
X507700Y1160000D01*
X507300Y1159067D01*
X506700Y1158267D01*
X506000Y1157733D01*
X505200Y1157600D01*
G01X511200D02*
Y1165600D01*
X513600D01*
X514400Y1165200D01*
X515000Y1164267D01*
X515200Y1163200D01*
X515000Y1162133D01*
X514500Y1161333D01*
X513600Y1160933D01*
X511200D01*
G01X523200Y1157600D02*
X519200D01*
Y1165600D01*
X523200D01*
G01X521600Y1161733D02*
X519200D01*
G01X526900Y1157600D02*
Y1165600D01*
X531500Y1157600D01*
Y1165600D01*
G01X545200Y1157600D02*
X544400Y1157733D01*
X543700Y1158267D01*
X543100Y1159067D01*
X542700Y1160000D01*
X542500Y1161067D01*
Y1162133D01*
X542700Y1163200D01*
X543100Y1164133D01*
X543700Y1164933D01*
X544400Y1165467D01*
X545200Y1165600D01*
X546000Y1165467D01*
X546700Y1164933D01*
X547300Y1164133D01*
X547700Y1163200D01*
X547900Y1162133D01*
Y1161067D01*
X547700Y1160000D01*
X547300Y1159067D01*
X546700Y1158267D01*
X546000Y1157733D01*
X545200Y1157600D01*
G01X550900D02*
Y1165600D01*
X555500Y1157600D01*
Y1165600D01*
G01X570000Y1161867D02*
X570400Y1162267D01*
X570700Y1162933D01*
X570900Y1163867D01*
X570700Y1164667D01*
X570300Y1165200D01*
X569600Y1165600D01*
X566900D01*
Y1157600D01*
X570200D01*
X570900Y1158133D01*
X571300Y1158933D01*
X571500Y1159867D01*
X571300Y1160800D01*
X570700Y1161600D01*
X570000Y1161867D01*
X566900D01*
G01X577200Y1157600D02*
X576400Y1157733D01*
X575700Y1158267D01*
X575100Y1159067D01*
X574700Y1160000D01*
X574500Y1161067D01*
Y1162133D01*
X574700Y1163200D01*
X575100Y1164133D01*
X575700Y1164933D01*
X576400Y1165467D01*
X577200Y1165600D01*
X578000Y1165467D01*
X578700Y1164933D01*
X579300Y1164133D01*
X579700Y1163200D01*
X579900Y1162133D01*
Y1161067D01*
X579700Y1160000D01*
X579300Y1159067D01*
X578700Y1158267D01*
X578000Y1157733D01*
X577200Y1157600D01*
G01X585200Y1165600D02*
Y1157600D01*
G01X582900Y1165600D02*
X587500D01*
G01X591100Y1157600D02*
Y1165600D01*
G01X595300D02*
Y1157600D01*
G01Y1161600D02*
X591100D01*
G01X607100Y1158666D02*
X607900Y1158000D01*
X608800Y1157600D01*
X609600D01*
X610400Y1158000D01*
X611000Y1158666D01*
X611300Y1159600D01*
X611100Y1160533D01*
X610600Y1161333D01*
X609700Y1161867D01*
X608500Y1162133D01*
X607800Y1162667D01*
X607500Y1163600D01*
X607700Y1164533D01*
X608200Y1165200D01*
X608900Y1165600D01*
X609600D01*
X610300Y1165333D01*
X610900Y1164667D01*
G01X616000Y1165600D02*
X618400D01*
G01X617200D02*
Y1157600D01*
G01X616000D02*
X618400D01*
G01X623000D02*
Y1165600D01*
X625000D01*
X625800Y1165200D01*
X626400Y1164667D01*
X626900Y1163867D01*
X627300Y1162933D01*
X627400Y1161600D01*
X627300Y1160267D01*
X626900Y1159333D01*
X626400Y1158533D01*
X625800Y1158000D01*
X625000Y1157600D01*
X623000D01*
G01X635200D02*
X631200D01*
Y1165600D01*
X635200D01*
G01X633600Y1161733D02*
X631200D01*
G01X641200Y1157333D02*
X641000Y1157467D01*
Y1157733D01*
X641200Y1157867D01*
X641400Y1157733D01*
Y1157467D01*
X641200Y1157333D01*
G01X453741Y590339D02*
X441241D01*
X443741Y588479D01*
G01X453741D02*
Y592199D01*
G01X454158Y602739D02*
X453949Y602429D01*
X453533D01*
X453324Y602739D01*
X453533Y603049D01*
X453949D01*
X454158Y602739D01*
G01X451866Y611729D02*
X452908Y612659D01*
X453533Y613744D01*
X453741Y615139D01*
X453324Y616534D01*
X452491Y617619D01*
X451033Y618394D01*
X449366Y618549D01*
X447699Y618239D01*
X446658Y617464D01*
X445824Y616379D01*
X445616Y615294D01*
X445824Y614209D01*
X446658Y612814D01*
X441241Y613279D01*
Y617464D01*
G01X453741Y623509D02*
X441241D01*
X451658Y627539D01*
X441241Y631569D01*
X453741D01*
G01Y635909D02*
X441241D01*
X451658Y639939D01*
X441241Y643969D01*
X453741D01*
G01X457212Y-338900D02*
Y-343900D01*
G01X455755Y-338900D02*
X458669D01*
G01X463579Y-343900D02*
X461045D01*
Y-338900D01*
X463579D01*
G01X462565Y-341317D02*
X461045D01*
G01X466145Y-338900D02*
Y-343900D01*
X468679D01*
G01X472512Y-344067D02*
X472385Y-343983D01*
Y-343817D01*
X472512Y-343733D01*
X472639Y-343817D01*
Y-343983D01*
X472512Y-344067D01*
G01Y-341817D02*
X472385Y-341733D01*
Y-341567D01*
X472512Y-341483D01*
X472639Y-341567D01*
Y-341733D01*
X472512Y-341817D01*
G01X477295Y-345567D02*
X476662Y-344733D01*
X476345Y-343900D01*
Y-340567D01*
X476662Y-339733D01*
X477295Y-338900D01*
G01X482712D02*
X482205Y-339067D01*
X481825Y-339483D01*
X481572Y-339983D01*
X481382Y-340650D01*
X481319Y-341400D01*
X481382Y-342150D01*
X481572Y-342817D01*
X481825Y-343317D01*
X482205Y-343733D01*
X482712Y-343900D01*
X483219Y-343733D01*
X483599Y-343317D01*
X483852Y-342817D01*
X484042Y-342150D01*
X484105Y-341400D01*
X484042Y-340650D01*
X483852Y-339983D01*
X483599Y-339483D01*
X483219Y-339067D01*
X482712Y-338900D01*
G01X486419Y-342900D02*
X486799Y-343483D01*
X487305Y-343817D01*
X487875Y-343900D01*
X488382Y-343817D01*
X488889Y-343400D01*
X489205Y-342900D01*
X489269Y-342400D01*
X489142Y-341817D01*
X488699Y-341400D01*
X488255Y-341233D01*
X487685D01*
G01X488255D02*
X488635Y-340983D01*
X488952Y-340567D01*
X489079Y-340067D01*
X488952Y-339567D01*
X488635Y-339150D01*
X488065Y-338900D01*
X487495Y-338983D01*
X486925Y-339317D01*
G01X493229Y-345567D02*
X493862Y-344733D01*
X494179Y-343900D01*
Y-340567D01*
X493862Y-339733D01*
X493229Y-338900D01*
G01X496619Y-342900D02*
X496999Y-343483D01*
X497505Y-343817D01*
X498075Y-343900D01*
X498582Y-343817D01*
X499089Y-343400D01*
X499405Y-342900D01*
X499469Y-342400D01*
X499342Y-341817D01*
X498899Y-341400D01*
X498455Y-341233D01*
X497885D01*
G01X498455D02*
X498835Y-340983D01*
X499152Y-340567D01*
X499279Y-340067D01*
X499152Y-339567D01*
X498835Y-339150D01*
X498265Y-338900D01*
X497695Y-338983D01*
X497125Y-339317D01*
G01X501909Y-339733D02*
X502289Y-339233D01*
X502732Y-338983D01*
X503239Y-338900D01*
X503872Y-339067D01*
X504315Y-339483D01*
X504442Y-339983D01*
X504379Y-340483D01*
X504125Y-340900D01*
X502859Y-341733D01*
X502289Y-342317D01*
X501909Y-343150D01*
X501782Y-343900D01*
X504442D01*
G01X508085D02*
X508212Y-342817D01*
X508402Y-341900D01*
X508655Y-341067D01*
X508972Y-340150D01*
X509479Y-338900D01*
X506945D01*
G01X512489Y-342233D02*
X514135D01*
G01X517209Y-339733D02*
X517589Y-339233D01*
X518032Y-338983D01*
X518539Y-338900D01*
X519172Y-339067D01*
X519615Y-339483D01*
X519742Y-339983D01*
X519679Y-340483D01*
X519425Y-340900D01*
X518159Y-341733D01*
X517589Y-342317D01*
X517209Y-343150D01*
X517082Y-343900D01*
X519742D01*
G01X522119Y-342900D02*
X522499Y-343483D01*
X523005Y-343817D01*
X523575Y-343900D01*
X524082Y-343817D01*
X524589Y-343400D01*
X524905Y-342900D01*
X524969Y-342400D01*
X524842Y-341817D01*
X524399Y-341400D01*
X523955Y-341233D01*
X523385D01*
G01X523955D02*
X524335Y-340983D01*
X524652Y-340567D01*
X524779Y-340067D01*
X524652Y-339567D01*
X524335Y-339150D01*
X523765Y-338900D01*
X523195Y-338983D01*
X522625Y-339317D01*
G01X529372Y-343900D02*
Y-338900D01*
X527029Y-342483D01*
X530195D01*
G01X532319Y-343150D02*
X532699Y-343567D01*
X533142Y-343817D01*
X533712Y-343900D01*
X534282Y-343733D01*
X534725Y-343400D01*
X535042Y-342817D01*
X535105Y-342150D01*
X534979Y-341483D01*
X534662Y-341067D01*
X534219Y-340733D01*
X533775Y-340650D01*
X533332Y-340733D01*
X532762Y-341067D01*
X532952Y-338900D01*
X534662D01*
G01X542709Y-343900D02*
Y-338900D01*
X545115D01*
G01X544229Y-341317D02*
X542709D01*
G01X547429Y-343900D02*
X549012Y-338900D01*
X550595Y-343900D01*
G01X550025Y-342150D02*
X547999D01*
G01X552782Y-343900D02*
X555442Y-338900D01*
G01X552782D02*
X555442Y-343900D01*
G01X559212Y-344067D02*
X559085Y-343983D01*
Y-343817D01*
X559212Y-343733D01*
X559339Y-343817D01*
Y-343983D01*
X559212Y-344067D01*
G01Y-341817D02*
X559085Y-341733D01*
Y-341567D01*
X559212Y-341483D01*
X559339Y-341567D01*
Y-341733D01*
X559212Y-341817D01*
G01X563995Y-345567D02*
X563362Y-344733D01*
X563045Y-343900D01*
Y-340567D01*
X563362Y-339733D01*
X563995Y-338900D01*
G01X569412D02*
X568905Y-339067D01*
X568525Y-339483D01*
X568272Y-339983D01*
X568082Y-340650D01*
X568019Y-341400D01*
X568082Y-342150D01*
X568272Y-342817D01*
X568525Y-343317D01*
X568905Y-343733D01*
X569412Y-343900D01*
X569919Y-343733D01*
X570299Y-343317D01*
X570552Y-342817D01*
X570742Y-342150D01*
X570805Y-341400D01*
X570742Y-340650D01*
X570552Y-339983D01*
X570299Y-339483D01*
X569919Y-339067D01*
X569412Y-338900D01*
G01X573119Y-342900D02*
X573499Y-343483D01*
X574005Y-343817D01*
X574575Y-343900D01*
X575082Y-343817D01*
X575589Y-343400D01*
X575905Y-342900D01*
X575969Y-342400D01*
X575842Y-341817D01*
X575399Y-341400D01*
X574955Y-341233D01*
X574385D01*
G01X574955D02*
X575335Y-340983D01*
X575652Y-340567D01*
X575779Y-340067D01*
X575652Y-339567D01*
X575335Y-339150D01*
X574765Y-338900D01*
X574195Y-338983D01*
X573625Y-339317D01*
G01X579929Y-345567D02*
X580562Y-344733D01*
X580879Y-343900D01*
Y-340567D01*
X580562Y-339733D01*
X579929Y-338900D01*
G01X583319Y-342900D02*
X583699Y-343483D01*
X584205Y-343817D01*
X584775Y-343900D01*
X585282Y-343817D01*
X585789Y-343400D01*
X586105Y-342900D01*
X586169Y-342400D01*
X586042Y-341817D01*
X585599Y-341400D01*
X585155Y-341233D01*
X584585D01*
G01X585155D02*
X585535Y-340983D01*
X585852Y-340567D01*
X585979Y-340067D01*
X585852Y-339567D01*
X585535Y-339150D01*
X584965Y-338900D01*
X584395Y-338983D01*
X583825Y-339317D01*
G01X588735Y-343317D02*
X589179Y-343733D01*
X589685Y-343900D01*
X590192Y-343733D01*
X590635Y-343233D01*
X590952Y-342483D01*
X591079Y-341733D01*
Y-340817D01*
X590952Y-340067D01*
X590635Y-339400D01*
X590255Y-339067D01*
X589812Y-338900D01*
X589305Y-339067D01*
X588925Y-339400D01*
X588672Y-339900D01*
X588545Y-340567D01*
X588672Y-341150D01*
X588989Y-341733D01*
X589369Y-342067D01*
X589812Y-342150D01*
X590319Y-341983D01*
X590699Y-341567D01*
X591079Y-340817D01*
G01X594785Y-343900D02*
X594912Y-342817D01*
X595102Y-341900D01*
X595355Y-341067D01*
X595672Y-340150D01*
X596179Y-338900D01*
X593645D01*
G01X599189Y-342233D02*
X600835D01*
G01X603719Y-342900D02*
X604099Y-343483D01*
X604605Y-343817D01*
X605175Y-343900D01*
X605682Y-343817D01*
X606189Y-343400D01*
X606505Y-342900D01*
X606569Y-342400D01*
X606442Y-341817D01*
X605999Y-341400D01*
X605555Y-341233D01*
X604985D01*
G01X605555D02*
X605935Y-340983D01*
X606252Y-340567D01*
X606379Y-340067D01*
X606252Y-339567D01*
X605935Y-339150D01*
X605365Y-338900D01*
X604795Y-338983D01*
X604225Y-339317D01*
G01X609009Y-341817D02*
X609452Y-341233D01*
X609832Y-340900D01*
X610339Y-340733D01*
X610782Y-340900D01*
X611099Y-341233D01*
X611352Y-341733D01*
X611415Y-342317D01*
X611352Y-342817D01*
X611099Y-343317D01*
X610719Y-343733D01*
X610275Y-343900D01*
X609769Y-343733D01*
X609325Y-343233D01*
X609072Y-342483D01*
X609009Y-341650D01*
X609135Y-340567D01*
X609325Y-339983D01*
X609642Y-339400D01*
X610085Y-338983D01*
X610529Y-338900D01*
X610972Y-339067D01*
X611289Y-339483D01*
G01X615312Y-343900D02*
Y-338900D01*
X614552Y-339900D01*
G01Y-343900D02*
X616072D01*
G01X621172D02*
Y-338900D01*
X618829Y-342483D01*
X621995D01*
G01X445212Y-273900D02*
Y-348900D01*
X945212D01*
Y-273900D01*
X445212D01*
G01X445157Y203000D02*
Y218825D01*
G01X462599Y699147D02*
Y603328D01*
G01D02*
Y702100D01*
G01Y705052D02*
Y736548D01*
G01D02*
Y702100D01*
G01X470434Y849737D02*
Y862237D01*
X468574Y859737D01*
G01Y849737D02*
X472294D01*
G01X482834Y862237D02*
X481594Y861820D01*
X480664Y860779D01*
X480044Y859529D01*
X479579Y857862D01*
X479424Y855987D01*
X479579Y854112D01*
X480044Y852445D01*
X480664Y851195D01*
X481594Y850154D01*
X482834Y849737D01*
X484074Y850154D01*
X485004Y851195D01*
X485624Y852445D01*
X486089Y854112D01*
X486244Y855987D01*
X486089Y857862D01*
X485624Y859529D01*
X485004Y860779D01*
X484074Y861820D01*
X482834Y862237D01*
G01X495234D02*
X493994Y861820D01*
X493064Y860779D01*
X492444Y859529D01*
X491979Y857862D01*
X491824Y855987D01*
X491979Y854112D01*
X492444Y852445D01*
X493064Y851195D01*
X493994Y850154D01*
X495234Y849737D01*
X496474Y850154D01*
X497404Y851195D01*
X498024Y852445D01*
X498489Y854112D01*
X498644Y855987D01*
X498489Y857862D01*
X498024Y859529D01*
X497404Y860779D01*
X496474Y861820D01*
X495234Y862237D01*
G01X505619Y853904D02*
X509649D01*
G01X520034Y849737D02*
Y862237D01*
X518174Y859737D01*
G01Y849737D02*
X521894D01*
G01X529024Y851612D02*
X529954Y850570D01*
X531039Y849945D01*
X532434Y849737D01*
X533829Y850154D01*
X534914Y850987D01*
X535689Y852445D01*
X535844Y854112D01*
X535534Y855779D01*
X534759Y856820D01*
X533674Y857654D01*
X532589Y857862D01*
X531504Y857654D01*
X530109Y856820D01*
X530574Y862237D01*
X534759D01*
G01X544834D02*
X543594Y861820D01*
X542664Y860779D01*
X542044Y859529D01*
X541579Y857862D01*
X541424Y855987D01*
X541579Y854112D01*
X542044Y852445D01*
X542664Y851195D01*
X543594Y850154D01*
X544834Y849737D01*
X546074Y850154D01*
X547004Y851195D01*
X547624Y852445D01*
X548089Y854112D01*
X548244Y855987D01*
X548089Y857862D01*
X547624Y859529D01*
X547004Y860779D01*
X546074Y861820D01*
X544834Y862237D01*
G01X553204Y849737D02*
Y862237D01*
X557234Y851820D01*
X561264Y862237D01*
Y849737D01*
G01X565604D02*
Y862237D01*
X569634Y851820D01*
X573664Y862237D01*
Y849737D01*
G01X523200Y692400D02*
X525200D01*
Y690000D01*
X524600Y689200D01*
X523900Y688667D01*
X522900Y688400D01*
X521900Y688667D01*
X521200Y689200D01*
X520600Y690000D01*
X520200Y690933D01*
X520000Y692000D01*
Y692933D01*
X520200Y693733D01*
X520600Y694667D01*
X521200Y695467D01*
X521800Y696000D01*
X522600Y696400D01*
X523300D01*
X524100Y696133D01*
X524700Y695600D01*
G01X528600Y688400D02*
Y696400D01*
X531100D01*
X531900Y696000D01*
X532400Y695467D01*
X532600Y694400D01*
X532400Y693333D01*
X531800Y692667D01*
X531100Y692267D01*
X528600D01*
G01X531100D02*
X532600Y688400D01*
G01X538600D02*
X537800Y688533D01*
X537100Y689067D01*
X536500Y689867D01*
X536100Y690800D01*
X535900Y691867D01*
Y692933D01*
X536100Y694000D01*
X536500Y694933D01*
X537100Y695733D01*
X537800Y696267D01*
X538600Y696400D01*
X539400Y696267D01*
X540100Y695733D01*
X540700Y694933D01*
X541100Y694000D01*
X541300Y692933D01*
Y691867D01*
X541100Y690800D01*
X540700Y689867D01*
X540100Y689067D01*
X539400Y688533D01*
X538600Y688400D01*
G01X544400Y696400D02*
Y690667D01*
X544800Y689466D01*
X545600Y688667D01*
X546600Y688400D01*
X547600Y688667D01*
X548400Y689466D01*
X548800Y690667D01*
Y696400D01*
G01X552600Y688400D02*
Y696400D01*
X555000D01*
X555800Y696000D01*
X556400Y695067D01*
X556600Y694000D01*
X556400Y692933D01*
X555900Y692133D01*
X555000Y691733D01*
X552600D01*
G01X560500Y689466D02*
X561300Y688800D01*
X562200Y688400D01*
X563000D01*
X563800Y688800D01*
X564400Y689466D01*
X564700Y690400D01*
X564500Y691333D01*
X564000Y692133D01*
X563100Y692667D01*
X561900Y692933D01*
X561200Y693467D01*
X560900Y694400D01*
X561100Y695333D01*
X561600Y696000D01*
X562300Y696400D01*
X563000D01*
X563700Y696133D01*
X564300Y695467D01*
G01X579400Y692667D02*
X579800Y693067D01*
X580100Y693733D01*
X580300Y694667D01*
X580100Y695467D01*
X579700Y696000D01*
X579000Y696400D01*
X576300D01*
Y688400D01*
X579600D01*
X580300Y688933D01*
X580700Y689733D01*
X580900Y690667D01*
X580700Y691600D01*
X580100Y692400D01*
X579400Y692667D01*
X576300D01*
G01X527520Y203000D02*
Y220425D01*
G01X815310Y846785D02*
X520034D01*
G01X594449Y205047D02*
Y218325D01*
G01X640212Y-273900D02*
Y-348900D01*
G01Y-323900D02*
X743212D01*
Y-298900D01*
G01X640212D02*
X743212D01*
G01X629851Y205268D02*
Y221125D01*
G01X743212Y-273900D02*
Y-348900D01*
G01X745212Y-273900D02*
Y-348900D01*
G01X750719Y-333900D02*
Y-328900D01*
X751985D01*
X752492Y-329150D01*
X752872Y-329483D01*
X753189Y-329983D01*
X753442Y-330567D01*
X753505Y-331400D01*
X753442Y-332233D01*
X753189Y-332817D01*
X752872Y-333317D01*
X752492Y-333650D01*
X751985Y-333900D01*
X750719D01*
G01X755629D02*
X757212Y-328900D01*
X758795Y-333900D01*
G01X758225Y-332150D02*
X756199D01*
G01X762312Y-328900D02*
Y-333900D01*
G01X760855Y-328900D02*
X763769D01*
G01X768679Y-333900D02*
X766145D01*
Y-328900D01*
X768679D01*
G01X767665Y-331317D02*
X766145D01*
G01X772512Y-334067D02*
X772385Y-333983D01*
Y-333817D01*
X772512Y-333733D01*
X772639Y-333817D01*
Y-333983D01*
X772512Y-334067D01*
G01Y-331817D02*
X772385Y-331733D01*
Y-331567D01*
X772512Y-331483D01*
X772639Y-331567D01*
Y-331733D01*
X772512Y-331817D01*
G01X745212Y-323900D02*
X945212D01*
G01X750845Y-308900D02*
Y-303900D01*
X752365D01*
X752872Y-304150D01*
X753252Y-304733D01*
X753379Y-305400D01*
X753252Y-306067D01*
X752935Y-306567D01*
X752365Y-306817D01*
X750845D01*
G01X756072Y-309067D02*
X758352Y-303900D01*
G01X760855Y-308900D02*
Y-303900D01*
X763769Y-308900D01*
Y-303900D01*
G01X767412Y-309067D02*
X767285Y-308983D01*
Y-308817D01*
X767412Y-308733D01*
X767539Y-308817D01*
Y-308983D01*
X767412Y-309067D01*
G01Y-306817D02*
X767285Y-306733D01*
Y-306567D01*
X767412Y-306483D01*
X767539Y-306567D01*
Y-306733D01*
X767412Y-306817D01*
G01X745212Y-298900D02*
X945212D01*
G01X750845Y-283900D02*
Y-278900D01*
X752365D01*
X752872Y-279150D01*
X753252Y-279733D01*
X753379Y-280400D01*
X753252Y-281067D01*
X752935Y-281567D01*
X752365Y-281817D01*
X750845D01*
G01X755945Y-283900D02*
Y-278900D01*
X757529D01*
X758035Y-279150D01*
X758352Y-279483D01*
X758479Y-280150D01*
X758352Y-280817D01*
X757972Y-281233D01*
X757529Y-281483D01*
X755945D01*
G01X757529D02*
X758479Y-283900D01*
G01X762312D02*
X761805Y-283817D01*
X761362Y-283483D01*
X760982Y-282983D01*
X760729Y-282400D01*
X760602Y-281733D01*
Y-281067D01*
X760729Y-280400D01*
X760982Y-279817D01*
X761362Y-279317D01*
X761805Y-278983D01*
X762312Y-278900D01*
X762819Y-278983D01*
X763262Y-279317D01*
X763642Y-279817D01*
X763895Y-280400D01*
X764022Y-281067D01*
Y-281733D01*
X763895Y-282400D01*
X763642Y-282983D01*
X763262Y-283483D01*
X762819Y-283817D01*
X762312Y-283900D01*
G01X766145Y-282900D02*
X766462Y-283400D01*
X766842Y-283733D01*
X767285Y-283900D01*
X767792Y-283733D01*
X768172Y-283400D01*
X768552Y-282900D01*
X768679Y-282233D01*
Y-278900D01*
G01X773779Y-283900D02*
X771245D01*
Y-278900D01*
X773779D01*
G01X772765Y-281317D02*
X771245D01*
G01X779005Y-279317D02*
X778625Y-279067D01*
X778182Y-278900D01*
X777675D01*
X777105Y-279150D01*
X776662Y-279567D01*
X776345Y-280067D01*
X776092Y-280900D01*
X776029Y-281650D01*
X776155Y-282400D01*
X776345Y-282900D01*
X776725Y-283400D01*
X777169Y-283733D01*
X777612Y-283900D01*
X778055D01*
X778499Y-283733D01*
X778879Y-283483D01*
X779195Y-283150D01*
G01X782712Y-278900D02*
Y-283900D01*
G01X781255Y-278900D02*
X784169D01*
G01X787812Y-284067D02*
X787685Y-283983D01*
Y-283817D01*
X787812Y-283733D01*
X787939Y-283817D01*
Y-283983D01*
X787812Y-284067D01*
G01Y-281817D02*
X787685Y-281733D01*
Y-281567D01*
X787812Y-281483D01*
X787939Y-281567D01*
Y-281733D01*
X787812Y-281817D01*
G01X762660Y825600D02*
Y838100D01*
X756925Y829142D01*
X764675D01*
G01X769170Y825600D02*
Y838100D01*
X773200Y827683D01*
X777230Y838100D01*
Y825600D01*
G01X781570D02*
Y838100D01*
X785600Y827683D01*
X789630Y838100D01*
Y825600D01*
G01X783661Y15504D02*
Y-39625D01*
G01X776772Y18504D02*
Y32533D01*
G02X790551I6889J9593D01*
G01Y18504D01*
G02X776772I-6890J0D01*
G01X799562Y819226D02*
X768066D01*
G01D02*
X807436D01*
G01X803141Y205268D02*
Y214225D01*
G01X802173Y198386D02*
X1714125D01*
G01X850743Y764107D02*
X807436D01*
G01X850743Y760170D02*
X807436D01*
G01X815310Y752296D02*
X799562Y760170D01*
G01Y744422D02*
X815310Y752296D01*
G01X799562Y764107D02*
X815310Y771982D01*
G01X799562Y783793D02*
Y827100D01*
G01X815310Y771982D02*
X799562Y779856D01*
G01X846806Y819226D02*
X807436D01*
G01X819134Y163386D02*
Y177415D01*
G02X832913I6890J9593D01*
G01Y163386D01*
G02X819134I-6889J0D01*
G01X826024Y166386D02*
Y222225D01*
G01X831362Y720993D02*
Y764300D01*
G01X815310Y775918D02*
Y827100D01*
G01Y775918D02*
Y854659D01*
G01Y819226D02*
X846806D01*
G01X842725Y272700D02*
X1688228D01*
G01X855300Y726400D02*
X842800D01*
X845300Y724540D01*
G01X855300D02*
Y728260D01*
G01Y734770D02*
X842800D01*
X853217Y738800D01*
X842800Y742830D01*
X855300D01*
G01Y747170D02*
X842800D01*
X853217Y751200D01*
X842800Y755230D01*
X855300D01*
G01X860212Y-323900D02*
Y-348900D01*
G01X865845Y-333900D02*
Y-328900D01*
X867429D01*
X867935Y-329150D01*
X868252Y-329483D01*
X868379Y-330150D01*
X868252Y-330817D01*
X867872Y-331233D01*
X867429Y-331483D01*
X865845D01*
G01X867429D02*
X868379Y-333900D01*
G01X873479D02*
X870945D01*
Y-328900D01*
X873479D01*
G01X872465Y-331317D02*
X870945D01*
G01X875729Y-328900D02*
X877312Y-333900D01*
X878895Y-328900D01*
G01X882412Y-334067D02*
X882285Y-333983D01*
Y-333817D01*
X882412Y-333733D01*
X882539Y-333817D01*
Y-333983D01*
X882412Y-334067D01*
G01Y-331817D02*
X882285Y-331733D01*
Y-331567D01*
X882412Y-331483D01*
X882539Y-331567D01*
Y-331733D01*
X882412Y-331817D01*
G01X875300Y762200D02*
X877300D01*
Y759800D01*
X876700Y759000D01*
X876000Y758467D01*
X875000Y758200D01*
X874000Y758467D01*
X873300Y759000D01*
X872700Y759800D01*
X872300Y760733D01*
X872100Y761800D01*
Y762733D01*
X872300Y763533D01*
X872700Y764467D01*
X873300Y765267D01*
X873900Y765800D01*
X874700Y766200D01*
X875400D01*
X876200Y765933D01*
X876800Y765400D01*
G01X880700Y758200D02*
Y766200D01*
X883200D01*
X884000Y765800D01*
X884500Y765267D01*
X884700Y764200D01*
X884500Y763133D01*
X883900Y762467D01*
X883200Y762067D01*
X880700D01*
G01X883200D02*
X884700Y758200D01*
G01X890700D02*
X889900Y758333D01*
X889200Y758867D01*
X888600Y759667D01*
X888200Y760600D01*
X888000Y761667D01*
Y762733D01*
X888200Y763800D01*
X888600Y764733D01*
X889200Y765533D01*
X889900Y766067D01*
X890700Y766200D01*
X891500Y766067D01*
X892200Y765533D01*
X892800Y764733D01*
X893200Y763800D01*
X893400Y762733D01*
Y761667D01*
X893200Y760600D01*
X892800Y759667D01*
X892200Y758867D01*
X891500Y758333D01*
X890700Y758200D01*
G01X896500Y766200D02*
Y760467D01*
X896900Y759266D01*
X897700Y758467D01*
X898700Y758200D01*
X899700Y758467D01*
X900500Y759266D01*
X900900Y760467D01*
Y766200D01*
G01X904700Y758200D02*
Y766200D01*
X907100D01*
X907900Y765800D01*
X908500Y764867D01*
X908700Y763800D01*
X908500Y762733D01*
X908000Y761933D01*
X907100Y761533D01*
X904700D01*
G01X912600Y759266D02*
X913400Y758600D01*
X914300Y758200D01*
X915100D01*
X915900Y758600D01*
X916500Y759266D01*
X916800Y760200D01*
X916600Y761133D01*
X916100Y761933D01*
X915200Y762467D01*
X914000Y762733D01*
X913300Y763267D01*
X913000Y764200D01*
X913200Y765133D01*
X913700Y765800D01*
X914400Y766200D01*
X915100D01*
X915800Y765933D01*
X916400Y765267D01*
G01X928200Y758200D02*
X930700Y766200D01*
X933200Y758200D01*
G01X932300Y761000D02*
X929100D01*
G01X909212Y-323900D02*
Y-348900D01*
G01X1101615Y15504D02*
Y-45675D01*
G01X1094331Y18504D02*
Y32828D01*
G02X1108898I7283J9298D01*
G01Y18504D01*
G02X1094331I-7283J0D01*
G01X1177008Y163386D02*
Y177710D01*
G02X1191575I7284J9298D01*
G01Y163386D01*
G02X1177008I-7283J0D01*
G01X1184292Y166386D02*
Y209875D01*
G01X1248307Y203000D02*
Y218675D01*
G01X1310100Y50600D02*
G03I-9430J6054D01*
G01X1326400Y-91100D02*
X1316400D01*
Y-88600D01*
X1316900Y-87600D01*
X1317567Y-86850D01*
X1318567Y-86225D01*
X1319734Y-85725D01*
X1321400Y-85600D01*
X1323067Y-85725D01*
X1324233Y-86225D01*
X1325234Y-86850D01*
X1325900Y-87600D01*
X1326400Y-88600D01*
Y-91100D01*
G01Y-75850D02*
Y-80850D01*
X1316400D01*
Y-75850D01*
G01X1321233Y-77850D02*
Y-80850D01*
G01X1316400Y-68350D02*
X1326400D01*
G01X1316400Y-71225D02*
Y-65475D01*
G01X1326400Y-61475D02*
X1316400Y-58350D01*
X1326400Y-55225D01*
G01X1322900Y-56350D02*
Y-60350D01*
G01X1316400Y-49850D02*
Y-46850D01*
G01Y-48350D02*
X1326400D01*
G01Y-49850D02*
Y-46850D01*
G01X1316400Y-40850D02*
X1326400D01*
Y-35850D01*
G01Y-21475D02*
X1316400Y-18350D01*
X1326400Y-15225D01*
G01X1322900Y-16350D02*
Y-20350D01*
G01X1314400Y-48400D02*
Y-6700D01*
X1305600Y46400D01*
X1305200Y44700D01*
G01X1300670Y53654D02*
Y-7675D01*
G01X1305600Y46400D02*
X1306600Y45200D01*
G01X1302800Y56500D02*
X1701925D01*
G01X1315236Y205047D02*
Y210275D01*
G01X1397598Y205047D02*
Y219675D01*
G01X1449962Y53653D02*
Y-17475D01*
G01X1464528Y205047D02*
Y215775D01*
G01X1679359Y-244800D02*
G03I-95259J0D01*
G01X1499930Y205268D02*
Y217075D01*
G01X1515227Y-233390D02*
X1515697Y-234125D01*
X1516323Y-234545D01*
X1517028Y-234650D01*
X1517655Y-234545D01*
X1518282Y-234020D01*
X1518673Y-233390D01*
X1518752Y-232760D01*
X1518595Y-232025D01*
X1518047Y-231500D01*
X1517498Y-231290D01*
X1516793D01*
G01X1517498D02*
X1517968Y-230975D01*
X1518360Y-230450D01*
X1518517Y-229820D01*
X1518360Y-229190D01*
X1517968Y-228665D01*
X1517263Y-228350D01*
X1516558Y-228455D01*
X1515853Y-228875D01*
G01X1523250Y-234650D02*
X1523798Y-234545D01*
X1524425Y-234230D01*
X1524817Y-233705D01*
X1524973Y-232970D01*
X1524817Y-232235D01*
X1524347Y-231605D01*
X1523642Y-231290D01*
X1522858D01*
X1522388Y-231080D01*
X1521997Y-230555D01*
X1521840Y-229820D01*
X1522075Y-229085D01*
X1522623Y-228560D01*
X1523250Y-228350D01*
X1523877Y-228560D01*
X1524425Y-229085D01*
X1524660Y-229820D01*
X1524503Y-230555D01*
X1524112Y-231080D01*
X1523642Y-231290D01*
X1522858D01*
X1522153Y-231605D01*
X1521683Y-232235D01*
X1521527Y-232970D01*
X1521683Y-233705D01*
X1522075Y-234230D01*
X1522702Y-234545D01*
X1523250Y-234650D01*
G01X1529550Y-234860D02*
X1529393Y-234755D01*
Y-234545D01*
X1529550Y-234440D01*
X1529707Y-234545D01*
Y-234755D01*
X1529550Y-234860D01*
G01X1535850Y-228350D02*
X1535223Y-228560D01*
X1534753Y-229085D01*
X1534440Y-229715D01*
X1534205Y-230555D01*
X1534127Y-231500D01*
X1534205Y-232445D01*
X1534440Y-233285D01*
X1534753Y-233915D01*
X1535223Y-234440D01*
X1535850Y-234650D01*
X1536477Y-234440D01*
X1536947Y-233915D01*
X1537260Y-233285D01*
X1537495Y-232445D01*
X1537573Y-231500D01*
X1537495Y-230555D01*
X1537260Y-229715D01*
X1536947Y-229085D01*
X1536477Y-228560D01*
X1535850Y-228350D01*
G01X1542150D02*
X1541523Y-228560D01*
X1541053Y-229085D01*
X1540740Y-229715D01*
X1540505Y-230555D01*
X1540427Y-231500D01*
X1540505Y-232445D01*
X1540740Y-233285D01*
X1541053Y-233915D01*
X1541523Y-234440D01*
X1542150Y-234650D01*
X1542777Y-234440D01*
X1543247Y-233915D01*
X1543560Y-233285D01*
X1543795Y-232445D01*
X1543873Y-231500D01*
X1543795Y-230555D01*
X1543560Y-229715D01*
X1543247Y-229085D01*
X1542777Y-228560D01*
X1542150Y-228350D01*
G01X1544433Y-313700D02*
X1543500Y-312450D01*
X1543033Y-311200D01*
Y-306200D01*
X1543500Y-304950D01*
X1544433Y-303700D01*
G01X1550253Y-311200D02*
Y-303700D01*
X1554547Y-311200D01*
Y-303700D01*
G01X1559900Y-311200D02*
X1559153Y-311075D01*
X1558500Y-310575D01*
X1557940Y-309825D01*
X1557567Y-308950D01*
X1557380Y-307950D01*
Y-306950D01*
X1557567Y-305950D01*
X1557940Y-305075D01*
X1558500Y-304325D01*
X1559153Y-303825D01*
X1559900Y-303700D01*
X1560647Y-303825D01*
X1561300Y-304325D01*
X1561860Y-305075D01*
X1562233Y-305950D01*
X1562420Y-306950D01*
Y-307950D01*
X1562233Y-308950D01*
X1561860Y-309825D01*
X1561300Y-310575D01*
X1560647Y-311075D01*
X1559900Y-311200D01*
G01X1565253D02*
Y-303700D01*
X1569547Y-311200D01*
Y-303700D01*
G01X1573687Y-308700D02*
X1576113D01*
G01X1580533Y-311200D02*
Y-303700D01*
X1582773D01*
X1583520Y-304075D01*
X1584080Y-304950D01*
X1584267Y-305950D01*
X1584080Y-306950D01*
X1583613Y-307700D01*
X1582773Y-308075D01*
X1580533D01*
G01X1588033Y-303700D02*
Y-311200D01*
X1591767D01*
G01X1595067D02*
X1597400Y-303700D01*
X1599733Y-311200D01*
G01X1598893Y-308575D02*
X1595907D01*
G01X1604900Y-303700D02*
Y-311200D01*
G01X1602753Y-303700D02*
X1607047D01*
G01X1614267Y-311200D02*
X1610533D01*
Y-303700D01*
X1614267D01*
G01X1612773Y-307325D02*
X1610533D01*
G01X1617847Y-311200D02*
Y-303700D01*
X1619713D01*
X1620460Y-304075D01*
X1621020Y-304575D01*
X1621487Y-305325D01*
X1621860Y-306200D01*
X1621953Y-307450D01*
X1621860Y-308700D01*
X1621487Y-309575D01*
X1621020Y-310325D01*
X1620460Y-310825D01*
X1619713Y-311200D01*
X1617847D01*
G01X1627867Y-313700D02*
X1628800Y-312450D01*
X1629267Y-311200D01*
Y-306200D01*
X1628800Y-304950D01*
X1627867Y-303700D01*
G01X1547200Y-177300D02*
Y-167300D01*
X1549700D01*
X1550700Y-167800D01*
X1551450Y-168467D01*
X1552075Y-169467D01*
X1552575Y-170634D01*
X1552700Y-172300D01*
X1552575Y-173967D01*
X1552075Y-175133D01*
X1551450Y-176134D01*
X1550700Y-176800D01*
X1549700Y-177300D01*
X1547200D01*
G01X1562450D02*
X1557450D01*
Y-167300D01*
X1562450D01*
G01X1560450Y-172133D02*
X1557450D01*
G01X1569950Y-167300D02*
Y-177300D01*
G01X1567075Y-167300D02*
X1572825D01*
G01X1576825Y-177300D02*
X1579950Y-167300D01*
X1583075Y-177300D01*
G01X1581950Y-173800D02*
X1577950D01*
G01X1588450Y-167300D02*
X1591450D01*
G01X1589950D02*
Y-177300D01*
G01X1588450D02*
X1591450D01*
G01X1597450Y-167300D02*
Y-177300D01*
X1602450D01*
G01X1616825D02*
X1619950Y-167300D01*
X1623075Y-177300D01*
G01X1621950Y-173800D02*
X1617950D01*
G01X1546200Y-179800D02*
X1626200D01*
G01X1572083Y-330500D02*
X1571150Y-329250D01*
X1570683Y-328000D01*
Y-323000D01*
X1571150Y-321750D01*
X1572083Y-320500D01*
G01X1581170Y-328000D02*
Y-320500D01*
X1577717Y-325875D01*
X1582383D01*
G01X1585590Y-328000D02*
X1589510Y-320500D01*
G01X1585590D02*
X1589510Y-328000D01*
G01X1595517Y-330500D02*
X1596450Y-329250D01*
X1596917Y-328000D01*
Y-323000D01*
X1596450Y-321750D01*
X1595517Y-320500D01*
G01X1555525Y-231500D02*
X1576300D01*
G01X1554353Y-189800D02*
Y-182300D01*
X1558647Y-189800D01*
Y-182300D01*
G01X1564000Y-189800D02*
X1563253Y-189675D01*
X1562600Y-189175D01*
X1562040Y-188425D01*
X1561667Y-187550D01*
X1561480Y-186550D01*
Y-185550D01*
X1561667Y-184550D01*
X1562040Y-183675D01*
X1562600Y-182925D01*
X1563253Y-182425D01*
X1564000Y-182300D01*
X1564747Y-182425D01*
X1565400Y-182925D01*
X1565960Y-183675D01*
X1566333Y-184550D01*
X1566520Y-185550D01*
Y-186550D01*
X1566333Y-187550D01*
X1565960Y-188425D01*
X1565400Y-189175D01*
X1564747Y-189675D01*
X1564000Y-189800D01*
G01X1577040Y-188800D02*
X1577787Y-189425D01*
X1578627Y-189800D01*
X1579373D01*
X1580120Y-189425D01*
X1580680Y-188800D01*
X1580960Y-187925D01*
X1580773Y-187050D01*
X1580307Y-186300D01*
X1579467Y-185800D01*
X1578347Y-185550D01*
X1577693Y-185050D01*
X1577413Y-184175D01*
X1577600Y-183300D01*
X1578067Y-182675D01*
X1578720Y-182300D01*
X1579373D01*
X1580027Y-182550D01*
X1580587Y-183175D01*
G01X1588553Y-182925D02*
X1587993Y-182550D01*
X1587340Y-182300D01*
X1586593D01*
X1585753Y-182675D01*
X1585100Y-183300D01*
X1584633Y-184050D01*
X1584260Y-185300D01*
X1584167Y-186425D01*
X1584353Y-187550D01*
X1584633Y-188300D01*
X1585193Y-189050D01*
X1585847Y-189550D01*
X1586500Y-189800D01*
X1587153D01*
X1587807Y-189550D01*
X1588367Y-189175D01*
X1588833Y-188675D01*
G01X1591667Y-189800D02*
X1594000Y-182300D01*
X1596333Y-189800D01*
G01X1595493Y-187175D02*
X1592507D01*
G01X1599633Y-182300D02*
Y-189800D01*
X1603367D01*
G01X1610867D02*
X1607133D01*
Y-182300D01*
X1610867D01*
G01X1609373Y-185925D02*
X1607133D01*
G01X1589100Y-287000D02*
X1635100D01*
G01X1576300Y-279200D02*
Y-260000D01*
G01X1591900D02*
Y-279200D01*
G01X1576300D02*
G03X1591900I7800J0D01*
G01X1589100Y-252200D02*
X1635100D01*
G01X1591900Y-254800D02*
Y-227500D01*
G01X1576300Y-254800D02*
Y-227500D01*
G01X1591900Y-260000D02*
G03X1576300I-7800J0D01*
G01X1586900Y-232500D02*
X1591900Y-231500D01*
X1586900Y-230500D01*
Y-232500D01*
G01X1576300Y-231500D02*
X1591900D01*
G01X1581300Y-230500D02*
X1576300Y-231500D01*
X1581300Y-232500D01*
Y-230500D01*
G01X1630100Y-282000D02*
X1631100Y-287000D01*
X1632100Y-282000D01*
X1630100D01*
G01X1631100Y-252200D02*
Y-287000D01*
G01X1632100Y-257200D02*
X1631100Y-252200D01*
X1630100Y-257200D01*
X1632100D01*
G01X1631100Y-238125D02*
Y-252200D01*
G01X1631625Y-232538D02*
X1630890Y-231990D01*
X1630470Y-231520D01*
X1630260Y-230893D01*
X1630470Y-230345D01*
X1630890Y-229953D01*
X1631520Y-229640D01*
X1632255Y-229562D01*
X1632885Y-229640D01*
X1633515Y-229953D01*
X1634040Y-230423D01*
X1634250Y-230972D01*
X1634040Y-231598D01*
X1633410Y-232147D01*
X1632465Y-232460D01*
X1631415Y-232538D01*
X1630050Y-232382D01*
X1629315Y-232147D01*
X1628580Y-231755D01*
X1628055Y-231207D01*
X1627950Y-230658D01*
X1628160Y-230110D01*
X1628685Y-229718D01*
G01X1632990Y-226473D02*
X1633725Y-226003D01*
X1634145Y-225377D01*
X1634250Y-224672D01*
X1634145Y-224045D01*
X1633620Y-223418D01*
X1632990Y-223027D01*
X1632360Y-222948D01*
X1631625Y-223105D01*
X1631100Y-223653D01*
X1630890Y-224202D01*
Y-224907D01*
G01Y-224202D02*
X1630575Y-223732D01*
X1630050Y-223340D01*
X1629420Y-223183D01*
X1628790Y-223340D01*
X1628265Y-223732D01*
X1627950Y-224437D01*
X1628055Y-225142D01*
X1628475Y-225847D01*
G01X1634460Y-218450D02*
X1634355Y-218607D01*
X1634145D01*
X1634040Y-218450D01*
X1634145Y-218293D01*
X1634355D01*
X1634460Y-218450D01*
G01X1627950Y-212150D02*
X1628160Y-212777D01*
X1628685Y-213247D01*
X1629315Y-213560D01*
X1630155Y-213795D01*
X1631100Y-213873D01*
X1632045Y-213795D01*
X1632885Y-213560D01*
X1633515Y-213247D01*
X1634040Y-212777D01*
X1634250Y-212150D01*
X1634040Y-211523D01*
X1633515Y-211053D01*
X1632885Y-210740D01*
X1632045Y-210505D01*
X1631100Y-210427D01*
X1630155Y-210505D01*
X1629315Y-210740D01*
X1628685Y-211053D01*
X1628160Y-211523D01*
X1627950Y-212150D01*
G01Y-205850D02*
X1628160Y-206477D01*
X1628685Y-206947D01*
X1629315Y-207260D01*
X1630155Y-207495D01*
X1631100Y-207573D01*
X1632045Y-207495D01*
X1632885Y-207260D01*
X1633515Y-206947D01*
X1634040Y-206477D01*
X1634250Y-205850D01*
X1634040Y-205223D01*
X1633515Y-204753D01*
X1632885Y-204440D01*
X1632045Y-204205D01*
X1631100Y-204127D01*
X1630155Y-204205D01*
X1629315Y-204440D01*
X1628685Y-204753D01*
X1628160Y-205223D01*
X1627950Y-205850D01*
G01X1673800Y-179200D02*
Y-169200D01*
X1676300D01*
X1677300Y-169700D01*
X1678050Y-170367D01*
X1678675Y-171367D01*
X1679175Y-172534D01*
X1679300Y-174200D01*
X1679175Y-175867D01*
X1678675Y-177033D01*
X1678050Y-178034D01*
X1677300Y-178700D01*
X1676300Y-179200D01*
X1673800D01*
G01X1689050D02*
X1684050D01*
Y-169200D01*
X1689050D01*
G01X1687050Y-174033D02*
X1684050D01*
G01X1696550Y-169200D02*
Y-179200D01*
G01X1693675Y-169200D02*
X1699425D01*
G01X1703425Y-179200D02*
X1706550Y-169200D01*
X1709675Y-179200D01*
G01X1708550Y-175700D02*
X1704550D01*
G01X1715050Y-169200D02*
X1718050D01*
G01X1716550D02*
Y-179200D01*
G01X1715050D02*
X1718050D01*
G01X1724050Y-169200D02*
Y-179200D01*
X1729050D01*
G01X1743425D02*
X1746550Y-169200D01*
X1749675Y-179200D01*
G01X1748550Y-175700D02*
X1744550D01*
G01X1670512Y15504D02*
Y-27875D01*
G01X1682567Y124016D02*
X1701075D01*
G01X1676268Y163386D02*
X1704875D01*
G01X1673268Y166386D02*
Y224400D01*
X1668175Y229006D01*
G01X1683504Y193512D02*
Y211700D01*
X1685825Y215128D01*
G01X1683228Y271700D02*
X1688228Y272700D01*
X1683228Y273700D01*
Y271700D01*
G01X1688228Y168692D02*
Y275700D01*
G01X1757700Y-186100D02*
Y454000D01*
X2034500D01*
Y-186100D01*
X1757700D01*
G01Y-162400D02*
X2034500D01*
G01X1757700Y-138700D02*
X2034500D01*
G01X1757700Y-115000D02*
X2034500D01*
G01X1757700Y-91300D02*
X2034500D01*
G01X1757700Y-67600D02*
X2034500D01*
G01X1757700Y-43900D02*
X2034500D01*
G01X1757700Y-20200D02*
X2034500D01*
G01X1757700Y3500D02*
X2034500D01*
G01X1757700Y27200D02*
X2034500D01*
G01X1757700Y50900D02*
X2034500D01*
G01X1757700Y74600D02*
X2034500D01*
G01X1757700Y98300D02*
X2034500D01*
G01X1757700Y122000D02*
X2034500D01*
G01X1757700Y145700D02*
X2034500D01*
G01X1757700Y169400D02*
X2034500D01*
G01X1757700Y193100D02*
X2034500D01*
G01X1757700Y216800D02*
X2034500D01*
G01X1757700Y240500D02*
X2034500D01*
G01X1757700Y264200D02*
X2034500D01*
G01X1757700Y287900D02*
X2034500D01*
G01X1757700Y311600D02*
X2034500D01*
G01X1757700Y335300D02*
X2034500D01*
G01X1757700Y359000D02*
X2034500D01*
G01X1757700Y382700D02*
X2034500D01*
G01X1757700Y417700D02*
X2034500D01*
G01X1757700Y406400D02*
X2034500D01*
G01X1757700Y429000D02*
X2034500D01*
G01X1794700Y417700D02*
Y-186100D01*
G01X1872500Y417700D02*
Y-186100D01*
G01X1950300Y417700D02*
Y-186100D01*
G01X2002600Y417700D02*
Y-186100D01*
G01X-471400Y-391900D02*
Y1528800D01*
X2244200D01*
Y-391900D01*
X-471400D01*
G01X-133750Y111023D02*
Y117323D01*
X-134690Y116063D01*
G01Y111023D02*
X-132810D01*
G01X-127450D02*
Y117323D01*
X-128390Y116063D01*
G01Y111023D02*
X-126510D01*
G01X-120210D02*
Y117323D01*
X-123108Y112808D01*
X-119192D01*
G01X-114850Y111023D02*
Y117323D01*
X-115790Y116063D01*
G01Y111023D02*
X-113910D01*
G01X-108550Y110813D02*
X-108707Y110918D01*
Y111128D01*
X-108550Y111233D01*
X-108393Y111128D01*
Y110918D01*
X-108550Y110813D01*
G01X-102407Y111023D02*
X-102250Y112388D01*
X-102015Y113543D01*
X-101702Y114593D01*
X-101310Y115748D01*
X-100683Y117323D01*
X-103817D01*
G01X-97673Y112283D02*
X-97203Y111548D01*
X-96577Y111128D01*
X-95872Y111023D01*
X-95245Y111128D01*
X-94618Y111653D01*
X-94227Y112283D01*
X-94148Y112913D01*
X-94305Y113648D01*
X-94853Y114173D01*
X-95402Y114383D01*
X-96107D01*
G01X-95402D02*
X-94932Y114698D01*
X-94540Y115223D01*
X-94383Y115853D01*
X-94540Y116483D01*
X-94932Y117008D01*
X-95637Y117323D01*
X-96342Y117218D01*
X-97047Y116798D01*
G01X-122250Y160236D02*
Y166536D01*
X-123190Y165276D01*
G01Y160236D02*
X-121310D01*
G01X-117438Y162861D02*
X-116890Y163596D01*
X-116420Y164016D01*
X-115793Y164226D01*
X-115245Y164016D01*
X-114853Y163596D01*
X-114540Y162966D01*
X-114462Y162231D01*
X-114540Y161601D01*
X-114853Y160971D01*
X-115323Y160446D01*
X-115872Y160236D01*
X-116498Y160446D01*
X-117047Y161076D01*
X-117360Y162021D01*
X-117438Y163071D01*
X-117282Y164436D01*
X-117047Y165171D01*
X-116655Y165906D01*
X-116107Y166431D01*
X-115558Y166536D01*
X-115010Y166326D01*
X-114618Y165801D01*
G01X-111373Y161496D02*
X-110903Y160761D01*
X-110277Y160341D01*
X-109572Y160236D01*
X-108945Y160341D01*
X-108318Y160866D01*
X-107927Y161496D01*
X-107848Y162126D01*
X-108005Y162861D01*
X-108553Y163386D01*
X-109102Y163596D01*
X-109807D01*
G01X-109102D02*
X-108632Y163911D01*
X-108240Y164436D01*
X-108083Y165066D01*
X-108240Y165696D01*
X-108632Y166221D01*
X-109337Y166536D01*
X-110042Y166431D01*
X-110747Y166011D01*
G01X-105073Y161496D02*
X-104603Y160761D01*
X-103977Y160341D01*
X-103272Y160236D01*
X-102645Y160341D01*
X-102018Y160866D01*
X-101627Y161496D01*
X-101548Y162126D01*
X-101705Y162861D01*
X-102253Y163386D01*
X-102802Y163596D01*
X-103507D01*
G01X-102802D02*
X-102332Y163911D01*
X-101940Y164436D01*
X-101783Y165066D01*
X-101940Y165696D01*
X-102332Y166221D01*
X-103037Y166536D01*
X-103742Y166431D01*
X-104447Y166011D01*
G01X-97050Y160026D02*
X-97207Y160131D01*
Y160341D01*
X-97050Y160446D01*
X-96893Y160341D01*
Y160131D01*
X-97050Y160026D01*
G01X-90750Y160236D02*
X-90202Y160341D01*
X-89575Y160656D01*
X-89183Y161181D01*
X-89027Y161916D01*
X-89183Y162651D01*
X-89653Y163281D01*
X-90358Y163596D01*
X-91142D01*
X-91612Y163806D01*
X-92003Y164331D01*
X-92160Y165066D01*
X-91925Y165801D01*
X-91377Y166326D01*
X-90750Y166536D01*
X-90123Y166326D01*
X-89575Y165801D01*
X-89340Y165066D01*
X-89497Y164331D01*
X-89888Y163806D01*
X-90358Y163596D01*
X-91142D01*
X-91847Y163281D01*
X-92317Y162651D01*
X-92473Y161916D01*
X-92317Y161181D01*
X-91925Y160656D01*
X-91298Y160341D01*
X-90750Y160236D01*
G01X-85938Y162861D02*
X-85390Y163596D01*
X-84920Y164016D01*
X-84293Y164226D01*
X-83745Y164016D01*
X-83353Y163596D01*
X-83040Y162966D01*
X-82962Y162231D01*
X-83040Y161601D01*
X-83353Y160971D01*
X-83823Y160446D01*
X-84372Y160236D01*
X-84998Y160446D01*
X-85547Y161076D01*
X-85860Y162021D01*
X-85938Y163071D01*
X-85782Y164436D01*
X-85547Y165171D01*
X-85155Y165906D01*
X-84607Y166431D01*
X-84058Y166536D01*
X-83510Y166326D01*
X-83118Y165801D01*
G01X-106300Y188513D02*
Y194813D01*
X-107240Y193553D01*
G01Y188513D02*
X-105360D01*
G01X-101332Y189248D02*
X-100783Y188723D01*
X-100157Y188513D01*
X-99530Y188723D01*
X-98982Y189353D01*
X-98590Y190298D01*
X-98433Y191243D01*
Y192398D01*
X-98590Y193343D01*
X-98982Y194183D01*
X-99452Y194603D01*
X-100000Y194813D01*
X-100627Y194603D01*
X-101097Y194183D01*
X-101410Y193553D01*
X-101567Y192713D01*
X-101410Y191978D01*
X-101018Y191243D01*
X-100548Y190823D01*
X-100000Y190718D01*
X-99373Y190928D01*
X-98903Y191453D01*
X-98433Y192398D01*
G01X-95188Y191138D02*
X-94640Y191873D01*
X-94170Y192293D01*
X-93543Y192503D01*
X-92995Y192293D01*
X-92603Y191873D01*
X-92290Y191243D01*
X-92212Y190508D01*
X-92290Y189878D01*
X-92603Y189248D01*
X-93073Y188723D01*
X-93622Y188513D01*
X-94248Y188723D01*
X-94797Y189353D01*
X-95110Y190298D01*
X-95188Y191348D01*
X-95032Y192713D01*
X-94797Y193448D01*
X-94405Y194183D01*
X-93857Y194708D01*
X-93308Y194813D01*
X-92760Y194603D01*
X-92368Y194078D01*
G01X-87400Y194813D02*
X-88027Y194603D01*
X-88497Y194078D01*
X-88810Y193448D01*
X-89045Y192608D01*
X-89123Y191663D01*
X-89045Y190718D01*
X-88810Y189878D01*
X-88497Y189248D01*
X-88027Y188723D01*
X-87400Y188513D01*
X-86773Y188723D01*
X-86303Y189248D01*
X-85990Y189878D01*
X-85755Y190718D01*
X-85677Y191663D01*
X-85755Y192608D01*
X-85990Y193448D01*
X-86303Y194078D01*
X-86773Y194603D01*
X-87400Y194813D01*
G01X-81100Y188303D02*
X-81257Y188408D01*
Y188618D01*
X-81100Y188723D01*
X-80943Y188618D01*
Y188408D01*
X-81100Y188303D01*
G01X-76288Y191138D02*
X-75740Y191873D01*
X-75270Y192293D01*
X-74643Y192503D01*
X-74095Y192293D01*
X-73703Y191873D01*
X-73390Y191243D01*
X-73312Y190508D01*
X-73390Y189878D01*
X-73703Y189248D01*
X-74173Y188723D01*
X-74722Y188513D01*
X-75348Y188723D01*
X-75897Y189353D01*
X-76210Y190298D01*
X-76288Y191348D01*
X-76132Y192713D01*
X-75897Y193448D01*
X-75505Y194183D01*
X-74957Y194708D01*
X-74408Y194813D01*
X-73860Y194603D01*
X-73468Y194078D01*
G01X-70223Y189773D02*
X-69753Y189038D01*
X-69127Y188618D01*
X-68422Y188513D01*
X-67795Y188618D01*
X-67168Y189143D01*
X-66777Y189773D01*
X-66698Y190403D01*
X-66855Y191138D01*
X-67403Y191663D01*
X-67952Y191873D01*
X-68657D01*
G01X-67952D02*
X-67482Y192188D01*
X-67090Y192713D01*
X-66933Y193343D01*
X-67090Y193973D01*
X-67482Y194498D01*
X-68187Y194813D01*
X-68892Y194708D01*
X-69597Y194288D01*
G01X-90774Y3150D02*
X-91401Y2940D01*
X-91871Y2415D01*
X-92184Y1785D01*
X-92419Y945D01*
X-92497Y0D01*
X-92419Y-945D01*
X-92184Y-1785D01*
X-91871Y-2415D01*
X-91401Y-2940D01*
X-90774Y-3150D01*
X-90147Y-2940D01*
X-89677Y-2415D01*
X-89364Y-1785D01*
X-89129Y-945D01*
X-89051Y0D01*
X-89129Y945D01*
X-89364Y1785D01*
X-89677Y2415D01*
X-90147Y2940D01*
X-90774Y3150D01*
G01X-99000Y14254D02*
Y20554D01*
X-99940Y19294D01*
G01Y14254D02*
X-98060D01*
G01X-92700D02*
X-92152Y14359D01*
X-91525Y14674D01*
X-91133Y15199D01*
X-90977Y15934D01*
X-91133Y16669D01*
X-91603Y17299D01*
X-92308Y17614D01*
X-93092D01*
X-93562Y17824D01*
X-93953Y18349D01*
X-94110Y19084D01*
X-93875Y19819D01*
X-93327Y20344D01*
X-92700Y20554D01*
X-92073Y20344D01*
X-91525Y19819D01*
X-91290Y19084D01*
X-91447Y18349D01*
X-91838Y17824D01*
X-92308Y17614D01*
X-93092D01*
X-93797Y17299D01*
X-94267Y16669D01*
X-94423Y15934D01*
X-94267Y15199D01*
X-93875Y14674D01*
X-93248Y14359D01*
X-92700Y14254D01*
G01X-88123Y15199D02*
X-87653Y14674D01*
X-87105Y14359D01*
X-86400Y14254D01*
X-85695Y14464D01*
X-85147Y14884D01*
X-84755Y15619D01*
X-84677Y16459D01*
X-84833Y17299D01*
X-85225Y17824D01*
X-85773Y18244D01*
X-86322Y18349D01*
X-86870Y18244D01*
X-87575Y17824D01*
X-87340Y20554D01*
X-85225D01*
G01X-80100Y14044D02*
X-80257Y14149D01*
Y14359D01*
X-80100Y14464D01*
X-79943Y14359D01*
Y14149D01*
X-80100Y14044D01*
G01X-73800Y20554D02*
X-74427Y20344D01*
X-74897Y19819D01*
X-75210Y19189D01*
X-75445Y18349D01*
X-75523Y17404D01*
X-75445Y16459D01*
X-75210Y15619D01*
X-74897Y14989D01*
X-74427Y14464D01*
X-73800Y14254D01*
X-73173Y14464D01*
X-72703Y14989D01*
X-72390Y15619D01*
X-72155Y16459D01*
X-72077Y17404D01*
X-72155Y18349D01*
X-72390Y19189D01*
X-72703Y19819D01*
X-73173Y20344D01*
X-73800Y20554D01*
G01X-66560Y14254D02*
Y20554D01*
X-69458Y16039D01*
X-65542D01*
G01X-46600Y77012D02*
X-47230Y77482D01*
X-47545Y78030D01*
X-47650Y78657D01*
X-47440Y79440D01*
X-46915Y79988D01*
X-46285Y80145D01*
X-45655Y80067D01*
X-45130Y79753D01*
X-44080Y78187D01*
X-43345Y77482D01*
X-42295Y77012D01*
X-41350Y76855D01*
Y80145D01*
G01X-47650Y84800D02*
X-47440Y84173D01*
X-46915Y83703D01*
X-46285Y83390D01*
X-45445Y83155D01*
X-44500Y83077D01*
X-43555Y83155D01*
X-42715Y83390D01*
X-42085Y83703D01*
X-41560Y84173D01*
X-41350Y84800D01*
X-41560Y85427D01*
X-42085Y85897D01*
X-42715Y86210D01*
X-43555Y86445D01*
X-44500Y86523D01*
X-45445Y86445D01*
X-46285Y86210D01*
X-46915Y85897D01*
X-47440Y85427D01*
X-47650Y84800D01*
G01X-42085Y89768D02*
X-41560Y90317D01*
X-41350Y90943D01*
X-41560Y91570D01*
X-42190Y92118D01*
X-43135Y92510D01*
X-44080Y92667D01*
X-45235D01*
X-46180Y92510D01*
X-47020Y92118D01*
X-47440Y91648D01*
X-47650Y91100D01*
X-47440Y90473D01*
X-47020Y90003D01*
X-46390Y89690D01*
X-45550Y89533D01*
X-44815Y89690D01*
X-44080Y90082D01*
X-43660Y90552D01*
X-43555Y91100D01*
X-43765Y91727D01*
X-44290Y92197D01*
X-45235Y92667D01*
G01X-41350Y97400D02*
X-41455Y97948D01*
X-41770Y98575D01*
X-42295Y98967D01*
X-43030Y99123D01*
X-43765Y98967D01*
X-44395Y98497D01*
X-44710Y97792D01*
Y97008D01*
X-44920Y96538D01*
X-45445Y96147D01*
X-46180Y95990D01*
X-46915Y96225D01*
X-47440Y96773D01*
X-47650Y97400D01*
X-47440Y98027D01*
X-46915Y98575D01*
X-46180Y98810D01*
X-45445Y98653D01*
X-44920Y98262D01*
X-44710Y97792D01*
Y97008D01*
X-44395Y96303D01*
X-43765Y95833D01*
X-43030Y95677D01*
X-42295Y95833D01*
X-41770Y96225D01*
X-41455Y96852D01*
X-41350Y97400D01*
G01X-41140Y103700D02*
X-41245Y103543D01*
X-41455D01*
X-41560Y103700D01*
X-41455Y103857D01*
X-41245D01*
X-41140Y103700D01*
G01X-41350Y110940D02*
X-47650D01*
X-43135Y108042D01*
Y111958D01*
G01X-46600Y114812D02*
X-47230Y115282D01*
X-47545Y115830D01*
X-47650Y116457D01*
X-47440Y117240D01*
X-46915Y117788D01*
X-46285Y117945D01*
X-45655Y117867D01*
X-45130Y117553D01*
X-44080Y115987D01*
X-43345Y115282D01*
X-42295Y114812D01*
X-41350Y114655D01*
Y117945D01*
G01X0Y-61224D02*
X-627Y-61434D01*
X-1097Y-61959D01*
X-1410Y-62589D01*
X-1645Y-63429D01*
X-1723Y-64374D01*
X-1645Y-65319D01*
X-1410Y-66159D01*
X-1097Y-66789D01*
X-627Y-67314D01*
X0Y-67524D01*
X627Y-67314D01*
X1097Y-66789D01*
X1410Y-66159D01*
X1645Y-65319D01*
X1723Y-64374D01*
X1645Y-63429D01*
X1410Y-62589D01*
X1097Y-61959D01*
X627Y-61434D01*
X0Y-61224D01*
G01X8111Y237077D02*
X8636Y237547D01*
X8951Y238095D01*
X9056Y238800D01*
X8846Y239505D01*
X8426Y240053D01*
X7691Y240445D01*
X6851Y240523D01*
X6011Y240367D01*
X5486Y239975D01*
X5066Y239427D01*
X4961Y238878D01*
X5066Y238330D01*
X5486Y237625D01*
X2756Y237860D01*
Y239975D01*
G01X8321Y243768D02*
X8846Y244317D01*
X9056Y244943D01*
X8846Y245570D01*
X8216Y246118D01*
X7271Y246510D01*
X6326Y246667D01*
X5171D01*
X4226Y246510D01*
X3386Y246118D01*
X2966Y245648D01*
X2756Y245100D01*
X2966Y244473D01*
X3386Y244003D01*
X4016Y243690D01*
X4856Y243533D01*
X5591Y243690D01*
X6326Y244082D01*
X6746Y244552D01*
X6851Y245100D01*
X6641Y245727D01*
X6116Y246197D01*
X5171Y246667D01*
G01X9266Y251400D02*
X9161Y251243D01*
X8951D01*
X8846Y251400D01*
X8951Y251557D01*
X9161D01*
X9266Y251400D01*
G01X2756Y257700D02*
X2966Y257073D01*
X3491Y256603D01*
X4121Y256290D01*
X4961Y256055D01*
X5906Y255977D01*
X6851Y256055D01*
X7691Y256290D01*
X8321Y256603D01*
X8846Y257073D01*
X9056Y257700D01*
X8846Y258327D01*
X8321Y258797D01*
X7691Y259110D01*
X6851Y259345D01*
X5906Y259423D01*
X4961Y259345D01*
X4121Y259110D01*
X3491Y258797D01*
X2966Y258327D01*
X2756Y257700D01*
G01X6431Y262512D02*
X5696Y263060D01*
X5276Y263530D01*
X5066Y264157D01*
X5276Y264705D01*
X5696Y265097D01*
X6326Y265410D01*
X7061Y265488D01*
X7691Y265410D01*
X8321Y265097D01*
X8846Y264627D01*
X9056Y264078D01*
X8846Y263452D01*
X8216Y262903D01*
X7271Y262590D01*
X6221Y262512D01*
X4856Y262668D01*
X4121Y262903D01*
X3386Y263295D01*
X2861Y263843D01*
X2756Y264392D01*
X2966Y264940D01*
X3491Y265332D01*
G01X20867Y-56250D02*
X14567D01*
X15827Y-57190D01*
G01X20867D02*
Y-55310D01*
G01Y-50107D02*
X19502Y-49950D01*
X18347Y-49715D01*
X17297Y-49402D01*
X16142Y-49010D01*
X14567Y-48383D01*
Y-51517D01*
G01X20867Y-43807D02*
X19502Y-43650D01*
X18347Y-43415D01*
X17297Y-43102D01*
X16142Y-42710D01*
X14567Y-42083D01*
Y-45217D01*
G01X21077Y-37350D02*
X20972Y-37507D01*
X20762D01*
X20657Y-37350D01*
X20762Y-37193D01*
X20972D01*
X21077Y-37350D01*
G01X20867Y-31050D02*
X14567D01*
X15827Y-31990D01*
G01X20867D02*
Y-30110D01*
G01Y-24907D02*
X19502Y-24750D01*
X18347Y-24515D01*
X17297Y-24202D01*
X16142Y-23810D01*
X14567Y-23183D01*
Y-26317D01*
G01X20866Y236250D02*
X14566D01*
X15826Y235310D01*
G01X20866D02*
Y237190D01*
G01Y242393D02*
X19501Y242550D01*
X18346Y242785D01*
X17296Y243098D01*
X16141Y243490D01*
X14566Y244117D01*
Y240983D01*
G01X20866Y248693D02*
X19501Y248850D01*
X18346Y249085D01*
X17296Y249398D01*
X16141Y249790D01*
X14566Y250417D01*
Y247283D01*
G01X21076Y255150D02*
X20971Y254993D01*
X20761D01*
X20656Y255150D01*
X20761Y255307D01*
X20971D01*
X21076Y255150D01*
G01X20866Y261450D02*
X14566D01*
X15826Y260510D01*
G01X20866D02*
Y262390D01*
G01X18241Y266262D02*
X17506Y266810D01*
X17086Y267280D01*
X16876Y267907D01*
X17086Y268455D01*
X17506Y268847D01*
X18136Y269160D01*
X18871Y269238D01*
X19501Y269160D01*
X20131Y268847D01*
X20656Y268377D01*
X20866Y267828D01*
X20656Y267202D01*
X20026Y266653D01*
X19081Y266340D01*
X18031Y266262D01*
X16666Y266418D01*
X15931Y266653D01*
X15196Y267045D01*
X14671Y267593D01*
X14566Y268142D01*
X14776Y268690D01*
X15301Y269082D01*
G01X37126Y228627D02*
X37861Y229097D01*
X38281Y229723D01*
X38386Y230428D01*
X38281Y231055D01*
X37756Y231682D01*
X37126Y232073D01*
X36496Y232152D01*
X35761Y231995D01*
X35236Y231447D01*
X35026Y230898D01*
Y230193D01*
G01Y230898D02*
X34711Y231368D01*
X34186Y231760D01*
X33556Y231917D01*
X32926Y231760D01*
X32401Y231368D01*
X32086Y230663D01*
X32191Y229958D01*
X32611Y229253D01*
G01X37441Y234927D02*
X37966Y235397D01*
X38281Y235945D01*
X38386Y236650D01*
X38176Y237355D01*
X37756Y237903D01*
X37021Y238295D01*
X36181Y238373D01*
X35341Y238217D01*
X34816Y237825D01*
X34396Y237277D01*
X34291Y236728D01*
X34396Y236180D01*
X34816Y235475D01*
X32086Y235710D01*
Y237825D01*
G01X33136Y241462D02*
X32506Y241932D01*
X32191Y242480D01*
X32086Y243107D01*
X32296Y243890D01*
X32821Y244438D01*
X33451Y244595D01*
X34081Y244517D01*
X34606Y244203D01*
X35656Y242637D01*
X36391Y241932D01*
X37441Y241462D01*
X38386Y241305D01*
Y244595D01*
G01X38596Y249250D02*
X38491Y249093D01*
X38281D01*
X38176Y249250D01*
X38281Y249407D01*
X38491D01*
X38596Y249250D01*
G01X37126Y253827D02*
X37861Y254297D01*
X38281Y254923D01*
X38386Y255628D01*
X38281Y256255D01*
X37756Y256882D01*
X37126Y257273D01*
X36496Y257352D01*
X35761Y257195D01*
X35236Y256647D01*
X35026Y256098D01*
Y255393D01*
G01Y256098D02*
X34711Y256568D01*
X34186Y256960D01*
X33556Y257117D01*
X32926Y256960D01*
X32401Y256568D01*
X32086Y255863D01*
X32191Y255158D01*
X32611Y254453D01*
G01X35761Y260362D02*
X35026Y260910D01*
X34606Y261380D01*
X34396Y262007D01*
X34606Y262555D01*
X35026Y262947D01*
X35656Y263260D01*
X36391Y263338D01*
X37021Y263260D01*
X37651Y262947D01*
X38176Y262477D01*
X38386Y261928D01*
X38176Y261302D01*
X37546Y260753D01*
X36601Y260440D01*
X35551Y260362D01*
X34186Y260518D01*
X33451Y260753D01*
X32716Y261145D01*
X32191Y261693D01*
X32086Y262242D01*
X32296Y262790D01*
X32821Y263182D01*
G01X52650Y218790D02*
X46350D01*
X50865Y215892D01*
Y219808D01*
G01X51390Y222427D02*
X52125Y222897D01*
X52545Y223523D01*
X52650Y224228D01*
X52545Y224855D01*
X52020Y225482D01*
X51390Y225873D01*
X50760Y225952D01*
X50025Y225795D01*
X49500Y225247D01*
X49290Y224698D01*
Y223993D01*
G01Y224698D02*
X48975Y225168D01*
X48450Y225560D01*
X47820Y225717D01*
X47190Y225560D01*
X46665Y225168D01*
X46350Y224463D01*
X46455Y223758D01*
X46875Y223053D01*
G01X52650Y230450D02*
X52545Y230998D01*
X52230Y231625D01*
X51705Y232017D01*
X50970Y232173D01*
X50235Y232017D01*
X49605Y231547D01*
X49290Y230842D01*
Y230058D01*
X49080Y229588D01*
X48555Y229197D01*
X47820Y229040D01*
X47085Y229275D01*
X46560Y229823D01*
X46350Y230450D01*
X46560Y231077D01*
X47085Y231625D01*
X47820Y231860D01*
X48555Y231703D01*
X49080Y231312D01*
X49290Y230842D01*
Y230058D01*
X49605Y229353D01*
X50235Y228883D01*
X50970Y228727D01*
X51705Y228883D01*
X52230Y229275D01*
X52545Y229902D01*
X52650Y230450D01*
G01X52860Y236750D02*
X52755Y236593D01*
X52545D01*
X52440Y236750D01*
X52545Y236907D01*
X52755D01*
X52860Y236750D01*
G01X51915Y241718D02*
X52440Y242267D01*
X52650Y242893D01*
X52440Y243520D01*
X51810Y244068D01*
X50865Y244460D01*
X49920Y244617D01*
X48765D01*
X47820Y244460D01*
X46980Y244068D01*
X46560Y243598D01*
X46350Y243050D01*
X46560Y242423D01*
X46980Y241953D01*
X47610Y241640D01*
X48450Y241483D01*
X49185Y241640D01*
X49920Y242032D01*
X50340Y242502D01*
X50445Y243050D01*
X50235Y243677D01*
X49710Y244147D01*
X48765Y244617D01*
G01X52650Y249350D02*
X52545Y249898D01*
X52230Y250525D01*
X51705Y250917D01*
X50970Y251073D01*
X50235Y250917D01*
X49605Y250447D01*
X49290Y249742D01*
Y248958D01*
X49080Y248488D01*
X48555Y248097D01*
X47820Y247940D01*
X47085Y248175D01*
X46560Y248723D01*
X46350Y249350D01*
X46560Y249977D01*
X47085Y250525D01*
X47820Y250760D01*
X48555Y250603D01*
X49080Y250212D01*
X49290Y249742D01*
Y248958D01*
X49605Y248253D01*
X50235Y247783D01*
X50970Y247627D01*
X51705Y247783D01*
X52230Y248175D01*
X52545Y248802D01*
X52650Y249350D01*
G01X202939Y230412D02*
X202309Y230882D01*
X201994Y231430D01*
X201889Y232057D01*
X202099Y232840D01*
X202624Y233388D01*
X203254Y233545D01*
X203884Y233467D01*
X204409Y233153D01*
X205459Y231587D01*
X206194Y230882D01*
X207244Y230412D01*
X208189Y230255D01*
Y233545D01*
G01X201889Y238200D02*
X202099Y237573D01*
X202624Y237103D01*
X203254Y236790D01*
X204094Y236555D01*
X205039Y236477D01*
X205984Y236555D01*
X206824Y236790D01*
X207454Y237103D01*
X207979Y237573D01*
X208189Y238200D01*
X207979Y238827D01*
X207454Y239297D01*
X206824Y239610D01*
X205984Y239845D01*
X205039Y239923D01*
X204094Y239845D01*
X203254Y239610D01*
X202624Y239297D01*
X202099Y238827D01*
X201889Y238200D01*
G01X207244Y242777D02*
X207769Y243247D01*
X208084Y243795D01*
X208189Y244500D01*
X207979Y245205D01*
X207559Y245753D01*
X206824Y246145D01*
X205984Y246223D01*
X205144Y246067D01*
X204619Y245675D01*
X204199Y245127D01*
X204094Y244578D01*
X204199Y244030D01*
X204619Y243325D01*
X201889Y243560D01*
Y245675D01*
G01Y250800D02*
X202099Y250173D01*
X202624Y249703D01*
X203254Y249390D01*
X204094Y249155D01*
X205039Y249077D01*
X205984Y249155D01*
X206824Y249390D01*
X207454Y249703D01*
X207979Y250173D01*
X208189Y250800D01*
X207979Y251427D01*
X207454Y251897D01*
X206824Y252210D01*
X205984Y252445D01*
X205039Y252523D01*
X204094Y252445D01*
X203254Y252210D01*
X202624Y251897D01*
X202099Y251427D01*
X201889Y250800D01*
G01X208399Y257100D02*
X208294Y256943D01*
X208084D01*
X207979Y257100D01*
X208084Y257257D01*
X208294D01*
X208399Y257100D01*
G01X206929Y261677D02*
X207664Y262147D01*
X208084Y262773D01*
X208189Y263478D01*
X208084Y264105D01*
X207559Y264732D01*
X206929Y265123D01*
X206299Y265202D01*
X205564Y265045D01*
X205039Y264497D01*
X204829Y263948D01*
Y263243D01*
G01Y263948D02*
X204514Y264418D01*
X203989Y264810D01*
X203359Y264967D01*
X202729Y264810D01*
X202204Y264418D01*
X201889Y263713D01*
X201994Y263008D01*
X202414Y262303D01*
G01X207454Y268368D02*
X207979Y268917D01*
X208189Y269543D01*
X207979Y270170D01*
X207349Y270718D01*
X206404Y271110D01*
X205459Y271267D01*
X204304D01*
X203359Y271110D01*
X202519Y270718D01*
X202099Y270248D01*
X201889Y269700D01*
X202099Y269073D01*
X202519Y268603D01*
X203149Y268290D01*
X203989Y268133D01*
X204724Y268290D01*
X205459Y268682D01*
X205879Y269152D01*
X205984Y269700D01*
X205774Y270327D01*
X205249Y270797D01*
X204304Y271267D01*
G01X218687Y224112D02*
X218057Y224582D01*
X217742Y225130D01*
X217637Y225757D01*
X217847Y226540D01*
X218372Y227088D01*
X219002Y227245D01*
X219632Y227167D01*
X220157Y226853D01*
X221207Y225287D01*
X221942Y224582D01*
X222992Y224112D01*
X223937Y223955D01*
Y227245D01*
G01X218687Y230412D02*
X218057Y230882D01*
X217742Y231430D01*
X217637Y232057D01*
X217847Y232840D01*
X218372Y233388D01*
X219002Y233545D01*
X219632Y233467D01*
X220157Y233153D01*
X221207Y231587D01*
X221942Y230882D01*
X222992Y230412D01*
X223937Y230255D01*
Y233545D01*
G01X217637Y238200D02*
X217847Y237573D01*
X218372Y237103D01*
X219002Y236790D01*
X219842Y236555D01*
X220787Y236477D01*
X221732Y236555D01*
X222572Y236790D01*
X223202Y237103D01*
X223727Y237573D01*
X223937Y238200D01*
X223727Y238827D01*
X223202Y239297D01*
X222572Y239610D01*
X221732Y239845D01*
X220787Y239923D01*
X219842Y239845D01*
X219002Y239610D01*
X218372Y239297D01*
X217847Y238827D01*
X217637Y238200D01*
G01X223937Y244343D02*
X222572Y244500D01*
X221417Y244735D01*
X220367Y245048D01*
X219212Y245440D01*
X217637Y246067D01*
Y242933D01*
G01X224147Y250800D02*
X224042Y250643D01*
X223832D01*
X223727Y250800D01*
X223832Y250957D01*
X224042D01*
X224147Y250800D01*
G01X223937Y257100D02*
X223832Y257648D01*
X223517Y258275D01*
X222992Y258667D01*
X222257Y258823D01*
X221522Y258667D01*
X220892Y258197D01*
X220577Y257492D01*
Y256708D01*
X220367Y256238D01*
X219842Y255847D01*
X219107Y255690D01*
X218372Y255925D01*
X217847Y256473D01*
X217637Y257100D01*
X217847Y257727D01*
X218372Y258275D01*
X219107Y258510D01*
X219842Y258353D01*
X220367Y257962D01*
X220577Y257492D01*
Y256708D01*
X220892Y256003D01*
X221522Y255533D01*
X222257Y255377D01*
X222992Y255533D01*
X223517Y255925D01*
X223832Y256552D01*
X223937Y257100D01*
G01Y263243D02*
X222572Y263400D01*
X221417Y263635D01*
X220367Y263948D01*
X219212Y264340D01*
X217637Y264967D01*
Y261833D01*
G01X226561Y227712D02*
X225931Y228182D01*
X225616Y228730D01*
X225511Y229357D01*
X225721Y230140D01*
X226246Y230688D01*
X226876Y230845D01*
X227506Y230767D01*
X228031Y230453D01*
X229081Y228887D01*
X229816Y228182D01*
X230866Y227712D01*
X231811Y227555D01*
Y230845D01*
G01X226561Y234012D02*
X225931Y234482D01*
X225616Y235030D01*
X225511Y235657D01*
X225721Y236440D01*
X226246Y236988D01*
X226876Y237145D01*
X227506Y237067D01*
X228031Y236753D01*
X229081Y235187D01*
X229816Y234482D01*
X230866Y234012D01*
X231811Y233855D01*
Y237145D01*
G01Y241800D02*
X231706Y242348D01*
X231391Y242975D01*
X230866Y243367D01*
X230131Y243523D01*
X229396Y243367D01*
X228766Y242897D01*
X228451Y242192D01*
Y241408D01*
X228241Y240938D01*
X227716Y240547D01*
X226981Y240390D01*
X226246Y240625D01*
X225721Y241173D01*
X225511Y241800D01*
X225721Y242427D01*
X226246Y242975D01*
X226981Y243210D01*
X227716Y243053D01*
X228241Y242662D01*
X228451Y242192D01*
Y241408D01*
X228766Y240703D01*
X229396Y240233D01*
X230131Y240077D01*
X230866Y240233D01*
X231391Y240625D01*
X231706Y241252D01*
X231811Y241800D01*
G01X229186Y246612D02*
X228451Y247160D01*
X228031Y247630D01*
X227821Y248257D01*
X228031Y248805D01*
X228451Y249197D01*
X229081Y249510D01*
X229816Y249588D01*
X230446Y249510D01*
X231076Y249197D01*
X231601Y248727D01*
X231811Y248178D01*
X231601Y247552D01*
X230971Y247003D01*
X230026Y246690D01*
X228976Y246612D01*
X227611Y246768D01*
X226876Y247003D01*
X226141Y247395D01*
X225616Y247943D01*
X225511Y248492D01*
X225721Y249040D01*
X226246Y249432D01*
G01X232021Y254400D02*
X231916Y254243D01*
X231706D01*
X231601Y254400D01*
X231706Y254557D01*
X231916D01*
X232021Y254400D01*
G01X229186Y259212D02*
X228451Y259760D01*
X228031Y260230D01*
X227821Y260857D01*
X228031Y261405D01*
X228451Y261797D01*
X229081Y262110D01*
X229816Y262188D01*
X230446Y262110D01*
X231076Y261797D01*
X231601Y261327D01*
X231811Y260778D01*
X231601Y260152D01*
X230971Y259603D01*
X230026Y259290D01*
X228976Y259212D01*
X227611Y259368D01*
X226876Y259603D01*
X226141Y259995D01*
X225616Y260543D01*
X225511Y261092D01*
X225721Y261640D01*
X226246Y262032D01*
G01X231811Y267000D02*
X225511D01*
X226771Y266060D01*
G01X231811D02*
Y267940D01*
G01X316103Y228477D02*
X316838Y228947D01*
X317258Y229573D01*
X317363Y230278D01*
X317258Y230905D01*
X316733Y231532D01*
X316103Y231923D01*
X315473Y232002D01*
X314738Y231845D01*
X314213Y231297D01*
X314003Y230748D01*
Y230043D01*
G01Y230748D02*
X313688Y231218D01*
X313163Y231610D01*
X312533Y231767D01*
X311903Y231610D01*
X311378Y231218D01*
X311063Y230513D01*
X311168Y229808D01*
X311588Y229103D01*
G01X317363Y236500D02*
X311063D01*
X312323Y235560D01*
G01X317363D02*
Y237440D01*
G01Y243740D02*
X311063D01*
X315578Y240842D01*
Y244758D01*
G01X312113Y247612D02*
X311483Y248082D01*
X311168Y248630D01*
X311063Y249257D01*
X311273Y250040D01*
X311798Y250588D01*
X312428Y250745D01*
X313058Y250667D01*
X313583Y250353D01*
X314633Y248787D01*
X315368Y248082D01*
X316418Y247612D01*
X317363Y247455D01*
Y250745D01*
G01X317573Y255400D02*
X317468Y255243D01*
X317258D01*
X317153Y255400D01*
X317258Y255557D01*
X317468D01*
X317573Y255400D01*
G01X317363Y261700D02*
X311063D01*
X312323Y260760D01*
G01X317363D02*
Y262640D01*
G01X316103Y266277D02*
X316838Y266747D01*
X317258Y267373D01*
X317363Y268078D01*
X317258Y268705D01*
X316733Y269332D01*
X316103Y269723D01*
X315473Y269802D01*
X314738Y269645D01*
X314213Y269097D01*
X314003Y268548D01*
Y267843D01*
G01Y268548D02*
X313688Y269018D01*
X313163Y269410D01*
X312533Y269567D01*
X311903Y269410D01*
X311378Y269018D01*
X311063Y268313D01*
X311168Y267608D01*
X311588Y266903D01*
G01X380118Y226677D02*
X380853Y227147D01*
X381273Y227773D01*
X381378Y228478D01*
X381273Y229105D01*
X380748Y229732D01*
X380118Y230123D01*
X379488Y230202D01*
X378753Y230045D01*
X378228Y229497D01*
X378018Y228948D01*
Y228243D01*
G01Y228948D02*
X377703Y229418D01*
X377178Y229810D01*
X376548Y229967D01*
X375918Y229810D01*
X375393Y229418D01*
X375078Y228713D01*
X375183Y228008D01*
X375603Y227303D01*
G01X381378Y234543D02*
X380013Y234700D01*
X378858Y234935D01*
X377808Y235248D01*
X376653Y235640D01*
X375078Y236267D01*
Y233133D01*
G01X381378Y241000D02*
X381273Y241548D01*
X380958Y242175D01*
X380433Y242567D01*
X379698Y242723D01*
X378963Y242567D01*
X378333Y242097D01*
X378018Y241392D01*
Y240608D01*
X377808Y240138D01*
X377283Y239747D01*
X376548Y239590D01*
X375813Y239825D01*
X375288Y240373D01*
X375078Y241000D01*
X375288Y241627D01*
X375813Y242175D01*
X376548Y242410D01*
X377283Y242253D01*
X377808Y241862D01*
X378018Y241392D01*
Y240608D01*
X378333Y239903D01*
X378963Y239433D01*
X379698Y239277D01*
X380433Y239433D01*
X380958Y239825D01*
X381273Y240452D01*
X381378Y241000D01*
G01X376128Y245812D02*
X375498Y246282D01*
X375183Y246830D01*
X375078Y247457D01*
X375288Y248240D01*
X375813Y248788D01*
X376443Y248945D01*
X377073Y248867D01*
X377598Y248553D01*
X378648Y246987D01*
X379383Y246282D01*
X380433Y245812D01*
X381378Y245655D01*
Y248945D01*
G01X381588Y253600D02*
X381483Y253443D01*
X381273D01*
X381168Y253600D01*
X381273Y253757D01*
X381483D01*
X381588Y253600D01*
G01X376128Y258412D02*
X375498Y258882D01*
X375183Y259430D01*
X375078Y260057D01*
X375288Y260840D01*
X375813Y261388D01*
X376443Y261545D01*
X377073Y261467D01*
X377598Y261153D01*
X378648Y259587D01*
X379383Y258882D01*
X380433Y258412D01*
X381378Y258255D01*
Y261545D01*
G01Y266200D02*
X381273Y266748D01*
X380958Y267375D01*
X380433Y267767D01*
X379698Y267923D01*
X378963Y267767D01*
X378333Y267297D01*
X378018Y266592D01*
Y265808D01*
X377808Y265338D01*
X377283Y264947D01*
X376548Y264790D01*
X375813Y265025D01*
X375288Y265573D01*
X375078Y266200D01*
X375288Y266827D01*
X375813Y267375D01*
X376548Y267610D01*
X377283Y267453D01*
X377808Y267062D01*
X378018Y266592D01*
Y265808D01*
X378333Y265103D01*
X378963Y264633D01*
X379698Y264477D01*
X380433Y264633D01*
X380958Y265025D01*
X381273Y265652D01*
X381378Y266200D01*
G01X448307Y227140D02*
X442007D01*
X446522Y224242D01*
Y228158D01*
G01X448307Y233440D02*
X442007D01*
X446522Y230542D01*
Y234458D01*
G01X447362Y237077D02*
X447887Y237547D01*
X448202Y238095D01*
X448307Y238800D01*
X448097Y239505D01*
X447677Y240053D01*
X446942Y240445D01*
X446102Y240523D01*
X445262Y240367D01*
X444737Y239975D01*
X444317Y239427D01*
X444212Y238878D01*
X444317Y238330D01*
X444737Y237625D01*
X442007Y237860D01*
Y239975D01*
G01X448307Y245100D02*
X442007D01*
X443267Y244160D01*
G01X448307D02*
Y246040D01*
G01X448517Y251400D02*
X448412Y251243D01*
X448202D01*
X448097Y251400D01*
X448202Y251557D01*
X448412D01*
X448517Y251400D01*
G01X447362Y255977D02*
X447887Y256447D01*
X448202Y256995D01*
X448307Y257700D01*
X448097Y258405D01*
X447677Y258953D01*
X446942Y259345D01*
X446102Y259423D01*
X445262Y259267D01*
X444737Y258875D01*
X444317Y258327D01*
X444212Y257778D01*
X444317Y257230D01*
X444737Y256525D01*
X442007Y256760D01*
Y258875D01*
G01X448307Y263843D02*
X446942Y264000D01*
X445787Y264235D01*
X444737Y264548D01*
X443582Y264940D01*
X442007Y265567D01*
Y262433D01*
G01X455917Y-335560D02*
X456544Y-336085D01*
X457249Y-336400D01*
X457875D01*
X458502Y-336085D01*
X458972Y-335560D01*
X459207Y-334825D01*
X459050Y-334090D01*
X458659Y-333460D01*
X457954Y-333040D01*
X457014Y-332830D01*
X456465Y-332410D01*
X456230Y-331675D01*
X456387Y-330940D01*
X456779Y-330415D01*
X457327Y-330100D01*
X457875D01*
X458424Y-330310D01*
X458894Y-330835D01*
G01X462217Y-336400D02*
Y-330100D01*
G01X465507D02*
Y-336400D01*
G01Y-333250D02*
X462217D01*
G01X469222Y-330100D02*
X471102D01*
G01X470162D02*
Y-336400D01*
G01X469222D02*
X471102D01*
G01X478029D02*
X474895D01*
Y-330100D01*
X478029D01*
G01X476775Y-333145D02*
X474895D01*
G01X480960Y-336400D02*
Y-330100D01*
X484564Y-336400D01*
Y-330100D01*
G01X488905Y-337555D02*
X489219Y-336190D01*
G01X495362Y-330100D02*
Y-336400D01*
G01X493560Y-330100D02*
X497164D01*
G01X499704Y-336400D02*
X501662Y-330100D01*
X503620Y-336400D01*
G01X502915Y-334195D02*
X500409D01*
G01X507022Y-330100D02*
X508902D01*
G01X507962D02*
Y-336400D01*
G01X507022D02*
X508902D01*
G01X511912Y-330100D02*
X513009Y-336400D01*
X514262Y-330100D01*
X515515Y-336400D01*
X516612Y-330100D01*
G01X518604Y-336400D02*
X520562Y-330100D01*
X522520Y-336400D01*
G01X521815Y-334195D02*
X519309D01*
G01X525060Y-336400D02*
Y-330100D01*
X528664Y-336400D01*
Y-330100D01*
G01X537895Y-336400D02*
Y-330100D01*
X539854D01*
X540480Y-330415D01*
X540872Y-330835D01*
X541029Y-331675D01*
X540872Y-332515D01*
X540402Y-333040D01*
X539854Y-333355D01*
X537895D01*
G01X539854D02*
X541029Y-336400D01*
G01X545762Y-336610D02*
X545605Y-336505D01*
Y-336295D01*
X545762Y-336190D01*
X545919Y-336295D01*
Y-336505D01*
X545762Y-336610D01*
G01X552062Y-336400D02*
X551435Y-336295D01*
X550887Y-335875D01*
X550417Y-335245D01*
X550104Y-334510D01*
X549947Y-333670D01*
Y-332830D01*
X550104Y-331990D01*
X550417Y-331255D01*
X550887Y-330625D01*
X551435Y-330205D01*
X552062Y-330100D01*
X552689Y-330205D01*
X553237Y-330625D01*
X553707Y-331255D01*
X554020Y-331990D01*
X554177Y-332830D01*
Y-333670D01*
X554020Y-334510D01*
X553707Y-335245D01*
X553237Y-335875D01*
X552689Y-336295D01*
X552062Y-336400D01*
G01X558362Y-336610D02*
X558205Y-336505D01*
Y-336295D01*
X558362Y-336190D01*
X558519Y-336295D01*
Y-336505D01*
X558362Y-336610D01*
G01X566385Y-330625D02*
X565915Y-330310D01*
X565367Y-330100D01*
X564740D01*
X564035Y-330415D01*
X563487Y-330940D01*
X563095Y-331570D01*
X562782Y-332620D01*
X562704Y-333565D01*
X562860Y-334510D01*
X563095Y-335140D01*
X563565Y-335770D01*
X564114Y-336190D01*
X564662Y-336400D01*
X565210D01*
X565759Y-336190D01*
X566229Y-335875D01*
X566620Y-335455D01*
G01X570962Y-336610D02*
X570805Y-336505D01*
Y-336295D01*
X570962Y-336190D01*
X571119Y-336295D01*
Y-336505D01*
X570962Y-336610D01*
G01X455839Y-326400D02*
Y-320100D01*
G01X458815D02*
X455839Y-323985D01*
G01X459285Y-326400D02*
X457170Y-322200D01*
G01X462139Y-320100D02*
Y-324615D01*
X462452Y-325560D01*
X463079Y-326190D01*
X463862Y-326400D01*
X464645Y-326190D01*
X465272Y-325560D01*
X465585Y-324615D01*
Y-320100D01*
G01X471729Y-326400D02*
X468595D01*
Y-320100D01*
X471729D01*
G01X470475Y-323145D02*
X468595D01*
G01X475522Y-320100D02*
X477402D01*
G01X476462D02*
Y-326400D01*
G01X475522D02*
X477402D01*
G01X487417Y-325560D02*
X488044Y-326085D01*
X488749Y-326400D01*
X489375D01*
X490002Y-326085D01*
X490472Y-325560D01*
X490707Y-324825D01*
X490550Y-324090D01*
X490159Y-323460D01*
X489454Y-323040D01*
X488514Y-322830D01*
X487965Y-322410D01*
X487730Y-321675D01*
X487887Y-320940D01*
X488279Y-320415D01*
X488827Y-320100D01*
X489375D01*
X489924Y-320310D01*
X490394Y-320835D01*
G01X493717Y-326400D02*
Y-320100D01*
G01X497007D02*
Y-326400D01*
G01Y-323250D02*
X493717D01*
G01X499704Y-326400D02*
X501662Y-320100D01*
X503620Y-326400D01*
G01X502915Y-324195D02*
X500409D01*
G01X506160Y-326400D02*
Y-320100D01*
X509764Y-326400D01*
Y-320100D01*
G01X518917Y-326400D02*
Y-320100D01*
G01X522207D02*
Y-326400D01*
G01Y-323250D02*
X518917D01*
G01X525217Y-325560D02*
X525844Y-326085D01*
X526549Y-326400D01*
X527175D01*
X527802Y-326085D01*
X528272Y-325560D01*
X528507Y-324825D01*
X528350Y-324090D01*
X527959Y-323460D01*
X527254Y-323040D01*
X526314Y-322830D01*
X525765Y-322410D01*
X525530Y-321675D01*
X525687Y-320940D01*
X526079Y-320415D01*
X526627Y-320100D01*
X527175D01*
X527724Y-320310D01*
X528194Y-320835D01*
G01X532222Y-320100D02*
X534102D01*
G01X533162D02*
Y-326400D01*
G01X532222D02*
X534102D01*
G01X537504D02*
X539462Y-320100D01*
X541420Y-326400D01*
G01X540715Y-324195D02*
X538209D01*
G01X543960Y-326400D02*
Y-320100D01*
X547564Y-326400D01*
Y-320100D01*
G01X552532Y-323250D02*
X554099D01*
Y-325140D01*
X553629Y-325770D01*
X553080Y-326190D01*
X552297Y-326400D01*
X551514Y-326190D01*
X550965Y-325770D01*
X550495Y-325140D01*
X550182Y-324405D01*
X550025Y-323565D01*
Y-322830D01*
X550182Y-322200D01*
X550495Y-321465D01*
X550965Y-320835D01*
X551435Y-320415D01*
X552062Y-320100D01*
X552610D01*
X553237Y-320310D01*
X553707Y-320730D01*
G01X558205Y-327555D02*
X558519Y-326190D01*
G01X564662Y-320100D02*
Y-326400D01*
G01X562860Y-320100D02*
X566464D01*
G01X569004Y-326400D02*
X570962Y-320100D01*
X572920Y-326400D01*
G01X572215Y-324195D02*
X569709D01*
G01X577262Y-326400D02*
X576635Y-326295D01*
X576087Y-325875D01*
X575617Y-325245D01*
X575304Y-324510D01*
X575147Y-323670D01*
Y-322830D01*
X575304Y-321990D01*
X575617Y-321255D01*
X576087Y-320625D01*
X576635Y-320205D01*
X577262Y-320100D01*
X577889Y-320205D01*
X578437Y-320625D01*
X578907Y-321255D01*
X579220Y-321990D01*
X579377Y-322830D01*
Y-323670D01*
X579220Y-324510D01*
X578907Y-325245D01*
X578437Y-325875D01*
X577889Y-326295D01*
X577262Y-326400D01*
G01X589862D02*
Y-323565D01*
X588295Y-320100D01*
G01X591429D02*
X589862Y-323565D01*
G01X594439Y-320100D02*
Y-324615D01*
X594752Y-325560D01*
X595379Y-326190D01*
X596162Y-326400D01*
X596945Y-326190D01*
X597572Y-325560D01*
X597885Y-324615D01*
Y-320100D01*
G01X600504Y-326400D02*
X602462Y-320100D01*
X604420Y-326400D01*
G01X603715Y-324195D02*
X601209D01*
G01X606960Y-326400D02*
Y-320100D01*
X610564Y-326400D01*
Y-320100D01*
G01X455760Y-316400D02*
Y-310100D01*
X459364Y-316400D01*
Y-310100D01*
G01X463862Y-316400D02*
X463235Y-316295D01*
X462687Y-315875D01*
X462217Y-315245D01*
X461904Y-314510D01*
X461747Y-313670D01*
Y-312830D01*
X461904Y-311990D01*
X462217Y-311255D01*
X462687Y-310625D01*
X463235Y-310205D01*
X463862Y-310100D01*
X464489Y-310205D01*
X465037Y-310625D01*
X465507Y-311255D01*
X465820Y-311990D01*
X465977Y-312830D01*
Y-313670D01*
X465820Y-314510D01*
X465507Y-315245D01*
X465037Y-315875D01*
X464489Y-316295D01*
X463862Y-316400D01*
G01X470162Y-316610D02*
X470005Y-316505D01*
Y-316295D01*
X470162Y-316190D01*
X470319Y-316295D01*
Y-316505D01*
X470162Y-316610D01*
G01X476462Y-316400D02*
Y-310100D01*
X475522Y-311360D01*
G01Y-316400D02*
X477402D01*
G01X482762D02*
X483310Y-316295D01*
X483937Y-315980D01*
X484329Y-315455D01*
X484485Y-314720D01*
X484329Y-313985D01*
X483859Y-313355D01*
X483154Y-313040D01*
X482370D01*
X481900Y-312830D01*
X481509Y-312305D01*
X481352Y-311570D01*
X481587Y-310835D01*
X482135Y-310310D01*
X482762Y-310100D01*
X483389Y-310310D01*
X483937Y-310835D01*
X484172Y-311570D01*
X484015Y-312305D01*
X483624Y-312830D01*
X483154Y-313040D01*
X482370D01*
X481665Y-313355D01*
X481195Y-313985D01*
X481039Y-314720D01*
X481195Y-315455D01*
X481587Y-315980D01*
X482214Y-316295D01*
X482762Y-316400D01*
G01X489062D02*
X489610Y-316295D01*
X490237Y-315980D01*
X490629Y-315455D01*
X490785Y-314720D01*
X490629Y-313985D01*
X490159Y-313355D01*
X489454Y-313040D01*
X488670D01*
X488200Y-312830D01*
X487809Y-312305D01*
X487652Y-311570D01*
X487887Y-310835D01*
X488435Y-310310D01*
X489062Y-310100D01*
X489689Y-310310D01*
X490237Y-310835D01*
X490472Y-311570D01*
X490315Y-312305D01*
X489924Y-312830D01*
X489454Y-313040D01*
X488670D01*
X487965Y-313355D01*
X487495Y-313985D01*
X487339Y-314720D01*
X487495Y-315455D01*
X487887Y-315980D01*
X488514Y-316295D01*
X489062Y-316400D01*
G01X495205Y-317555D02*
X495519Y-316190D01*
G01X499312Y-310100D02*
X500409Y-316400D01*
X501662Y-310100D01*
X502915Y-316400D01*
X504012Y-310100D01*
G01X509529Y-316400D02*
X506395D01*
Y-310100D01*
X509529D01*
G01X508275Y-313145D02*
X506395D01*
G01X512460Y-316400D02*
Y-310100D01*
X516064Y-316400D01*
Y-310100D01*
G01X525217Y-316400D02*
Y-310100D01*
G01X528507D02*
Y-316400D01*
G01Y-313250D02*
X525217D01*
G01X530812Y-310100D02*
X531909Y-316400D01*
X533162Y-310100D01*
X534415Y-316400D01*
X535512Y-310100D01*
G01X537504Y-316400D02*
X539462Y-310100D01*
X541420Y-316400D01*
G01X540715Y-314195D02*
X538209D01*
G01X550574Y-311150D02*
X551044Y-310520D01*
X551592Y-310205D01*
X552219Y-310100D01*
X553002Y-310310D01*
X553550Y-310835D01*
X553707Y-311465D01*
X553629Y-312095D01*
X553315Y-312620D01*
X551749Y-313670D01*
X551044Y-314405D01*
X550574Y-315455D01*
X550417Y-316400D01*
X553707D01*
G01X556560D02*
Y-310100D01*
X560164Y-316400D01*
Y-310100D01*
G01X562939Y-316400D02*
Y-310100D01*
X564505D01*
X565132Y-310415D01*
X565602Y-310835D01*
X565994Y-311465D01*
X566307Y-312200D01*
X566385Y-313250D01*
X566307Y-314300D01*
X565994Y-315035D01*
X565602Y-315665D01*
X565132Y-316085D01*
X564505Y-316400D01*
X562939D01*
G01X575695D02*
Y-310100D01*
X577654D01*
X578280Y-310415D01*
X578672Y-310835D01*
X578829Y-311675D01*
X578672Y-312515D01*
X578202Y-313040D01*
X577654Y-313355D01*
X575695D01*
G01X577654D02*
X578829Y-316400D01*
G01X581839D02*
Y-310100D01*
X583405D01*
X584032Y-310415D01*
X584502Y-310835D01*
X584894Y-311465D01*
X585207Y-312200D01*
X585285Y-313250D01*
X585207Y-314300D01*
X584894Y-315035D01*
X584502Y-315665D01*
X584032Y-316085D01*
X583405Y-316400D01*
X581839D01*
G01X589862Y-316610D02*
X589705Y-316505D01*
Y-316295D01*
X589862Y-316190D01*
X590019Y-316295D01*
Y-316505D01*
X589862Y-316610D01*
G01X479862Y-303700D02*
X477342Y-303283D01*
X475137Y-301617D01*
X473247Y-299117D01*
X471987Y-296200D01*
X471357Y-292867D01*
Y-289533D01*
X471987Y-286200D01*
X473247Y-283283D01*
X475137Y-280784D01*
X477342Y-279117D01*
X479862Y-278700D01*
X482382Y-279117D01*
X484587Y-280784D01*
X486477Y-283283D01*
X487737Y-286200D01*
X488367Y-289533D01*
Y-292867D01*
X487737Y-296200D01*
X486477Y-299117D01*
X484587Y-301617D01*
X482382Y-303283D01*
X479862Y-303700D01*
G01X482382Y-297033D02*
X486162Y-303700D01*
G01X499707Y-287034D02*
Y-298700D01*
X500967Y-301617D01*
X502857Y-303283D01*
X505062Y-303700D01*
X507267Y-303283D01*
X509157Y-301617D01*
X510417Y-298700D01*
G01Y-303700D02*
Y-287034D01*
G01X535932Y-303700D02*
Y-287034D01*
G01Y-289950D02*
X534672Y-288284D01*
X532782Y-287450D01*
X530577Y-287034D01*
X528372Y-287867D01*
X526482Y-289533D01*
X525222Y-292034D01*
X524592Y-295367D01*
X525222Y-298700D01*
X526482Y-301201D01*
X528372Y-302867D01*
X530577Y-303700D01*
X532782Y-303283D01*
X534672Y-302034D01*
X535932Y-300367D01*
G01X550107Y-303700D02*
Y-287034D01*
G01Y-291200D02*
X551367Y-289117D01*
X553257Y-287450D01*
X555777Y-287034D01*
X557982Y-287450D01*
X559872Y-289117D01*
X560817Y-292034D01*
Y-303700D01*
G01X580662Y-278700D02*
Y-303700D01*
G01X576252Y-287034D02*
X585072D01*
G01X611532Y-303700D02*
Y-287034D01*
G01Y-289950D02*
X610272Y-288284D01*
X608382Y-287450D01*
X606177Y-287034D01*
X603972Y-287867D01*
X602082Y-289533D01*
X600822Y-292034D01*
X600192Y-295367D01*
X600822Y-298700D01*
X602082Y-301201D01*
X603972Y-302867D01*
X606177Y-303700D01*
X608382Y-303283D01*
X610272Y-302034D01*
X611532Y-300367D01*
G01X529725Y226077D02*
X530250Y226547D01*
X530565Y227095D01*
X530670Y227800D01*
X530460Y228505D01*
X530040Y229053D01*
X529305Y229445D01*
X528465Y229523D01*
X527625Y229367D01*
X527100Y228975D01*
X526680Y228427D01*
X526575Y227878D01*
X526680Y227330D01*
X527100Y226625D01*
X524370Y226860D01*
Y228975D01*
G01X525420Y232612D02*
X524790Y233082D01*
X524475Y233630D01*
X524370Y234257D01*
X524580Y235040D01*
X525105Y235588D01*
X525735Y235745D01*
X526365Y235667D01*
X526890Y235353D01*
X527940Y233787D01*
X528675Y233082D01*
X529725Y232612D01*
X530670Y232455D01*
Y235745D01*
G01Y240243D02*
X529305Y240400D01*
X528150Y240635D01*
X527100Y240948D01*
X525945Y241340D01*
X524370Y241967D01*
Y238833D01*
G01X529725Y244977D02*
X530250Y245447D01*
X530565Y245995D01*
X530670Y246700D01*
X530460Y247405D01*
X530040Y247953D01*
X529305Y248345D01*
X528465Y248423D01*
X527625Y248267D01*
X527100Y247875D01*
X526680Y247327D01*
X526575Y246778D01*
X526680Y246230D01*
X527100Y245525D01*
X524370Y245760D01*
Y247875D01*
G01X530880Y253000D02*
X530775Y252843D01*
X530565D01*
X530460Y253000D01*
X530565Y253157D01*
X530775D01*
X530880Y253000D01*
G01X525420Y257812D02*
X524790Y258282D01*
X524475Y258830D01*
X524370Y259457D01*
X524580Y260240D01*
X525105Y260788D01*
X525735Y260945D01*
X526365Y260867D01*
X526890Y260553D01*
X527940Y258987D01*
X528675Y258282D01*
X529725Y257812D01*
X530670Y257655D01*
Y260945D01*
G01X524370Y265600D02*
X524580Y264973D01*
X525105Y264503D01*
X525735Y264190D01*
X526575Y263955D01*
X527520Y263877D01*
X528465Y263955D01*
X529305Y264190D01*
X529935Y264503D01*
X530460Y264973D01*
X530670Y265600D01*
X530460Y266227D01*
X529935Y266697D01*
X529305Y267010D01*
X528465Y267245D01*
X527520Y267323D01*
X526575Y267245D01*
X525735Y267010D01*
X525105Y266697D01*
X524580Y266227D01*
X524370Y265600D01*
G01X596654Y223977D02*
X597179Y224447D01*
X597494Y224995D01*
X597599Y225700D01*
X597389Y226405D01*
X596969Y226953D01*
X596234Y227345D01*
X595394Y227423D01*
X594554Y227267D01*
X594029Y226875D01*
X593609Y226327D01*
X593504Y225778D01*
X593609Y225230D01*
X594029Y224525D01*
X591299Y224760D01*
Y226875D01*
G01X596864Y230668D02*
X597389Y231217D01*
X597599Y231843D01*
X597389Y232470D01*
X596759Y233018D01*
X595814Y233410D01*
X594869Y233567D01*
X593714D01*
X592769Y233410D01*
X591929Y233018D01*
X591509Y232548D01*
X591299Y232000D01*
X591509Y231373D01*
X591929Y230903D01*
X592559Y230590D01*
X593399Y230433D01*
X594134Y230590D01*
X594869Y230982D01*
X595289Y231452D01*
X595394Y232000D01*
X595184Y232627D01*
X594659Y233097D01*
X593714Y233567D01*
G01X597599Y239240D02*
X591299D01*
X595814Y236342D01*
Y240258D01*
G01X597599Y245540D02*
X591299D01*
X595814Y242642D01*
Y246558D01*
G01X597809Y250900D02*
X597704Y250743D01*
X597494D01*
X597389Y250900D01*
X597494Y251057D01*
X597704D01*
X597809Y250900D01*
G01X597599Y258140D02*
X591299D01*
X595814Y255242D01*
Y259158D01*
G01X596864Y262168D02*
X597389Y262717D01*
X597599Y263343D01*
X597389Y263970D01*
X596759Y264518D01*
X595814Y264910D01*
X594869Y265067D01*
X593714D01*
X592769Y264910D01*
X591929Y264518D01*
X591509Y264048D01*
X591299Y263500D01*
X591509Y262873D01*
X591929Y262403D01*
X592559Y262090D01*
X593399Y261933D01*
X594134Y262090D01*
X594869Y262482D01*
X595289Y262952D01*
X595394Y263500D01*
X595184Y264127D01*
X594659Y264597D01*
X593714Y265067D01*
G01X630376Y227012D02*
X629641Y227560D01*
X629221Y228030D01*
X629011Y228657D01*
X629221Y229205D01*
X629641Y229597D01*
X630271Y229910D01*
X631006Y229988D01*
X631636Y229910D01*
X632266Y229597D01*
X632791Y229127D01*
X633001Y228578D01*
X632791Y227952D01*
X632161Y227403D01*
X631216Y227090D01*
X630166Y227012D01*
X628801Y227168D01*
X628066Y227403D01*
X627331Y227795D01*
X626806Y228343D01*
X626701Y228892D01*
X626911Y229440D01*
X627436Y229832D01*
G01X627751Y233312D02*
X627121Y233782D01*
X626806Y234330D01*
X626701Y234957D01*
X626911Y235740D01*
X627436Y236288D01*
X628066Y236445D01*
X628696Y236367D01*
X629221Y236053D01*
X630271Y234487D01*
X631006Y233782D01*
X632056Y233312D01*
X633001Y233155D01*
Y236445D01*
G01X632266Y239768D02*
X632791Y240317D01*
X633001Y240943D01*
X632791Y241570D01*
X632161Y242118D01*
X631216Y242510D01*
X630271Y242667D01*
X629116D01*
X628171Y242510D01*
X627331Y242118D01*
X626911Y241648D01*
X626701Y241100D01*
X626911Y240473D01*
X627331Y240003D01*
X627961Y239690D01*
X628801Y239533D01*
X629536Y239690D01*
X630271Y240082D01*
X630691Y240552D01*
X630796Y241100D01*
X630586Y241727D01*
X630061Y242197D01*
X629116Y242667D01*
G01X633001Y247400D02*
X632896Y247948D01*
X632581Y248575D01*
X632056Y248967D01*
X631321Y249123D01*
X630586Y248967D01*
X629956Y248497D01*
X629641Y247792D01*
Y247008D01*
X629431Y246538D01*
X628906Y246147D01*
X628171Y245990D01*
X627436Y246225D01*
X626911Y246773D01*
X626701Y247400D01*
X626911Y248027D01*
X627436Y248575D01*
X628171Y248810D01*
X628906Y248653D01*
X629431Y248262D01*
X629641Y247792D01*
Y247008D01*
X629956Y246303D01*
X630586Y245833D01*
X631321Y245677D01*
X632056Y245833D01*
X632581Y246225D01*
X632896Y246852D01*
X633001Y247400D01*
G01X633211Y253700D02*
X633106Y253543D01*
X632896D01*
X632791Y253700D01*
X632896Y253857D01*
X633106D01*
X633211Y253700D01*
G01X632056Y258277D02*
X632581Y258747D01*
X632896Y259295D01*
X633001Y260000D01*
X632791Y260705D01*
X632371Y261253D01*
X631636Y261645D01*
X630796Y261723D01*
X629956Y261567D01*
X629431Y261175D01*
X629011Y260627D01*
X628906Y260078D01*
X629011Y259530D01*
X629431Y258825D01*
X626701Y259060D01*
Y261175D01*
G01X633001Y266300D02*
X626701D01*
X627961Y265360D01*
G01X633001D02*
Y267240D01*
G01X651212Y-283400D02*
Y-291400D01*
X655212D01*
G01X663012D02*
Y-286067D01*
G01Y-287000D02*
X662612Y-286467D01*
X662012Y-286200D01*
X661312Y-286067D01*
X660612Y-286333D01*
X660012Y-286867D01*
X659612Y-287667D01*
X659412Y-288733D01*
X659612Y-289800D01*
X660012Y-290600D01*
X660612Y-291133D01*
X661312Y-291400D01*
X662012Y-291267D01*
X662612Y-290867D01*
X663012Y-290334D01*
G01X667112Y-293800D02*
X667712Y-294067D01*
X668512Y-293800D01*
X669012Y-293267D01*
X669412Y-292600D01*
X670012Y-290467D01*
X671312Y-286067D01*
G01X668112D02*
X670012Y-290467D01*
G01X675712Y-287800D02*
X678912D01*
X678612Y-286867D01*
X678112Y-286333D01*
X677412Y-286067D01*
X676712Y-286200D01*
X676112Y-286600D01*
X675712Y-287533D01*
X675512Y-288334D01*
Y-289133D01*
X675712Y-289933D01*
X676212Y-290733D01*
X676812Y-291267D01*
X677512Y-291400D01*
X678212Y-291133D01*
X678912Y-290334D01*
G01X683812Y-291400D02*
Y-286067D01*
G01Y-287133D02*
X684312Y-286600D01*
X684812Y-286200D01*
X685512Y-286067D01*
X686012Y-286200D01*
X686612Y-286600D01*
G01X673512Y-333400D02*
X675912D01*
G01X674712D02*
Y-341400D01*
G01X673512D02*
X675912D01*
G01X681312D02*
Y-336067D01*
G01Y-337133D02*
X681812Y-336600D01*
X682312Y-336200D01*
X683012Y-336067D01*
X683512Y-336200D01*
X684112Y-336600D01*
G01X689212Y-337800D02*
X692412D01*
X692112Y-336867D01*
X691612Y-336333D01*
X690912Y-336067D01*
X690212Y-336200D01*
X689612Y-336600D01*
X689212Y-337533D01*
X689012Y-338334D01*
Y-339133D01*
X689212Y-339933D01*
X689712Y-340733D01*
X690312Y-341267D01*
X691012Y-341400D01*
X691712Y-341133D01*
X692412Y-340334D01*
G01X697012Y-341400D02*
Y-336067D01*
G01Y-337400D02*
X697412Y-336733D01*
X698012Y-336200D01*
X698812Y-336067D01*
X699512Y-336200D01*
X700112Y-336733D01*
X700412Y-337667D01*
Y-341400D01*
G01X705212Y-337800D02*
X708412D01*
X708112Y-336867D01*
X707612Y-336333D01*
X706912Y-336067D01*
X706212Y-336200D01*
X705612Y-336600D01*
X705212Y-337533D01*
X705012Y-338334D01*
Y-339133D01*
X705212Y-339933D01*
X705712Y-340733D01*
X706312Y-341267D01*
X707012Y-341400D01*
X707712Y-341133D01*
X708412Y-340334D01*
G01X675312Y-316400D02*
Y-308400D01*
X679112D01*
G01X677712Y-312267D02*
X675312D01*
G01X682712Y-316400D02*
X685212Y-308400D01*
X687712Y-316400D01*
G01X686812Y-313600D02*
X683612D01*
G01X694012Y-312133D02*
X694412Y-311733D01*
X694712Y-311067D01*
X694912Y-310133D01*
X694712Y-309333D01*
X694312Y-308800D01*
X693612Y-308400D01*
X690912D01*
Y-316400D01*
X694212D01*
X694912Y-315867D01*
X695312Y-315067D01*
X695512Y-314133D01*
X695312Y-313200D01*
X694712Y-312400D01*
X694012Y-312133D01*
X690912D01*
G01X1017300Y504800D02*
G03I-150000J0D01*
G01X777812Y-334733D02*
X778412Y-333933D01*
X779112Y-333533D01*
X779912Y-333400D01*
X780912Y-333667D01*
X781612Y-334333D01*
X781812Y-335133D01*
X781712Y-335934D01*
X781312Y-336600D01*
X779312Y-337933D01*
X778412Y-338867D01*
X777812Y-340200D01*
X777612Y-341400D01*
X781812D01*
G01X787712Y-333400D02*
X786912Y-333667D01*
X786312Y-334333D01*
X785912Y-335133D01*
X785612Y-336200D01*
X785512Y-337400D01*
X785612Y-338600D01*
X785912Y-339667D01*
X786312Y-340467D01*
X786912Y-341133D01*
X787712Y-341400D01*
X788512Y-341133D01*
X789112Y-340467D01*
X789512Y-339667D01*
X789812Y-338600D01*
X789912Y-337400D01*
X789812Y-336200D01*
X789512Y-335133D01*
X789112Y-334333D01*
X788512Y-333667D01*
X787712Y-333400D01*
G01X795712Y-341400D02*
Y-333400D01*
X794512Y-335000D01*
G01Y-341400D02*
X796912D01*
G01X801812Y-334733D02*
X802412Y-333933D01*
X803112Y-333533D01*
X803912Y-333400D01*
X804912Y-333667D01*
X805612Y-334333D01*
X805812Y-335133D01*
X805712Y-335934D01*
X805312Y-336600D01*
X803312Y-337933D01*
X802412Y-338867D01*
X801812Y-340200D01*
X801612Y-341400D01*
X805812D01*
G01X809912Y-341667D02*
X813512Y-333400D01*
G01X819712Y-341400D02*
Y-333400D01*
X818512Y-335000D01*
G01Y-341400D02*
X820912D01*
G01X827712Y-333400D02*
X826912Y-333667D01*
X826312Y-334333D01*
X825912Y-335133D01*
X825612Y-336200D01*
X825512Y-337400D01*
X825612Y-338600D01*
X825912Y-339667D01*
X826312Y-340467D01*
X826912Y-341133D01*
X827712Y-341400D01*
X828512Y-341133D01*
X829112Y-340467D01*
X829512Y-339667D01*
X829812Y-338600D01*
X829912Y-337400D01*
X829812Y-336200D01*
X829512Y-335133D01*
X829112Y-334333D01*
X828512Y-333667D01*
X827712Y-333400D01*
G01X833912Y-341667D02*
X837512Y-333400D01*
G01X841512Y-339800D02*
X842112Y-340733D01*
X842912Y-341267D01*
X843812Y-341400D01*
X844612Y-341267D01*
X845412Y-340600D01*
X845912Y-339800D01*
X846012Y-339000D01*
X845812Y-338067D01*
X845112Y-337400D01*
X844412Y-337133D01*
X843512D01*
G01X844412D02*
X845012Y-336733D01*
X845512Y-336067D01*
X845712Y-335267D01*
X845512Y-334467D01*
X845012Y-333800D01*
X844112Y-333400D01*
X843212Y-333533D01*
X842312Y-334067D01*
G01X851712Y-341400D02*
Y-333400D01*
X850512Y-335000D01*
G01Y-341400D02*
X852912D01*
G01X777512Y-316400D02*
Y-308400D01*
X779512D01*
X780312Y-308800D01*
X780912Y-309333D01*
X781412Y-310133D01*
X781812Y-311067D01*
X781912Y-312400D01*
X781812Y-313733D01*
X781412Y-314667D01*
X780912Y-315467D01*
X780312Y-316000D01*
X779512Y-316400D01*
X777512D01*
G01X785212D02*
X787712Y-308400D01*
X790212Y-316400D01*
G01X789312Y-313600D02*
X786112D01*
G01X795712Y-308400D02*
X794912Y-308667D01*
X794312Y-309333D01*
X793912Y-310133D01*
X793612Y-311200D01*
X793512Y-312400D01*
X793612Y-313600D01*
X793912Y-314667D01*
X794312Y-315467D01*
X794912Y-316133D01*
X795712Y-316400D01*
X796512Y-316133D01*
X797112Y-315467D01*
X797512Y-314667D01*
X797812Y-313600D01*
X797912Y-312400D01*
X797812Y-311200D01*
X797512Y-310133D01*
X797112Y-309333D01*
X796512Y-308667D01*
X795712Y-308400D01*
G01X803712D02*
Y-316400D01*
G01X801412Y-308400D02*
X806012D01*
G01X809812Y-313067D02*
X810512Y-312133D01*
X811112Y-311600D01*
X811912Y-311333D01*
X812612Y-311600D01*
X813112Y-312133D01*
X813512Y-312933D01*
X813612Y-313867D01*
X813512Y-314667D01*
X813112Y-315467D01*
X812512Y-316133D01*
X811812Y-316400D01*
X811012Y-316133D01*
X810312Y-315334D01*
X809912Y-314133D01*
X809812Y-312800D01*
X810012Y-311067D01*
X810312Y-310133D01*
X810812Y-309200D01*
X811512Y-308533D01*
X812212Y-308400D01*
X812912Y-308667D01*
X813412Y-309333D01*
G01X817112Y-316400D02*
Y-308400D01*
X819712Y-315067D01*
X822312Y-308400D01*
Y-316400D01*
G01X827712Y-308400D02*
Y-316400D01*
G01X825412Y-308400D02*
X830012D01*
G01X833612Y-316400D02*
Y-308400D01*
G01X837812D02*
Y-316400D01*
G01Y-312400D02*
X833612D01*
G01X843712Y-316400D02*
X844412Y-316267D01*
X845212Y-315867D01*
X845712Y-315200D01*
X845912Y-314267D01*
X845712Y-313334D01*
X845112Y-312533D01*
X844212Y-312133D01*
X843212D01*
X842612Y-311867D01*
X842112Y-311200D01*
X841912Y-310267D01*
X842212Y-309333D01*
X842912Y-308667D01*
X843712Y-308400D01*
X844512Y-308667D01*
X845212Y-309333D01*
X845512Y-310267D01*
X845312Y-311200D01*
X844812Y-311867D01*
X844212Y-312133D01*
X843212D01*
X842312Y-312533D01*
X841712Y-313334D01*
X841512Y-314267D01*
X841712Y-315200D01*
X842212Y-315867D01*
X843012Y-316267D01*
X843712Y-316400D01*
G01X853912Y-309067D02*
X853312Y-308667D01*
X852612Y-308400D01*
X851812D01*
X850912Y-308800D01*
X850212Y-309467D01*
X849712Y-310267D01*
X849312Y-311600D01*
X849212Y-312800D01*
X849412Y-314000D01*
X849712Y-314800D01*
X850312Y-315600D01*
X851012Y-316133D01*
X851712Y-316400D01*
X852412D01*
X853112Y-316133D01*
X853712Y-315733D01*
X854212Y-315200D01*
G01X859712Y-308400D02*
X858912Y-308667D01*
X858312Y-309333D01*
X857912Y-310133D01*
X857612Y-311200D01*
X857512Y-312400D01*
X857612Y-313600D01*
X857912Y-314667D01*
X858312Y-315467D01*
X858912Y-316133D01*
X859712Y-316400D01*
X860512Y-316133D01*
X861112Y-315467D01*
X861512Y-314667D01*
X861812Y-313600D01*
X861912Y-312400D01*
X861812Y-311200D01*
X861512Y-310133D01*
X861112Y-309333D01*
X860512Y-308667D01*
X859712Y-308400D01*
G01X786811Y-84957D02*
X785446Y-84800D01*
X784291Y-84565D01*
X783241Y-84252D01*
X782086Y-83860D01*
X780511Y-83233D01*
Y-86367D01*
G01X786811Y-78500D02*
X786706Y-77952D01*
X786391Y-77325D01*
X785866Y-76933D01*
X785131Y-76777D01*
X784396Y-76933D01*
X783766Y-77403D01*
X783451Y-78108D01*
Y-78892D01*
X783241Y-79362D01*
X782716Y-79753D01*
X781981Y-79910D01*
X781246Y-79675D01*
X780721Y-79127D01*
X780511Y-78500D01*
X780721Y-77873D01*
X781246Y-77325D01*
X781981Y-77090D01*
X782716Y-77247D01*
X783241Y-77638D01*
X783451Y-78108D01*
Y-78892D01*
X783766Y-79597D01*
X784396Y-80067D01*
X785131Y-80223D01*
X785866Y-80067D01*
X786391Y-79675D01*
X786706Y-79048D01*
X786811Y-78500D01*
G01X785551Y-73923D02*
X786286Y-73453D01*
X786706Y-72827D01*
X786811Y-72122D01*
X786706Y-71495D01*
X786181Y-70868D01*
X785551Y-70477D01*
X784921Y-70398D01*
X784186Y-70555D01*
X783661Y-71103D01*
X783451Y-71652D01*
Y-72357D01*
G01Y-71652D02*
X783136Y-71182D01*
X782611Y-70790D01*
X781981Y-70633D01*
X781351Y-70790D01*
X780826Y-71182D01*
X780511Y-71887D01*
X780616Y-72592D01*
X781036Y-73297D01*
G01X784186Y-67388D02*
X783451Y-66840D01*
X783031Y-66370D01*
X782821Y-65743D01*
X783031Y-65195D01*
X783451Y-64803D01*
X784081Y-64490D01*
X784816Y-64412D01*
X785446Y-64490D01*
X786076Y-64803D01*
X786601Y-65273D01*
X786811Y-65822D01*
X786601Y-66448D01*
X785971Y-66997D01*
X785026Y-67310D01*
X783976Y-67388D01*
X782611Y-67232D01*
X781876Y-66997D01*
X781141Y-66605D01*
X780616Y-66057D01*
X780511Y-65508D01*
X780721Y-64960D01*
X781246Y-64568D01*
G01X787021Y-59600D02*
X786916Y-59757D01*
X786706D01*
X786601Y-59600D01*
X786706Y-59443D01*
X786916D01*
X787021Y-59600D01*
G01X784186Y-54788D02*
X783451Y-54240D01*
X783031Y-53770D01*
X782821Y-53143D01*
X783031Y-52595D01*
X783451Y-52203D01*
X784081Y-51890D01*
X784816Y-51812D01*
X785446Y-51890D01*
X786076Y-52203D01*
X786601Y-52673D01*
X786811Y-53222D01*
X786601Y-53848D01*
X785971Y-54397D01*
X785026Y-54710D01*
X783976Y-54788D01*
X782611Y-54632D01*
X781876Y-54397D01*
X781141Y-54005D01*
X780616Y-53457D01*
X780511Y-52908D01*
X780721Y-52360D01*
X781246Y-51968D01*
G01X786811Y-47000D02*
X780511D01*
X781771Y-47940D01*
G01X786811D02*
Y-46060D01*
G01X791250Y269550D02*
Y275850D01*
X790310Y274590D01*
G01Y269550D02*
X792190D01*
G01X796062Y272175D02*
X796610Y272910D01*
X797080Y273330D01*
X797707Y273540D01*
X798255Y273330D01*
X798647Y272910D01*
X798960Y272280D01*
X799038Y271545D01*
X798960Y270915D01*
X798647Y270285D01*
X798177Y269760D01*
X797628Y269550D01*
X797002Y269760D01*
X796453Y270390D01*
X796140Y271335D01*
X796062Y272385D01*
X796218Y273750D01*
X796453Y274485D01*
X796845Y275220D01*
X797393Y275745D01*
X797942Y275850D01*
X798490Y275640D01*
X798882Y275115D01*
G01X803850Y269550D02*
X804398Y269655D01*
X805025Y269970D01*
X805417Y270495D01*
X805573Y271230D01*
X805417Y271965D01*
X804947Y272595D01*
X804242Y272910D01*
X803458D01*
X802988Y273120D01*
X802597Y273645D01*
X802440Y274380D01*
X802675Y275115D01*
X803223Y275640D01*
X803850Y275850D01*
X804477Y275640D01*
X805025Y275115D01*
X805260Y274380D01*
X805103Y273645D01*
X804712Y273120D01*
X804242Y272910D01*
X803458D01*
X802753Y272595D01*
X802283Y271965D01*
X802127Y271230D01*
X802283Y270495D01*
X802675Y269970D01*
X803302Y269655D01*
X803850Y269550D01*
G01X810150D02*
X810698Y269655D01*
X811325Y269970D01*
X811717Y270495D01*
X811873Y271230D01*
X811717Y271965D01*
X811247Y272595D01*
X810542Y272910D01*
X809758D01*
X809288Y273120D01*
X808897Y273645D01*
X808740Y274380D01*
X808975Y275115D01*
X809523Y275640D01*
X810150Y275850D01*
X810777Y275640D01*
X811325Y275115D01*
X811560Y274380D01*
X811403Y273645D01*
X811012Y273120D01*
X810542Y272910D01*
X809758D01*
X809053Y272595D01*
X808583Y271965D01*
X808427Y271230D01*
X808583Y270495D01*
X808975Y269970D01*
X809602Y269655D01*
X810150Y269550D01*
G01X814962Y274800D02*
X815432Y275430D01*
X815980Y275745D01*
X816607Y275850D01*
X817390Y275640D01*
X817938Y275115D01*
X818095Y274485D01*
X818017Y273855D01*
X817703Y273330D01*
X816137Y272280D01*
X815432Y271545D01*
X814962Y270495D01*
X814805Y269550D01*
X818095D01*
G01X822750Y269340D02*
X822593Y269445D01*
Y269655D01*
X822750Y269760D01*
X822907Y269655D01*
Y269445D01*
X822750Y269340D01*
G01X827562Y274800D02*
X828032Y275430D01*
X828580Y275745D01*
X829207Y275850D01*
X829990Y275640D01*
X830538Y275115D01*
X830695Y274485D01*
X830617Y273855D01*
X830303Y273330D01*
X828737Y272280D01*
X828032Y271545D01*
X827562Y270495D01*
X827405Y269550D01*
X830695D01*
G01X835350D02*
X835898Y269655D01*
X836525Y269970D01*
X836917Y270495D01*
X837073Y271230D01*
X836917Y271965D01*
X836447Y272595D01*
X835742Y272910D01*
X834958D01*
X834488Y273120D01*
X834097Y273645D01*
X833940Y274380D01*
X834175Y275115D01*
X834723Y275640D01*
X835350Y275850D01*
X835977Y275640D01*
X836525Y275115D01*
X836760Y274380D01*
X836603Y273645D01*
X836212Y273120D01*
X835742Y272910D01*
X834958D01*
X834253Y272595D01*
X833783Y271965D01*
X833627Y271230D01*
X833783Y270495D01*
X834175Y269970D01*
X834802Y269655D01*
X835350Y269550D01*
G01X799712Y-283400D02*
Y-291400D01*
G01X797412Y-283400D02*
X802012D01*
G01X805812Y-288067D02*
X806512Y-287133D01*
X807112Y-286600D01*
X807912Y-286333D01*
X808612Y-286600D01*
X809112Y-287133D01*
X809512Y-287933D01*
X809612Y-288867D01*
X809512Y-289667D01*
X809112Y-290467D01*
X808512Y-291133D01*
X807812Y-291400D01*
X807012Y-291133D01*
X806312Y-290334D01*
X805912Y-289133D01*
X805812Y-287800D01*
X806012Y-286067D01*
X806312Y-285133D01*
X806812Y-284200D01*
X807512Y-283533D01*
X808212Y-283400D01*
X808912Y-283667D01*
X809412Y-284333D01*
G01X813112Y-291400D02*
Y-283400D01*
X815712Y-290067D01*
X818312Y-283400D01*
Y-291400D01*
G01X820712Y-294067D02*
X826712D01*
G01X831712Y-283400D02*
Y-291400D01*
G01X829412Y-283400D02*
X834012D01*
G01X838312Y-291400D02*
Y-286067D01*
G01Y-287133D02*
X838812Y-286600D01*
X839312Y-286200D01*
X840012Y-286067D01*
X840512Y-286200D01*
X841112Y-286600D01*
G01X849512Y-291400D02*
Y-286067D01*
G01Y-287000D02*
X849112Y-286467D01*
X848512Y-286200D01*
X847812Y-286067D01*
X847112Y-286333D01*
X846512Y-286867D01*
X846112Y-287667D01*
X845912Y-288733D01*
X846112Y-289800D01*
X846512Y-290600D01*
X847112Y-291133D01*
X847812Y-291400D01*
X848512Y-291267D01*
X849112Y-290867D01*
X849512Y-290334D01*
G01X853612Y-293800D02*
X854212Y-294067D01*
X855012Y-293800D01*
X855512Y-293267D01*
X855912Y-292600D01*
X856512Y-290467D01*
X857812Y-286067D01*
G01X854612D02*
X856512Y-290467D01*
G01X860712Y-294067D02*
X866712D01*
G01X872512Y-287133D02*
X872912Y-286733D01*
X873212Y-286067D01*
X873412Y-285133D01*
X873212Y-284333D01*
X872812Y-283800D01*
X872112Y-283400D01*
X869412D01*
Y-291400D01*
X872712D01*
X873412Y-290867D01*
X873812Y-290067D01*
X874012Y-289133D01*
X873812Y-288200D01*
X873212Y-287400D01*
X872512Y-287133D01*
X869412D01*
G01X877712Y-291400D02*
Y-283400D01*
X880112D01*
X880912Y-283800D01*
X881512Y-284733D01*
X881712Y-285800D01*
X881512Y-286867D01*
X881012Y-287667D01*
X880112Y-288067D01*
X877712D01*
G01X806291Y221600D02*
X806186Y222148D01*
X805871Y222775D01*
X805346Y223167D01*
X804611Y223323D01*
X803876Y223167D01*
X803246Y222697D01*
X802931Y221992D01*
Y221208D01*
X802721Y220738D01*
X802196Y220347D01*
X801461Y220190D01*
X800726Y220425D01*
X800201Y220973D01*
X799991Y221600D01*
X800201Y222227D01*
X800726Y222775D01*
X801461Y223010D01*
X802196Y222853D01*
X802721Y222462D01*
X802931Y221992D01*
Y221208D01*
X803246Y220503D01*
X803876Y220033D01*
X804611Y219877D01*
X805346Y220033D01*
X805871Y220425D01*
X806186Y221052D01*
X806291Y221600D01*
G01X799991Y227900D02*
X800201Y227273D01*
X800726Y226803D01*
X801356Y226490D01*
X802196Y226255D01*
X803141Y226177D01*
X804086Y226255D01*
X804926Y226490D01*
X805556Y226803D01*
X806081Y227273D01*
X806291Y227900D01*
X806081Y228527D01*
X805556Y228997D01*
X804926Y229310D01*
X804086Y229545D01*
X803141Y229623D01*
X802196Y229545D01*
X801356Y229310D01*
X800726Y228997D01*
X800201Y228527D01*
X799991Y227900D01*
G01X805031Y232477D02*
X805766Y232947D01*
X806186Y233573D01*
X806291Y234278D01*
X806186Y234905D01*
X805661Y235532D01*
X805031Y235923D01*
X804401Y236002D01*
X803666Y235845D01*
X803141Y235297D01*
X802931Y234748D01*
Y234043D01*
G01Y234748D02*
X802616Y235218D01*
X802091Y235610D01*
X801461Y235767D01*
X800831Y235610D01*
X800306Y235218D01*
X799991Y234513D01*
X800096Y233808D01*
X800516Y233103D01*
G01X806291Y240500D02*
X799991D01*
X801251Y239560D01*
G01X806291D02*
Y241440D01*
G01X806501Y246800D02*
X806396Y246643D01*
X806186D01*
X806081Y246800D01*
X806186Y246957D01*
X806396D01*
X806501Y246800D01*
G01X806291Y254040D02*
X799991D01*
X804506Y251142D01*
Y255058D01*
G01X806291Y259400D02*
X799991D01*
X801251Y258460D01*
G01X806291D02*
Y260340D01*
G01X833774Y218400D02*
X833669Y218948D01*
X833354Y219575D01*
X832829Y219967D01*
X832094Y220123D01*
X831359Y219967D01*
X830729Y219497D01*
X830414Y218792D01*
Y218008D01*
X830204Y217538D01*
X829679Y217147D01*
X828944Y216990D01*
X828209Y217225D01*
X827684Y217773D01*
X827474Y218400D01*
X827684Y219027D01*
X828209Y219575D01*
X828944Y219810D01*
X829679Y219653D01*
X830204Y219262D01*
X830414Y218792D01*
Y218008D01*
X830729Y217303D01*
X831359Y216833D01*
X832094Y216677D01*
X832829Y216833D01*
X833354Y217225D01*
X833669Y217852D01*
X833774Y218400D01*
G01X828524Y223212D02*
X827894Y223682D01*
X827579Y224230D01*
X827474Y224857D01*
X827684Y225640D01*
X828209Y226188D01*
X828839Y226345D01*
X829469Y226267D01*
X829994Y225953D01*
X831044Y224387D01*
X831779Y223682D01*
X832829Y223212D01*
X833774Y223055D01*
Y226345D01*
G01X831149Y229512D02*
X830414Y230060D01*
X829994Y230530D01*
X829784Y231157D01*
X829994Y231705D01*
X830414Y232097D01*
X831044Y232410D01*
X831779Y232488D01*
X832409Y232410D01*
X833039Y232097D01*
X833564Y231627D01*
X833774Y231078D01*
X833564Y230452D01*
X832934Y229903D01*
X831989Y229590D01*
X830939Y229512D01*
X829574Y229668D01*
X828839Y229903D01*
X828104Y230295D01*
X827579Y230843D01*
X827474Y231392D01*
X827684Y231940D01*
X828209Y232332D01*
G01X827474Y237300D02*
X827684Y236673D01*
X828209Y236203D01*
X828839Y235890D01*
X829679Y235655D01*
X830624Y235577D01*
X831569Y235655D01*
X832409Y235890D01*
X833039Y236203D01*
X833564Y236673D01*
X833774Y237300D01*
X833564Y237927D01*
X833039Y238397D01*
X832409Y238710D01*
X831569Y238945D01*
X830624Y239023D01*
X829679Y238945D01*
X828839Y238710D01*
X828209Y238397D01*
X827684Y237927D01*
X827474Y237300D01*
G01X833984Y243600D02*
X833879Y243443D01*
X833669D01*
X833564Y243600D01*
X833669Y243757D01*
X833879D01*
X833984Y243600D01*
G01X828524Y248412D02*
X827894Y248882D01*
X827579Y249430D01*
X827474Y250057D01*
X827684Y250840D01*
X828209Y251388D01*
X828839Y251545D01*
X829469Y251467D01*
X829994Y251153D01*
X831044Y249587D01*
X831779Y248882D01*
X832829Y248412D01*
X833774Y248255D01*
Y251545D01*
G01Y257140D02*
X827474D01*
X831989Y254242D01*
Y258158D01*
G01X834650Y378300D02*
Y384600D01*
X833710Y383340D01*
G01Y378300D02*
X835590D01*
G01X840950Y378090D02*
X840793Y378195D01*
Y378405D01*
X840950Y378510D01*
X841107Y378405D01*
Y378195D01*
X840950Y378090D01*
G01X845762Y380925D02*
X846310Y381660D01*
X846780Y382080D01*
X847407Y382290D01*
X847955Y382080D01*
X848347Y381660D01*
X848660Y381030D01*
X848738Y380295D01*
X848660Y379665D01*
X848347Y379035D01*
X847877Y378510D01*
X847328Y378300D01*
X846702Y378510D01*
X846153Y379140D01*
X845840Y380085D01*
X845762Y381135D01*
X845918Y382500D01*
X846153Y383235D01*
X846545Y383970D01*
X847093Y384495D01*
X847642Y384600D01*
X848190Y384390D01*
X848582Y383865D01*
G01X853550Y384600D02*
X852923Y384390D01*
X852453Y383865D01*
X852140Y383235D01*
X851905Y382395D01*
X851827Y381450D01*
X851905Y380505D01*
X852140Y379665D01*
X852453Y379035D01*
X852923Y378510D01*
X853550Y378300D01*
X854177Y378510D01*
X854647Y379035D01*
X854960Y379665D01*
X855195Y380505D01*
X855273Y381450D01*
X855195Y382395D01*
X854960Y383235D01*
X854647Y383865D01*
X854177Y384390D01*
X853550Y384600D01*
G01X857500Y378300D02*
Y382500D01*
G01Y381345D02*
X857735Y381870D01*
X858127Y382290D01*
X858675Y382500D01*
X859223Y382290D01*
X859615Y381870D01*
X859850Y381345D01*
Y378300D01*
G01Y381345D02*
X860085Y381870D01*
X860477Y382290D01*
X861025Y382500D01*
X861573Y382290D01*
X861965Y381870D01*
X862200Y381240D01*
Y378300D01*
G01X863800D02*
Y382500D01*
G01Y381345D02*
X864035Y381870D01*
X864427Y382290D01*
X864975Y382500D01*
X865523Y382290D01*
X865915Y381870D01*
X866150Y381345D01*
Y378300D01*
G01Y381345D02*
X866385Y381870D01*
X866777Y382290D01*
X867325Y382500D01*
X867873Y382290D01*
X868265Y381870D01*
X868500Y381240D01*
Y378300D01*
G01X885050D02*
Y384600D01*
X884110Y383340D01*
G01Y378300D02*
X885990D01*
G01X891350Y384600D02*
X890723Y384390D01*
X890253Y383865D01*
X889940Y383235D01*
X889705Y382395D01*
X889627Y381450D01*
X889705Y380505D01*
X889940Y379665D01*
X890253Y379035D01*
X890723Y378510D01*
X891350Y378300D01*
X891977Y378510D01*
X892447Y379035D01*
X892760Y379665D01*
X892995Y380505D01*
X893073Y381450D01*
X892995Y382395D01*
X892760Y383235D01*
X892447Y383865D01*
X891977Y384390D01*
X891350Y384600D01*
G01X896240Y378090D02*
X899060Y384600D01*
G01X896240D02*
X895770Y384390D01*
X895535Y384075D01*
X895378Y383445D01*
X895535Y382815D01*
X895770Y382500D01*
X896240Y382290D01*
X896710Y382500D01*
X896945Y382815D01*
X897102Y383445D01*
X896945Y384075D01*
X896710Y384390D01*
X896240Y384600D01*
G01X899060Y380400D02*
X898590Y380190D01*
X898355Y379875D01*
X898198Y379245D01*
X898355Y378615D01*
X898590Y378300D01*
X899060Y378090D01*
X899530Y378300D01*
X899765Y378615D01*
X899922Y379245D01*
X899765Y379875D01*
X899530Y380190D01*
X899060Y380400D01*
G01X822300Y624800D02*
X818300D01*
Y632800D01*
X822300D01*
G01X820700Y628933D02*
X818300D01*
G01X830100Y632800D02*
Y624800D01*
G01Y626000D02*
X829700Y625333D01*
X829100Y624933D01*
X828400Y624800D01*
X827600Y625067D01*
X827000Y625733D01*
X826600Y626533D01*
X826500Y627467D01*
X826600Y628400D01*
X827000Y629200D01*
X827600Y629867D01*
X828400Y630133D01*
X829100Y630000D01*
X829600Y629733D01*
X830100Y629200D01*
G01X834900Y622800D02*
X835600Y622267D01*
X836400Y622133D01*
X837100Y622267D01*
X837700Y622933D01*
X838100Y623867D01*
Y630133D01*
G01Y629067D02*
X837700Y629600D01*
X837100Y630000D01*
X836400Y630133D01*
X835600Y629867D01*
X835100Y629333D01*
X834700Y628400D01*
X834500Y627467D01*
X834600Y626667D01*
X835000Y625733D01*
X835600Y625067D01*
X836400Y624800D01*
X837000Y624933D01*
X837700Y625467D01*
X838100Y626000D01*
G01X842800Y628400D02*
X846000D01*
X845700Y629333D01*
X845200Y629867D01*
X844500Y630133D01*
X843800Y630000D01*
X843200Y629600D01*
X842800Y628667D01*
X842600Y627866D01*
Y627067D01*
X842800Y626267D01*
X843300Y625467D01*
X843900Y624933D01*
X844600Y624800D01*
X845300Y625067D01*
X846000Y625866D01*
G01X862500Y632133D02*
X861900Y632533D01*
X861200Y632800D01*
X860400D01*
X859500Y632400D01*
X858800Y631733D01*
X858300Y630933D01*
X857900Y629600D01*
X857800Y628400D01*
X858000Y627200D01*
X858300Y626400D01*
X858900Y625600D01*
X859600Y625067D01*
X860300Y624800D01*
X861000D01*
X861700Y625067D01*
X862300Y625467D01*
X862800Y626000D01*
G01X868300Y624800D02*
X867700Y624933D01*
X867100Y625467D01*
X866700Y626400D01*
X866500Y627467D01*
X866700Y628533D01*
X867100Y629467D01*
X867700Y630000D01*
X868300Y630133D01*
X868900Y630000D01*
X869500Y629467D01*
X869900Y628533D01*
X870000Y627467D01*
X869900Y626400D01*
X869500Y625467D01*
X868900Y624933D01*
X868300Y624800D01*
G01X874600D02*
Y630133D01*
G01Y628800D02*
X875000Y629467D01*
X875600Y630000D01*
X876400Y630133D01*
X877100Y630000D01*
X877700Y629467D01*
X878000Y628533D01*
Y624800D01*
G01X882600D02*
Y630133D01*
G01Y628800D02*
X883000Y629467D01*
X883600Y630000D01*
X884400Y630133D01*
X885100Y630000D01*
X885700Y629467D01*
X886000Y628533D01*
Y624800D01*
G01X890800Y628400D02*
X894000D01*
X893700Y629333D01*
X893200Y629867D01*
X892500Y630133D01*
X891800Y630000D01*
X891200Y629600D01*
X890800Y628667D01*
X890600Y627866D01*
Y627067D01*
X890800Y626267D01*
X891300Y625467D01*
X891900Y624933D01*
X892600Y624800D01*
X893300Y625067D01*
X894000Y625866D01*
G01X901900Y629467D02*
X901200Y630000D01*
X900600Y630133D01*
X899800Y629867D01*
X899200Y629333D01*
X898800Y628400D01*
X898700Y627467D01*
X898800Y626533D01*
X899200Y625733D01*
X899800Y625067D01*
X900600Y624800D01*
X901300Y625067D01*
X901900Y625600D01*
G01X908300Y632800D02*
Y624800D01*
G01X906900Y630133D02*
X909700D01*
G01X916300Y624800D02*
X915700Y624933D01*
X915100Y625467D01*
X914700Y626400D01*
X914500Y627467D01*
X914700Y628533D01*
X915100Y629467D01*
X915700Y630000D01*
X916300Y630133D01*
X916900Y630000D01*
X917500Y629467D01*
X917900Y628533D01*
X918000Y627467D01*
X917900Y626400D01*
X917500Y625467D01*
X916900Y624933D01*
X916300Y624800D01*
G01X922900D02*
Y630133D01*
G01Y629067D02*
X923400Y629600D01*
X923900Y630000D01*
X924600Y630133D01*
X925100Y630000D01*
X925700Y629600D01*
G01X857300Y438800D02*
Y390800D01*
G01Y395800D02*
X852300Y397300D01*
Y394300D01*
X857300Y395800D01*
G01D02*
X842300D01*
G01X857300Y604800D02*
Y444800D01*
X862300Y424800D01*
X872300D01*
X877300Y444800D01*
Y604800D01*
X872300Y594800D01*
X857300Y604800D01*
G01X877300Y438800D02*
Y390800D01*
G01Y384800D02*
Y379800D01*
G01X874800Y378300D02*
X879800D01*
G01X874800Y382300D02*
X879800D01*
G01X877300Y395800D02*
X882300Y397300D01*
Y394300D01*
X877300Y395800D01*
G01X892300D02*
X877300D01*
G01X874300Y424800D02*
X921300D01*
G01X879300Y444800D02*
X921300D01*
G01X919947Y615388D02*
X878376Y449104D01*
G01X877300Y587300D02*
X882300Y585800D01*
Y588800D01*
X877300Y587300D01*
G01X925300Y568200D02*
G03X878000Y587361I-47300J-48801D01*
G01X896912Y-334067D02*
X896312Y-333667D01*
X895612Y-333400D01*
X894812D01*
X893912Y-333800D01*
X893212Y-334467D01*
X892712Y-335267D01*
X892312Y-336600D01*
X892212Y-337800D01*
X892412Y-339000D01*
X892712Y-339800D01*
X893312Y-340600D01*
X894012Y-341133D01*
X894712Y-341400D01*
X895412D01*
X896112Y-341133D01*
X896712Y-340733D01*
X897212Y-340200D01*
G01X895150Y469300D02*
Y475600D01*
X894210Y474340D01*
G01Y469300D02*
X896090D01*
G01X901450Y469090D02*
X901293Y469195D01*
Y469405D01*
X901450Y469510D01*
X901607Y469405D01*
Y469195D01*
X901450Y469090D01*
G01X908690Y469300D02*
Y475600D01*
X905792Y471085D01*
X909708D01*
G01X914050Y475600D02*
X913423Y475390D01*
X912953Y474865D01*
X912640Y474235D01*
X912405Y473395D01*
X912327Y472450D01*
X912405Y471505D01*
X912640Y470665D01*
X912953Y470035D01*
X913423Y469510D01*
X914050Y469300D01*
X914677Y469510D01*
X915147Y470035D01*
X915460Y470665D01*
X915695Y471505D01*
X915773Y472450D01*
X915695Y473395D01*
X915460Y474235D01*
X915147Y474865D01*
X914677Y475390D01*
X914050Y475600D01*
G01X918000Y469300D02*
Y473500D01*
G01Y472345D02*
X918235Y472870D01*
X918627Y473290D01*
X919175Y473500D01*
X919723Y473290D01*
X920115Y472870D01*
X920350Y472345D01*
Y469300D01*
G01Y472345D02*
X920585Y472870D01*
X920977Y473290D01*
X921525Y473500D01*
X922073Y473290D01*
X922465Y472870D01*
X922700Y472240D01*
Y469300D01*
G01X924300D02*
Y473500D01*
G01Y472345D02*
X924535Y472870D01*
X924927Y473290D01*
X925475Y473500D01*
X926023Y473290D01*
X926415Y472870D01*
X926650Y472345D01*
Y469300D01*
G01Y472345D02*
X926885Y472870D01*
X927277Y473290D01*
X927825Y473500D01*
X928373Y473290D01*
X928765Y472870D01*
X929000Y472240D01*
Y469300D01*
G01X945550Y475600D02*
X944923Y475390D01*
X944453Y474865D01*
X944140Y474235D01*
X943905Y473395D01*
X943827Y472450D01*
X943905Y471505D01*
X944140Y470665D01*
X944453Y470035D01*
X944923Y469510D01*
X945550Y469300D01*
X946177Y469510D01*
X946647Y470035D01*
X946960Y470665D01*
X947195Y471505D01*
X947273Y472450D01*
X947195Y473395D01*
X946960Y474235D01*
X946647Y474865D01*
X946177Y475390D01*
X945550Y475600D01*
G01X951850Y469090D02*
X951693Y469195D01*
Y469405D01*
X951850Y469510D01*
X952007Y469405D01*
Y469195D01*
X951850Y469090D01*
G01X958150Y469300D02*
Y475600D01*
X957210Y474340D01*
G01Y469300D02*
X959090D01*
G01X962727Y470245D02*
X963197Y469720D01*
X963745Y469405D01*
X964450Y469300D01*
X965155Y469510D01*
X965703Y469930D01*
X966095Y470665D01*
X966173Y471505D01*
X966017Y472345D01*
X965625Y472870D01*
X965077Y473290D01*
X964528Y473395D01*
X963980Y473290D01*
X963275Y472870D01*
X963510Y475600D01*
X965625D01*
G01X922212Y-341400D02*
Y-333400D01*
X921012Y-335000D01*
G01Y-341400D02*
X923412D01*
G01X928312Y-338067D02*
X929012Y-337133D01*
X929612Y-336600D01*
X930412Y-336333D01*
X931112Y-336600D01*
X931612Y-337133D01*
X932012Y-337933D01*
X932112Y-338867D01*
X932012Y-339667D01*
X931612Y-340467D01*
X931012Y-341133D01*
X930312Y-341400D01*
X929512Y-341133D01*
X928812Y-340334D01*
X928412Y-339133D01*
X928312Y-337800D01*
X928512Y-336067D01*
X928812Y-335133D01*
X929312Y-334200D01*
X930012Y-333533D01*
X930712Y-333400D01*
X931412Y-333667D01*
X931912Y-334333D01*
G01X911300Y424800D02*
X909800Y429800D01*
X912800D01*
X911300Y424800D01*
G01Y444800D02*
X909800Y439800D01*
X912800D01*
X911300Y444800D01*
G01Y464800D02*
Y424800D01*
G01X913162Y561050D02*
X913632Y561680D01*
X914180Y561995D01*
X914807Y562100D01*
X915590Y561890D01*
X916138Y561365D01*
X916295Y560735D01*
X916217Y560105D01*
X915903Y559580D01*
X914337Y558530D01*
X913632Y557795D01*
X913162Y556745D01*
X913005Y555800D01*
X916295D01*
G01X920950Y562100D02*
X920323Y561890D01*
X919853Y561365D01*
X919540Y560735D01*
X919305Y559895D01*
X919227Y558950D01*
X919305Y558005D01*
X919540Y557165D01*
X919853Y556535D01*
X920323Y556010D01*
X920950Y555800D01*
X921577Y556010D01*
X922047Y556535D01*
X922360Y557165D01*
X922595Y558005D01*
X922673Y558950D01*
X922595Y559895D01*
X922360Y560735D01*
X922047Y561365D01*
X921577Y561890D01*
X920950Y562100D01*
G01X938362Y561050D02*
X938832Y561680D01*
X939380Y561995D01*
X940007Y562100D01*
X940790Y561890D01*
X941338Y561365D01*
X941495Y560735D01*
X941417Y560105D01*
X941103Y559580D01*
X939537Y558530D01*
X938832Y557795D01*
X938362Y556745D01*
X938205Y555800D01*
X941495D01*
G01X925418Y563800D02*
G03I-1118J0D01*
G01X910800Y578800D02*
X905800Y579800D01*
X907300Y582300D01*
X910800Y578800D01*
G01X937800Y475800D02*
Y470800D01*
G01X935300Y469300D02*
X940300D01*
G01X935300Y473300D02*
X940300D01*
G01X929800Y555800D02*
X934800D01*
G01X932300Y562300D02*
Y557300D01*
G01X929800Y559800D02*
X934800D01*
G01X944418Y563800D02*
G03I-1118J0D01*
G01X1104765Y-97150D02*
X1098465D01*
X1099725Y-98090D01*
G01X1104765D02*
Y-96210D01*
G01Y-90850D02*
X1098465D01*
X1099725Y-91790D01*
G01X1104765D02*
Y-89910D01*
G01X1098465Y-84550D02*
X1098675Y-85177D01*
X1099200Y-85647D01*
X1099830Y-85960D01*
X1100670Y-86195D01*
X1101615Y-86273D01*
X1102560Y-86195D01*
X1103400Y-85960D01*
X1104030Y-85647D01*
X1104555Y-85177D01*
X1104765Y-84550D01*
X1104555Y-83923D01*
X1104030Y-83453D01*
X1103400Y-83140D01*
X1102560Y-82905D01*
X1101615Y-82827D01*
X1100670Y-82905D01*
X1099830Y-83140D01*
X1099200Y-83453D01*
X1098675Y-83923D01*
X1098465Y-84550D01*
G01X1104765Y-78250D02*
X1098465D01*
X1099725Y-79190D01*
G01X1104765D02*
Y-77310D01*
G01X1102140Y-73438D02*
X1101405Y-72890D01*
X1100985Y-72420D01*
X1100775Y-71793D01*
X1100985Y-71245D01*
X1101405Y-70853D01*
X1102035Y-70540D01*
X1102770Y-70462D01*
X1103400Y-70540D01*
X1104030Y-70853D01*
X1104555Y-71323D01*
X1104765Y-71872D01*
X1104555Y-72498D01*
X1103925Y-73047D01*
X1102980Y-73360D01*
X1101930Y-73438D01*
X1100565Y-73282D01*
X1099830Y-73047D01*
X1099095Y-72655D01*
X1098570Y-72107D01*
X1098465Y-71558D01*
X1098675Y-71010D01*
X1099200Y-70618D01*
G01X1104975Y-65650D02*
X1104870Y-65807D01*
X1104660D01*
X1104555Y-65650D01*
X1104660Y-65493D01*
X1104870D01*
X1104975Y-65650D01*
G01X1104765Y-59350D02*
X1098465D01*
X1099725Y-60290D01*
G01X1104765D02*
Y-58410D01*
G01X1103820Y-54773D02*
X1104345Y-54303D01*
X1104660Y-53755D01*
X1104765Y-53050D01*
X1104555Y-52345D01*
X1104135Y-51797D01*
X1103400Y-51405D01*
X1102560Y-51327D01*
X1101720Y-51483D01*
X1101195Y-51875D01*
X1100775Y-52423D01*
X1100670Y-52972D01*
X1100775Y-53520D01*
X1101195Y-54225D01*
X1098465Y-53990D01*
Y-51875D01*
G01X1187442Y217250D02*
X1181142D01*
X1182402Y216310D01*
G01X1187442D02*
Y218190D01*
G01Y223550D02*
X1181142D01*
X1182402Y222610D01*
G01X1187442D02*
Y224490D01*
G01Y229850D02*
X1187337Y230398D01*
X1187022Y231025D01*
X1186497Y231417D01*
X1185762Y231573D01*
X1185027Y231417D01*
X1184397Y230947D01*
X1184082Y230242D01*
Y229458D01*
X1183872Y228988D01*
X1183347Y228597D01*
X1182612Y228440D01*
X1181877Y228675D01*
X1181352Y229223D01*
X1181142Y229850D01*
X1181352Y230477D01*
X1181877Y231025D01*
X1182612Y231260D01*
X1183347Y231103D01*
X1183872Y230712D01*
X1184082Y230242D01*
Y229458D01*
X1184397Y228753D01*
X1185027Y228283D01*
X1185762Y228127D01*
X1186497Y228283D01*
X1187022Y228675D01*
X1187337Y229302D01*
X1187442Y229850D01*
G01Y237090D02*
X1181142D01*
X1185657Y234192D01*
Y238108D01*
G01X1182192Y240962D02*
X1181562Y241432D01*
X1181247Y241980D01*
X1181142Y242607D01*
X1181352Y243390D01*
X1181877Y243938D01*
X1182507Y244095D01*
X1183137Y244017D01*
X1183662Y243703D01*
X1184712Y242137D01*
X1185447Y241432D01*
X1186497Y240962D01*
X1187442Y240805D01*
Y244095D01*
G01X1187652Y248750D02*
X1187547Y248593D01*
X1187337D01*
X1187232Y248750D01*
X1187337Y248907D01*
X1187547D01*
X1187652Y248750D01*
G01X1186707Y253718D02*
X1187232Y254267D01*
X1187442Y254893D01*
X1187232Y255520D01*
X1186602Y256068D01*
X1185657Y256460D01*
X1184712Y256617D01*
X1183557D01*
X1182612Y256460D01*
X1181772Y256068D01*
X1181352Y255598D01*
X1181142Y255050D01*
X1181352Y254423D01*
X1181772Y253953D01*
X1182402Y253640D01*
X1183242Y253483D01*
X1183977Y253640D01*
X1184712Y254032D01*
X1185132Y254502D01*
X1185237Y255050D01*
X1185027Y255677D01*
X1184502Y256147D01*
X1183557Y256617D01*
G01X1182192Y259862D02*
X1181562Y260332D01*
X1181247Y260880D01*
X1181142Y261507D01*
X1181352Y262290D01*
X1181877Y262838D01*
X1182507Y262995D01*
X1183137Y262917D01*
X1183662Y262603D01*
X1184712Y261037D01*
X1185447Y260332D01*
X1186497Y259862D01*
X1187442Y259705D01*
Y262995D01*
G01X1251457Y226050D02*
X1245157D01*
X1246417Y225110D01*
G01X1251457D02*
Y226990D01*
G01X1246207Y230862D02*
X1245577Y231332D01*
X1245262Y231880D01*
X1245157Y232507D01*
X1245367Y233290D01*
X1245892Y233838D01*
X1246522Y233995D01*
X1247152Y233917D01*
X1247677Y233603D01*
X1248727Y232037D01*
X1249462Y231332D01*
X1250512Y230862D01*
X1251457Y230705D01*
Y233995D01*
G01Y239590D02*
X1245157D01*
X1249672Y236692D01*
Y240608D01*
G01X1251457Y244950D02*
X1251352Y245498D01*
X1251037Y246125D01*
X1250512Y246517D01*
X1249777Y246673D01*
X1249042Y246517D01*
X1248412Y246047D01*
X1248097Y245342D01*
Y244558D01*
X1247887Y244088D01*
X1247362Y243697D01*
X1246627Y243540D01*
X1245892Y243775D01*
X1245367Y244323D01*
X1245157Y244950D01*
X1245367Y245577D01*
X1245892Y246125D01*
X1246627Y246360D01*
X1247362Y246203D01*
X1247887Y245812D01*
X1248097Y245342D01*
Y244558D01*
X1248412Y243853D01*
X1249042Y243383D01*
X1249777Y243227D01*
X1250512Y243383D01*
X1251037Y243775D01*
X1251352Y244402D01*
X1251457Y244950D01*
G01X1250197Y249527D02*
X1250932Y249997D01*
X1251352Y250623D01*
X1251457Y251328D01*
X1251352Y251955D01*
X1250827Y252582D01*
X1250197Y252973D01*
X1249567Y253052D01*
X1248832Y252895D01*
X1248307Y252347D01*
X1248097Y251798D01*
Y251093D01*
G01Y251798D02*
X1247782Y252268D01*
X1247257Y252660D01*
X1246627Y252817D01*
X1245997Y252660D01*
X1245472Y252268D01*
X1245157Y251563D01*
X1245262Y250858D01*
X1245682Y250153D01*
G01X1251667Y257550D02*
X1251562Y257393D01*
X1251352D01*
X1251247Y257550D01*
X1251352Y257707D01*
X1251562D01*
X1251667Y257550D01*
G01X1245157Y263850D02*
X1245367Y263223D01*
X1245892Y262753D01*
X1246522Y262440D01*
X1247362Y262205D01*
X1248307Y262127D01*
X1249252Y262205D01*
X1250092Y262440D01*
X1250722Y262753D01*
X1251247Y263223D01*
X1251457Y263850D01*
X1251247Y264477D01*
X1250722Y264947D01*
X1250092Y265260D01*
X1249252Y265495D01*
X1248307Y265573D01*
X1247362Y265495D01*
X1246522Y265260D01*
X1245892Y264947D01*
X1245367Y264477D01*
X1245157Y263850D01*
G01X1251457Y269993D02*
X1250092Y270150D01*
X1248937Y270385D01*
X1247887Y270698D01*
X1246732Y271090D01*
X1245157Y271717D01*
Y268583D01*
G01X1303820Y-59150D02*
X1297520D01*
X1298780Y-60090D01*
G01X1303820D02*
Y-58210D01*
G01X1302560Y-54573D02*
X1303295Y-54103D01*
X1303715Y-53477D01*
X1303820Y-52772D01*
X1303715Y-52145D01*
X1303190Y-51518D01*
X1302560Y-51127D01*
X1301930Y-51048D01*
X1301195Y-51205D01*
X1300670Y-51753D01*
X1300460Y-52302D01*
Y-53007D01*
G01Y-52302D02*
X1300145Y-51832D01*
X1299620Y-51440D01*
X1298990Y-51283D01*
X1298360Y-51440D01*
X1297835Y-51832D01*
X1297520Y-52537D01*
X1297625Y-53242D01*
X1298045Y-53947D01*
G01X1297520Y-46550D02*
X1297730Y-47177D01*
X1298255Y-47647D01*
X1298885Y-47960D01*
X1299725Y-48195D01*
X1300670Y-48273D01*
X1301615Y-48195D01*
X1302455Y-47960D01*
X1303085Y-47647D01*
X1303610Y-47177D01*
X1303820Y-46550D01*
X1303610Y-45923D01*
X1303085Y-45453D01*
X1302455Y-45140D01*
X1301615Y-44905D01*
X1300670Y-44827D01*
X1299725Y-44905D01*
X1298885Y-45140D01*
X1298255Y-45453D01*
X1297730Y-45923D01*
X1297520Y-46550D01*
G01Y-40250D02*
X1297730Y-40877D01*
X1298255Y-41347D01*
X1298885Y-41660D01*
X1299725Y-41895D01*
X1300670Y-41973D01*
X1301615Y-41895D01*
X1302455Y-41660D01*
X1303085Y-41347D01*
X1303610Y-40877D01*
X1303820Y-40250D01*
X1303610Y-39623D01*
X1303085Y-39153D01*
X1302455Y-38840D01*
X1301615Y-38605D01*
X1300670Y-38527D01*
X1299725Y-38605D01*
X1298885Y-38840D01*
X1298255Y-39153D01*
X1297730Y-39623D01*
X1297520Y-40250D01*
G01X1301195Y-35438D02*
X1300460Y-34890D01*
X1300040Y-34420D01*
X1299830Y-33793D01*
X1300040Y-33245D01*
X1300460Y-32853D01*
X1301090Y-32540D01*
X1301825Y-32462D01*
X1302455Y-32540D01*
X1303085Y-32853D01*
X1303610Y-33323D01*
X1303820Y-33872D01*
X1303610Y-34498D01*
X1302980Y-35047D01*
X1302035Y-35360D01*
X1300985Y-35438D01*
X1299620Y-35282D01*
X1298885Y-35047D01*
X1298150Y-34655D01*
X1297625Y-34107D01*
X1297520Y-33558D01*
X1297730Y-33010D01*
X1298255Y-32618D01*
G01X1304030Y-27650D02*
X1303925Y-27807D01*
X1303715D01*
X1303610Y-27650D01*
X1303715Y-27493D01*
X1303925D01*
X1304030Y-27650D01*
G01X1303820Y-21507D02*
X1302455Y-21350D01*
X1301300Y-21115D01*
X1300250Y-20802D01*
X1299095Y-20410D01*
X1297520Y-19783D01*
Y-22917D01*
G01Y-15050D02*
X1297730Y-15677D01*
X1298255Y-16147D01*
X1298885Y-16460D01*
X1299725Y-16695D01*
X1300670Y-16773D01*
X1301615Y-16695D01*
X1302455Y-16460D01*
X1303085Y-16147D01*
X1303610Y-15677D01*
X1303820Y-15050D01*
X1303610Y-14423D01*
X1303085Y-13953D01*
X1302455Y-13640D01*
X1301615Y-13405D01*
X1300670Y-13327D01*
X1299725Y-13405D01*
X1298885Y-13640D01*
X1298255Y-13953D01*
X1297730Y-14423D01*
X1297520Y-15050D01*
G01X1318386Y217650D02*
X1312086D01*
X1313346Y216710D01*
G01X1318386D02*
Y218590D01*
G01X1317126Y222227D02*
X1317861Y222697D01*
X1318281Y223323D01*
X1318386Y224028D01*
X1318281Y224655D01*
X1317756Y225282D01*
X1317126Y225673D01*
X1316496Y225752D01*
X1315761Y225595D01*
X1315236Y225047D01*
X1315026Y224498D01*
Y223793D01*
G01Y224498D02*
X1314711Y224968D01*
X1314186Y225360D01*
X1313556Y225517D01*
X1312926Y225360D01*
X1312401Y224968D01*
X1312086Y224263D01*
X1312191Y223558D01*
X1312611Y222853D01*
G01X1318386Y230250D02*
X1312086D01*
X1313346Y229310D01*
G01X1318386D02*
Y231190D01*
G01X1317441Y234827D02*
X1317966Y235297D01*
X1318281Y235845D01*
X1318386Y236550D01*
X1318176Y237255D01*
X1317756Y237803D01*
X1317021Y238195D01*
X1316181Y238273D01*
X1315341Y238117D01*
X1314816Y237725D01*
X1314396Y237177D01*
X1314291Y236628D01*
X1314396Y236080D01*
X1314816Y235375D01*
X1312086Y235610D01*
Y237725D01*
G01X1313136Y241362D02*
X1312506Y241832D01*
X1312191Y242380D01*
X1312086Y243007D01*
X1312296Y243790D01*
X1312821Y244338D01*
X1313451Y244495D01*
X1314081Y244417D01*
X1314606Y244103D01*
X1315656Y242537D01*
X1316391Y241832D01*
X1317441Y241362D01*
X1318386Y241205D01*
Y244495D01*
G01X1318596Y249150D02*
X1318491Y248993D01*
X1318281D01*
X1318176Y249150D01*
X1318281Y249307D01*
X1318491D01*
X1318596Y249150D01*
G01X1317126Y253727D02*
X1317861Y254197D01*
X1318281Y254823D01*
X1318386Y255528D01*
X1318281Y256155D01*
X1317756Y256782D01*
X1317126Y257173D01*
X1316496Y257252D01*
X1315761Y257095D01*
X1315236Y256547D01*
X1315026Y255998D01*
Y255293D01*
G01Y255998D02*
X1314711Y256468D01*
X1314186Y256860D01*
X1313556Y257017D01*
X1312926Y256860D01*
X1312401Y256468D01*
X1312086Y255763D01*
X1312191Y255058D01*
X1312611Y254353D01*
G01X1315761Y260262D02*
X1315026Y260810D01*
X1314606Y261280D01*
X1314396Y261907D01*
X1314606Y262455D01*
X1315026Y262847D01*
X1315656Y263160D01*
X1316391Y263238D01*
X1317021Y263160D01*
X1317651Y262847D01*
X1318176Y262377D01*
X1318386Y261828D01*
X1318176Y261202D01*
X1317546Y260653D01*
X1316601Y260340D01*
X1315551Y260262D01*
X1314186Y260418D01*
X1313451Y260653D01*
X1312716Y261045D01*
X1312191Y261593D01*
X1312086Y262142D01*
X1312296Y262690D01*
X1312821Y263082D01*
G01X1400748Y227050D02*
X1394448D01*
X1395708Y226110D01*
G01X1400748D02*
Y227990D01*
G01X1399488Y231627D02*
X1400223Y232097D01*
X1400643Y232723D01*
X1400748Y233428D01*
X1400643Y234055D01*
X1400118Y234682D01*
X1399488Y235073D01*
X1398858Y235152D01*
X1398123Y234995D01*
X1397598Y234447D01*
X1397388Y233898D01*
Y233193D01*
G01Y233898D02*
X1397073Y234368D01*
X1396548Y234760D01*
X1395918Y234917D01*
X1395288Y234760D01*
X1394763Y234368D01*
X1394448Y233663D01*
X1394553Y232958D01*
X1394973Y232253D01*
G01X1400013Y238318D02*
X1400538Y238867D01*
X1400748Y239493D01*
X1400538Y240120D01*
X1399908Y240668D01*
X1398963Y241060D01*
X1398018Y241217D01*
X1396863D01*
X1395918Y241060D01*
X1395078Y240668D01*
X1394658Y240198D01*
X1394448Y239650D01*
X1394658Y239023D01*
X1395078Y238553D01*
X1395708Y238240D01*
X1396548Y238083D01*
X1397283Y238240D01*
X1398018Y238632D01*
X1398438Y239102D01*
X1398543Y239650D01*
X1398333Y240277D01*
X1397808Y240747D01*
X1396863Y241217D01*
G01X1400748Y245793D02*
X1399383Y245950D01*
X1398228Y246185D01*
X1397178Y246498D01*
X1396023Y246890D01*
X1394448Y247517D01*
Y244383D01*
G01X1399803Y250527D02*
X1400328Y250997D01*
X1400643Y251545D01*
X1400748Y252250D01*
X1400538Y252955D01*
X1400118Y253503D01*
X1399383Y253895D01*
X1398543Y253973D01*
X1397703Y253817D01*
X1397178Y253425D01*
X1396758Y252877D01*
X1396653Y252328D01*
X1396758Y251780D01*
X1397178Y251075D01*
X1394448Y251310D01*
Y253425D01*
G01X1400958Y258550D02*
X1400853Y258393D01*
X1400643D01*
X1400538Y258550D01*
X1400643Y258707D01*
X1400853D01*
X1400958Y258550D01*
G01X1400013Y263518D02*
X1400538Y264067D01*
X1400748Y264693D01*
X1400538Y265320D01*
X1399908Y265868D01*
X1398963Y266260D01*
X1398018Y266417D01*
X1396863D01*
X1395918Y266260D01*
X1395078Y265868D01*
X1394658Y265398D01*
X1394448Y264850D01*
X1394658Y264223D01*
X1395078Y263753D01*
X1395708Y263440D01*
X1396548Y263283D01*
X1397283Y263440D01*
X1398018Y263832D01*
X1398438Y264302D01*
X1398543Y264850D01*
X1398333Y265477D01*
X1397808Y265947D01*
X1396863Y266417D01*
G01X1400748Y271150D02*
X1400643Y271698D01*
X1400328Y272325D01*
X1399803Y272717D01*
X1399068Y272873D01*
X1398333Y272717D01*
X1397703Y272247D01*
X1397388Y271542D01*
Y270758D01*
X1397178Y270288D01*
X1396653Y269897D01*
X1395918Y269740D01*
X1395183Y269975D01*
X1394658Y270523D01*
X1394448Y271150D01*
X1394658Y271777D01*
X1395183Y272325D01*
X1395918Y272560D01*
X1396653Y272403D01*
X1397178Y272012D01*
X1397388Y271542D01*
Y270758D01*
X1397703Y270053D01*
X1398333Y269583D01*
X1399068Y269427D01*
X1399803Y269583D01*
X1400328Y269975D01*
X1400643Y270602D01*
X1400748Y271150D01*
G01X1453112Y-68950D02*
X1446812D01*
X1448072Y-69890D01*
G01X1453112D02*
Y-68010D01*
G01Y-61710D02*
X1446812D01*
X1451327Y-64608D01*
Y-60692D01*
G01X1453112Y-55410D02*
X1446812D01*
X1451327Y-58308D01*
Y-54392D01*
G01X1452377Y-51382D02*
X1452902Y-50833D01*
X1453112Y-50207D01*
X1452902Y-49580D01*
X1452272Y-49032D01*
X1451327Y-48640D01*
X1450382Y-48483D01*
X1449227D01*
X1448282Y-48640D01*
X1447442Y-49032D01*
X1447022Y-49502D01*
X1446812Y-50050D01*
X1447022Y-50677D01*
X1447442Y-51147D01*
X1448072Y-51460D01*
X1448912Y-51617D01*
X1449647Y-51460D01*
X1450382Y-51068D01*
X1450802Y-50598D01*
X1450907Y-50050D01*
X1450697Y-49423D01*
X1450172Y-48953D01*
X1449227Y-48483D01*
G01X1452377Y-45082D02*
X1452902Y-44533D01*
X1453112Y-43907D01*
X1452902Y-43280D01*
X1452272Y-42732D01*
X1451327Y-42340D01*
X1450382Y-42183D01*
X1449227D01*
X1448282Y-42340D01*
X1447442Y-42732D01*
X1447022Y-43202D01*
X1446812Y-43750D01*
X1447022Y-44377D01*
X1447442Y-44847D01*
X1448072Y-45160D01*
X1448912Y-45317D01*
X1449647Y-45160D01*
X1450382Y-44768D01*
X1450802Y-44298D01*
X1450907Y-43750D01*
X1450697Y-43123D01*
X1450172Y-42653D01*
X1449227Y-42183D01*
G01X1453322Y-37450D02*
X1453217Y-37607D01*
X1453007D01*
X1452902Y-37450D01*
X1453007Y-37293D01*
X1453217D01*
X1453322Y-37450D01*
G01X1450487Y-32638D02*
X1449752Y-32090D01*
X1449332Y-31620D01*
X1449122Y-30993D01*
X1449332Y-30445D01*
X1449752Y-30053D01*
X1450382Y-29740D01*
X1451117Y-29662D01*
X1451747Y-29740D01*
X1452377Y-30053D01*
X1452902Y-30523D01*
X1453112Y-31072D01*
X1452902Y-31698D01*
X1452272Y-32247D01*
X1451327Y-32560D01*
X1450277Y-32638D01*
X1448912Y-32482D01*
X1448177Y-32247D01*
X1447442Y-31855D01*
X1446917Y-31307D01*
X1446812Y-30758D01*
X1447022Y-30210D01*
X1447547Y-29818D01*
G01X1447862Y-26338D02*
X1447232Y-25868D01*
X1446917Y-25320D01*
X1446812Y-24693D01*
X1447022Y-23910D01*
X1447547Y-23362D01*
X1448177Y-23205D01*
X1448807Y-23283D01*
X1449332Y-23597D01*
X1450382Y-25163D01*
X1451117Y-25868D01*
X1452167Y-26338D01*
X1453112Y-26495D01*
Y-23205D01*
G01X1467678Y223150D02*
X1461378D01*
X1462638Y222210D01*
G01X1467678D02*
Y224090D01*
G01Y230390D02*
X1461378D01*
X1465893Y227492D01*
Y231408D01*
G01X1465053Y234262D02*
X1464318Y234810D01*
X1463898Y235280D01*
X1463688Y235907D01*
X1463898Y236455D01*
X1464318Y236847D01*
X1464948Y237160D01*
X1465683Y237238D01*
X1466313Y237160D01*
X1466943Y236847D01*
X1467468Y236377D01*
X1467678Y235828D01*
X1467468Y235202D01*
X1466838Y234653D01*
X1465893Y234340D01*
X1464843Y234262D01*
X1463478Y234418D01*
X1462743Y234653D01*
X1462008Y235045D01*
X1461483Y235593D01*
X1461378Y236142D01*
X1461588Y236690D01*
X1462113Y237082D01*
G01X1467678Y242990D02*
X1461378D01*
X1465893Y240092D01*
Y244008D01*
G01X1466733Y246627D02*
X1467258Y247097D01*
X1467573Y247645D01*
X1467678Y248350D01*
X1467468Y249055D01*
X1467048Y249603D01*
X1466313Y249995D01*
X1465473Y250073D01*
X1464633Y249917D01*
X1464108Y249525D01*
X1463688Y248977D01*
X1463583Y248428D01*
X1463688Y247880D01*
X1464108Y247175D01*
X1461378Y247410D01*
Y249525D01*
G01X1467888Y254650D02*
X1467783Y254493D01*
X1467573D01*
X1467468Y254650D01*
X1467573Y254807D01*
X1467783D01*
X1467888Y254650D01*
G01X1462428Y259462D02*
X1461798Y259932D01*
X1461483Y260480D01*
X1461378Y261107D01*
X1461588Y261890D01*
X1462113Y262438D01*
X1462743Y262595D01*
X1463373Y262517D01*
X1463898Y262203D01*
X1464948Y260637D01*
X1465683Y259932D01*
X1466733Y259462D01*
X1467678Y259305D01*
Y262595D01*
G01Y267250D02*
X1467573Y267798D01*
X1467258Y268425D01*
X1466733Y268817D01*
X1465998Y268973D01*
X1465263Y268817D01*
X1464633Y268347D01*
X1464318Y267642D01*
Y266858D01*
X1464108Y266388D01*
X1463583Y265997D01*
X1462848Y265840D01*
X1462113Y266075D01*
X1461588Y266623D01*
X1461378Y267250D01*
X1461588Y267877D01*
X1462113Y268425D01*
X1462848Y268660D01*
X1463583Y268503D01*
X1464108Y268112D01*
X1464318Y267642D01*
Y266858D01*
X1464633Y266153D01*
X1465263Y265683D01*
X1465998Y265527D01*
X1466733Y265683D01*
X1467258Y266075D01*
X1467573Y266702D01*
X1467678Y267250D01*
G01X1503080Y224450D02*
X1496780D01*
X1498040Y223510D01*
G01X1503080D02*
Y225390D01*
G01Y231690D02*
X1496780D01*
X1501295Y228792D01*
Y232708D01*
G01X1502345Y235718D02*
X1502870Y236267D01*
X1503080Y236893D01*
X1502870Y237520D01*
X1502240Y238068D01*
X1501295Y238460D01*
X1500350Y238617D01*
X1499195D01*
X1498250Y238460D01*
X1497410Y238068D01*
X1496990Y237598D01*
X1496780Y237050D01*
X1496990Y236423D01*
X1497410Y235953D01*
X1498040Y235640D01*
X1498880Y235483D01*
X1499615Y235640D01*
X1500350Y236032D01*
X1500770Y236502D01*
X1500875Y237050D01*
X1500665Y237677D01*
X1500140Y238147D01*
X1499195Y238617D01*
G01X1502345Y242018D02*
X1502870Y242567D01*
X1503080Y243193D01*
X1502870Y243820D01*
X1502240Y244368D01*
X1501295Y244760D01*
X1500350Y244917D01*
X1499195D01*
X1498250Y244760D01*
X1497410Y244368D01*
X1496990Y243898D01*
X1496780Y243350D01*
X1496990Y242723D01*
X1497410Y242253D01*
X1498040Y241940D01*
X1498880Y241783D01*
X1499615Y241940D01*
X1500350Y242332D01*
X1500770Y242802D01*
X1500875Y243350D01*
X1500665Y243977D01*
X1500140Y244447D01*
X1499195Y244917D01*
G01X1502345Y248318D02*
X1502870Y248867D01*
X1503080Y249493D01*
X1502870Y250120D01*
X1502240Y250668D01*
X1501295Y251060D01*
X1500350Y251217D01*
X1499195D01*
X1498250Y251060D01*
X1497410Y250668D01*
X1496990Y250198D01*
X1496780Y249650D01*
X1496990Y249023D01*
X1497410Y248553D01*
X1498040Y248240D01*
X1498880Y248083D01*
X1499615Y248240D01*
X1500350Y248632D01*
X1500770Y249102D01*
X1500875Y249650D01*
X1500665Y250277D01*
X1500140Y250747D01*
X1499195Y251217D01*
G01X1503290Y255950D02*
X1503185Y255793D01*
X1502975D01*
X1502870Y255950D01*
X1502975Y256107D01*
X1503185D01*
X1503290Y255950D01*
G01X1501820Y260527D02*
X1502555Y260997D01*
X1502975Y261623D01*
X1503080Y262328D01*
X1502975Y262955D01*
X1502450Y263582D01*
X1501820Y263973D01*
X1501190Y264052D01*
X1500455Y263895D01*
X1499930Y263347D01*
X1499720Y262798D01*
Y262093D01*
G01Y262798D02*
X1499405Y263268D01*
X1498880Y263660D01*
X1498250Y263817D01*
X1497620Y263660D01*
X1497095Y263268D01*
X1496780Y262563D01*
X1496885Y261858D01*
X1497305Y261153D01*
G01X1496780Y268550D02*
X1496990Y267923D01*
X1497515Y267453D01*
X1498145Y267140D01*
X1498985Y266905D01*
X1499930Y266827D01*
X1500875Y266905D01*
X1501715Y267140D01*
X1502345Y267453D01*
X1502870Y267923D01*
X1503080Y268550D01*
X1502870Y269177D01*
X1502345Y269647D01*
X1501715Y269960D01*
X1500875Y270195D01*
X1499930Y270273D01*
X1498985Y270195D01*
X1498145Y269960D01*
X1497515Y269647D01*
X1496990Y269177D01*
X1496780Y268550D01*
G01X1663150Y214350D02*
X1656850D01*
X1658110Y213410D01*
G01X1663150D02*
Y215290D01*
G01X1660525Y219162D02*
X1659790Y219710D01*
X1659370Y220180D01*
X1659160Y220807D01*
X1659370Y221355D01*
X1659790Y221747D01*
X1660420Y222060D01*
X1661155Y222138D01*
X1661785Y222060D01*
X1662415Y221747D01*
X1662940Y221277D01*
X1663150Y220728D01*
X1662940Y220102D01*
X1662310Y219553D01*
X1661365Y219240D01*
X1660315Y219162D01*
X1658950Y219318D01*
X1658215Y219553D01*
X1657480Y219945D01*
X1656955Y220493D01*
X1656850Y221042D01*
X1657060Y221590D01*
X1657585Y221982D01*
G01X1663150Y226793D02*
X1661785Y226950D01*
X1660630Y227185D01*
X1659580Y227498D01*
X1658425Y227890D01*
X1656850Y228517D01*
Y225383D01*
G01X1661890Y231527D02*
X1662625Y231997D01*
X1663045Y232623D01*
X1663150Y233328D01*
X1663045Y233955D01*
X1662520Y234582D01*
X1661890Y234973D01*
X1661260Y235052D01*
X1660525Y234895D01*
X1660000Y234347D01*
X1659790Y233798D01*
Y233093D01*
G01Y233798D02*
X1659475Y234268D01*
X1658950Y234660D01*
X1658320Y234817D01*
X1657690Y234660D01*
X1657165Y234268D01*
X1656850Y233563D01*
X1656955Y232858D01*
X1657375Y232153D01*
G01X1657900Y238062D02*
X1657270Y238532D01*
X1656955Y239080D01*
X1656850Y239707D01*
X1657060Y240490D01*
X1657585Y241038D01*
X1658215Y241195D01*
X1658845Y241117D01*
X1659370Y240803D01*
X1660420Y239237D01*
X1661155Y238532D01*
X1662205Y238062D01*
X1663150Y237905D01*
Y241195D01*
G01X1663360Y245850D02*
X1663255Y245693D01*
X1663045D01*
X1662940Y245850D01*
X1663045Y246007D01*
X1663255D01*
X1663360Y245850D01*
G01X1660525Y250662D02*
X1659790Y251210D01*
X1659370Y251680D01*
X1659160Y252307D01*
X1659370Y252855D01*
X1659790Y253247D01*
X1660420Y253560D01*
X1661155Y253638D01*
X1661785Y253560D01*
X1662415Y253247D01*
X1662940Y252777D01*
X1663150Y252228D01*
X1662940Y251602D01*
X1662310Y251053D01*
X1661365Y250740D01*
X1660315Y250662D01*
X1658950Y250818D01*
X1658215Y251053D01*
X1657480Y251445D01*
X1656955Y251993D01*
X1656850Y252542D01*
X1657060Y253090D01*
X1657585Y253482D01*
G01X1663150Y258450D02*
X1663045Y258998D01*
X1662730Y259625D01*
X1662205Y260017D01*
X1661470Y260173D01*
X1660735Y260017D01*
X1660105Y259547D01*
X1659790Y258842D01*
Y258058D01*
X1659580Y257588D01*
X1659055Y257197D01*
X1658320Y257040D01*
X1657585Y257275D01*
X1657060Y257823D01*
X1656850Y258450D01*
X1657060Y259077D01*
X1657585Y259625D01*
X1658320Y259860D01*
X1659055Y259703D01*
X1659580Y259312D01*
X1659790Y258842D01*
Y258058D01*
X1660105Y257353D01*
X1660735Y256883D01*
X1661470Y256727D01*
X1662205Y256883D01*
X1662730Y257275D01*
X1663045Y257902D01*
X1663150Y258450D01*
G01X1673662Y-79350D02*
X1667362D01*
X1668622Y-80290D01*
G01X1673662D02*
Y-78410D01*
G01X1671037Y-74538D02*
X1670302Y-73990D01*
X1669882Y-73520D01*
X1669672Y-72893D01*
X1669882Y-72345D01*
X1670302Y-71953D01*
X1670932Y-71640D01*
X1671667Y-71562D01*
X1672297Y-71640D01*
X1672927Y-71953D01*
X1673452Y-72423D01*
X1673662Y-72972D01*
X1673452Y-73598D01*
X1672822Y-74147D01*
X1671877Y-74460D01*
X1670827Y-74538D01*
X1669462Y-74382D01*
X1668727Y-74147D01*
X1667992Y-73755D01*
X1667467Y-73207D01*
X1667362Y-72658D01*
X1667572Y-72110D01*
X1668097Y-71718D01*
G01X1673662Y-66907D02*
X1672297Y-66750D01*
X1671142Y-66515D01*
X1670092Y-66202D01*
X1668937Y-65810D01*
X1667362Y-65183D01*
Y-68317D01*
G01Y-60450D02*
X1667572Y-61077D01*
X1668097Y-61547D01*
X1668727Y-61860D01*
X1669567Y-62095D01*
X1670512Y-62173D01*
X1671457Y-62095D01*
X1672297Y-61860D01*
X1672927Y-61547D01*
X1673452Y-61077D01*
X1673662Y-60450D01*
X1673452Y-59823D01*
X1672927Y-59353D01*
X1672297Y-59040D01*
X1671457Y-58805D01*
X1670512Y-58727D01*
X1669567Y-58805D01*
X1668727Y-59040D01*
X1668097Y-59353D01*
X1667572Y-59823D01*
X1667362Y-60450D01*
G01X1672717Y-55873D02*
X1673242Y-55403D01*
X1673557Y-54855D01*
X1673662Y-54150D01*
X1673452Y-53445D01*
X1673032Y-52897D01*
X1672297Y-52505D01*
X1671457Y-52427D01*
X1670617Y-52583D01*
X1670092Y-52975D01*
X1669672Y-53523D01*
X1669567Y-54072D01*
X1669672Y-54620D01*
X1670092Y-55325D01*
X1667362Y-55090D01*
Y-52975D01*
G01X1673872Y-47850D02*
X1673767Y-48007D01*
X1673557D01*
X1673452Y-47850D01*
X1673557Y-47693D01*
X1673767D01*
X1673872Y-47850D01*
G01X1673662Y-41550D02*
X1667362D01*
X1668622Y-42490D01*
G01X1673662D02*
Y-40610D01*
G01X1668412Y-36738D02*
X1667782Y-36268D01*
X1667467Y-35720D01*
X1667362Y-35093D01*
X1667572Y-34310D01*
X1668097Y-33762D01*
X1668727Y-33605D01*
X1669357Y-33683D01*
X1669882Y-33997D01*
X1670932Y-35563D01*
X1671667Y-36268D01*
X1672717Y-36738D01*
X1673662Y-36895D01*
Y-33605D01*
G01X1707577Y54295D02*
X1708047Y53770D01*
X1708595Y53455D01*
X1709300Y53350D01*
X1710005Y53560D01*
X1710553Y53980D01*
X1710945Y54715D01*
X1711023Y55555D01*
X1710867Y56395D01*
X1710475Y56920D01*
X1709927Y57340D01*
X1709378Y57445D01*
X1708830Y57340D01*
X1708125Y56920D01*
X1708360Y59650D01*
X1710475D01*
G01X1714112Y55975D02*
X1714660Y56710D01*
X1715130Y57130D01*
X1715757Y57340D01*
X1716305Y57130D01*
X1716697Y56710D01*
X1717010Y56080D01*
X1717088Y55345D01*
X1717010Y54715D01*
X1716697Y54085D01*
X1716227Y53560D01*
X1715678Y53350D01*
X1715052Y53560D01*
X1714503Y54190D01*
X1714190Y55135D01*
X1714112Y56185D01*
X1714268Y57550D01*
X1714503Y58285D01*
X1714895Y59020D01*
X1715443Y59545D01*
X1715992Y59650D01*
X1716540Y59440D01*
X1716932Y58915D01*
G01X1720412Y55975D02*
X1720960Y56710D01*
X1721430Y57130D01*
X1722057Y57340D01*
X1722605Y57130D01*
X1722997Y56710D01*
X1723310Y56080D01*
X1723388Y55345D01*
X1723310Y54715D01*
X1722997Y54085D01*
X1722527Y53560D01*
X1721978Y53350D01*
X1721352Y53560D01*
X1720803Y54190D01*
X1720490Y55135D01*
X1720412Y56185D01*
X1720568Y57550D01*
X1720803Y58285D01*
X1721195Y59020D01*
X1721743Y59545D01*
X1722292Y59650D01*
X1722840Y59440D01*
X1723232Y58915D01*
G01X1728200Y53140D02*
X1728043Y53245D01*
Y53455D01*
X1728200Y53560D01*
X1728357Y53455D01*
Y53245D01*
X1728200Y53140D01*
G01X1732777Y54295D02*
X1733247Y53770D01*
X1733795Y53455D01*
X1734500Y53350D01*
X1735205Y53560D01*
X1735753Y53980D01*
X1736145Y54715D01*
X1736223Y55555D01*
X1736067Y56395D01*
X1735675Y56920D01*
X1735127Y57340D01*
X1734578Y57445D01*
X1734030Y57340D01*
X1733325Y56920D01*
X1733560Y59650D01*
X1735675D01*
G01X1739077Y54610D02*
X1739547Y53875D01*
X1740173Y53455D01*
X1740878Y53350D01*
X1741505Y53455D01*
X1742132Y53980D01*
X1742523Y54610D01*
X1742602Y55240D01*
X1742445Y55975D01*
X1741897Y56500D01*
X1741348Y56710D01*
X1740643D01*
G01X1741348D02*
X1741818Y57025D01*
X1742210Y57550D01*
X1742367Y58180D01*
X1742210Y58810D01*
X1741818Y59335D01*
X1741113Y59650D01*
X1740408Y59545D01*
X1739703Y59125D01*
G01X1708450Y120866D02*
Y127166D01*
X1707510Y125906D01*
G01Y120866D02*
X1709390D01*
G01X1713262Y126116D02*
X1713732Y126746D01*
X1714280Y127061D01*
X1714907Y127166D01*
X1715690Y126956D01*
X1716238Y126431D01*
X1716395Y125801D01*
X1716317Y125171D01*
X1716003Y124646D01*
X1714437Y123596D01*
X1713732Y122861D01*
X1713262Y121811D01*
X1713105Y120866D01*
X1716395D01*
G01X1721990D02*
Y127166D01*
X1719092Y122651D01*
X1723008D01*
G01X1727350Y127166D02*
X1726723Y126956D01*
X1726253Y126431D01*
X1725940Y125801D01*
X1725705Y124961D01*
X1725627Y124016D01*
X1725705Y123071D01*
X1725940Y122231D01*
X1726253Y121601D01*
X1726723Y121076D01*
X1727350Y120866D01*
X1727977Y121076D01*
X1728447Y121601D01*
X1728760Y122231D01*
X1728995Y123071D01*
X1729073Y124016D01*
X1728995Y124961D01*
X1728760Y125801D01*
X1728447Y126431D01*
X1727977Y126956D01*
X1727350Y127166D01*
G01X1733650Y120656D02*
X1733493Y120761D01*
Y120971D01*
X1733650Y121076D01*
X1733807Y120971D01*
Y120761D01*
X1733650Y120656D01*
G01X1739950Y120866D02*
Y127166D01*
X1739010Y125906D01*
G01Y120866D02*
X1740890D01*
G01X1744762Y123491D02*
X1745310Y124226D01*
X1745780Y124646D01*
X1746407Y124856D01*
X1746955Y124646D01*
X1747347Y124226D01*
X1747660Y123596D01*
X1747738Y122861D01*
X1747660Y122231D01*
X1747347Y121601D01*
X1746877Y121076D01*
X1746328Y120866D01*
X1745702Y121076D01*
X1745153Y121706D01*
X1744840Y122651D01*
X1744762Y123701D01*
X1744918Y125066D01*
X1745153Y125801D01*
X1745545Y126536D01*
X1746093Y127061D01*
X1746642Y127166D01*
X1747190Y126956D01*
X1747582Y126431D01*
G01X1712250Y160236D02*
Y166536D01*
X1711310Y165276D01*
G01Y160236D02*
X1713190D01*
G01X1717062Y162861D02*
X1717610Y163596D01*
X1718080Y164016D01*
X1718707Y164226D01*
X1719255Y164016D01*
X1719647Y163596D01*
X1719960Y162966D01*
X1720038Y162231D01*
X1719960Y161601D01*
X1719647Y160971D01*
X1719177Y160446D01*
X1718628Y160236D01*
X1718002Y160446D01*
X1717453Y161076D01*
X1717140Y162021D01*
X1717062Y163071D01*
X1717218Y164436D01*
X1717453Y165171D01*
X1717845Y165906D01*
X1718393Y166431D01*
X1718942Y166536D01*
X1719490Y166326D01*
X1719882Y165801D01*
G01X1723127Y161496D02*
X1723597Y160761D01*
X1724223Y160341D01*
X1724928Y160236D01*
X1725555Y160341D01*
X1726182Y160866D01*
X1726573Y161496D01*
X1726652Y162126D01*
X1726495Y162861D01*
X1725947Y163386D01*
X1725398Y163596D01*
X1724693D01*
G01X1725398D02*
X1725868Y163911D01*
X1726260Y164436D01*
X1726417Y165066D01*
X1726260Y165696D01*
X1725868Y166221D01*
X1725163Y166536D01*
X1724458Y166431D01*
X1723753Y166011D01*
G01X1729427Y161496D02*
X1729897Y160761D01*
X1730523Y160341D01*
X1731228Y160236D01*
X1731855Y160341D01*
X1732482Y160866D01*
X1732873Y161496D01*
X1732952Y162126D01*
X1732795Y162861D01*
X1732247Y163386D01*
X1731698Y163596D01*
X1730993D01*
G01X1731698D02*
X1732168Y163911D01*
X1732560Y164436D01*
X1732717Y165066D01*
X1732560Y165696D01*
X1732168Y166221D01*
X1731463Y166536D01*
X1730758Y166431D01*
X1730053Y166011D01*
G01X1737450Y160026D02*
X1737293Y160131D01*
Y160341D01*
X1737450Y160446D01*
X1737607Y160341D01*
Y160131D01*
X1737450Y160026D01*
G01X1743750Y160236D02*
X1744298Y160341D01*
X1744925Y160656D01*
X1745317Y161181D01*
X1745473Y161916D01*
X1745317Y162651D01*
X1744847Y163281D01*
X1744142Y163596D01*
X1743358D01*
X1742888Y163806D01*
X1742497Y164331D01*
X1742340Y165066D01*
X1742575Y165801D01*
X1743123Y166326D01*
X1743750Y166536D01*
X1744377Y166326D01*
X1744925Y165801D01*
X1745160Y165066D01*
X1745003Y164331D01*
X1744612Y163806D01*
X1744142Y163596D01*
X1743358D01*
X1742653Y163281D01*
X1742183Y162651D01*
X1742027Y161916D01*
X1742183Y161181D01*
X1742575Y160656D01*
X1743202Y160341D01*
X1743750Y160236D01*
G01X1748562Y162861D02*
X1749110Y163596D01*
X1749580Y164016D01*
X1750207Y164226D01*
X1750755Y164016D01*
X1751147Y163596D01*
X1751460Y162966D01*
X1751538Y162231D01*
X1751460Y161601D01*
X1751147Y160971D01*
X1750677Y160446D01*
X1750128Y160236D01*
X1749502Y160446D01*
X1748953Y161076D01*
X1748640Y162021D01*
X1748562Y163071D01*
X1748718Y164436D01*
X1748953Y165171D01*
X1749345Y165906D01*
X1749893Y166431D01*
X1750442Y166536D01*
X1750990Y166326D01*
X1751382Y165801D01*
G01X1707100Y190736D02*
Y197036D01*
X1706160Y195776D01*
G01Y190736D02*
X1708040D01*
G01X1712068Y191471D02*
X1712617Y190946D01*
X1713243Y190736D01*
X1713870Y190946D01*
X1714418Y191576D01*
X1714810Y192521D01*
X1714967Y193466D01*
Y194621D01*
X1714810Y195566D01*
X1714418Y196406D01*
X1713948Y196826D01*
X1713400Y197036D01*
X1712773Y196826D01*
X1712303Y196406D01*
X1711990Y195776D01*
X1711833Y194936D01*
X1711990Y194201D01*
X1712382Y193466D01*
X1712852Y193046D01*
X1713400Y192941D01*
X1714027Y193151D01*
X1714497Y193676D01*
X1714967Y194621D01*
G01X1719700Y190736D02*
X1720248Y190841D01*
X1720875Y191156D01*
X1721267Y191681D01*
X1721423Y192416D01*
X1721267Y193151D01*
X1720797Y193781D01*
X1720092Y194096D01*
X1719308D01*
X1718838Y194306D01*
X1718447Y194831D01*
X1718290Y195566D01*
X1718525Y196301D01*
X1719073Y196826D01*
X1719700Y197036D01*
X1720327Y196826D01*
X1720875Y196301D01*
X1721110Y195566D01*
X1720953Y194831D01*
X1720562Y194306D01*
X1720092Y194096D01*
X1719308D01*
X1718603Y193781D01*
X1718133Y193151D01*
X1717977Y192416D01*
X1718133Y191681D01*
X1718525Y191156D01*
X1719152Y190841D01*
X1719700Y190736D01*
G01X1724277Y191996D02*
X1724747Y191261D01*
X1725373Y190841D01*
X1726078Y190736D01*
X1726705Y190841D01*
X1727332Y191366D01*
X1727723Y191996D01*
X1727802Y192626D01*
X1727645Y193361D01*
X1727097Y193886D01*
X1726548Y194096D01*
X1725843D01*
G01X1726548D02*
X1727018Y194411D01*
X1727410Y194936D01*
X1727567Y195566D01*
X1727410Y196196D01*
X1727018Y196721D01*
X1726313Y197036D01*
X1725608Y196931D01*
X1724903Y196511D01*
G01X1732300Y190526D02*
X1732143Y190631D01*
Y190841D01*
X1732300Y190946D01*
X1732457Y190841D01*
Y190631D01*
X1732300Y190526D01*
G01X1738600Y190736D02*
X1739148Y190841D01*
X1739775Y191156D01*
X1740167Y191681D01*
X1740323Y192416D01*
X1740167Y193151D01*
X1739697Y193781D01*
X1738992Y194096D01*
X1738208D01*
X1737738Y194306D01*
X1737347Y194831D01*
X1737190Y195566D01*
X1737425Y196301D01*
X1737973Y196826D01*
X1738600Y197036D01*
X1739227Y196826D01*
X1739775Y196301D01*
X1740010Y195566D01*
X1739853Y194831D01*
X1739462Y194306D01*
X1738992Y194096D01*
X1738208D01*
X1737503Y193781D01*
X1737033Y193151D01*
X1736877Y192416D01*
X1737033Y191681D01*
X1737425Y191156D01*
X1738052Y190841D01*
X1738600Y190736D01*
G01X1743412Y193361D02*
X1743960Y194096D01*
X1744430Y194516D01*
X1745057Y194726D01*
X1745605Y194516D01*
X1745997Y194096D01*
X1746310Y193466D01*
X1746388Y192731D01*
X1746310Y192101D01*
X1745997Y191471D01*
X1745527Y190946D01*
X1744978Y190736D01*
X1744352Y190946D01*
X1743803Y191576D01*
X1743490Y192521D01*
X1743412Y193571D01*
X1743568Y194936D01*
X1743803Y195671D01*
X1744195Y196406D01*
X1744743Y196931D01*
X1745292Y197036D01*
X1745840Y196826D01*
X1746232Y196301D01*
G01X1697150Y205150D02*
X1690850D01*
X1692110Y204210D01*
G01X1697150D02*
Y206090D01*
G01X1694525Y209962D02*
X1693790Y210510D01*
X1693370Y210980D01*
X1693160Y211607D01*
X1693370Y212155D01*
X1693790Y212547D01*
X1694420Y212860D01*
X1695155Y212938D01*
X1695785Y212860D01*
X1696415Y212547D01*
X1696940Y212077D01*
X1697150Y211528D01*
X1696940Y210902D01*
X1696310Y210353D01*
X1695365Y210040D01*
X1694315Y209962D01*
X1692950Y210118D01*
X1692215Y210353D01*
X1691480Y210745D01*
X1690955Y211293D01*
X1690850Y211842D01*
X1691060Y212390D01*
X1691585Y212782D01*
G01X1697150Y217750D02*
X1697045Y218298D01*
X1696730Y218925D01*
X1696205Y219317D01*
X1695470Y219473D01*
X1694735Y219317D01*
X1694105Y218847D01*
X1693790Y218142D01*
Y217358D01*
X1693580Y216888D01*
X1693055Y216497D01*
X1692320Y216340D01*
X1691585Y216575D01*
X1691060Y217123D01*
X1690850Y217750D01*
X1691060Y218377D01*
X1691585Y218925D01*
X1692320Y219160D01*
X1693055Y219003D01*
X1693580Y218612D01*
X1693790Y218142D01*
Y217358D01*
X1694105Y216653D01*
X1694735Y216183D01*
X1695470Y216027D01*
X1696205Y216183D01*
X1696730Y216575D01*
X1697045Y217202D01*
X1697150Y217750D01*
G01X1695890Y222327D02*
X1696625Y222797D01*
X1697045Y223423D01*
X1697150Y224128D01*
X1697045Y224755D01*
X1696520Y225382D01*
X1695890Y225773D01*
X1695260Y225852D01*
X1694525Y225695D01*
X1694000Y225147D01*
X1693790Y224598D01*
Y223893D01*
G01Y224598D02*
X1693475Y225068D01*
X1692950Y225460D01*
X1692320Y225617D01*
X1691690Y225460D01*
X1691165Y225068D01*
X1690850Y224363D01*
X1690955Y223658D01*
X1691375Y222953D01*
G01X1696205Y228627D02*
X1696730Y229097D01*
X1697045Y229645D01*
X1697150Y230350D01*
X1696940Y231055D01*
X1696520Y231603D01*
X1695785Y231995D01*
X1694945Y232073D01*
X1694105Y231917D01*
X1693580Y231525D01*
X1693160Y230977D01*
X1693055Y230428D01*
X1693160Y229880D01*
X1693580Y229175D01*
X1690850Y229410D01*
Y231525D01*
G01X1697360Y236650D02*
X1697255Y236493D01*
X1697045D01*
X1696940Y236650D01*
X1697045Y236807D01*
X1697255D01*
X1697360Y236650D01*
G01X1690850Y242950D02*
X1691060Y242323D01*
X1691585Y241853D01*
X1692215Y241540D01*
X1693055Y241305D01*
X1694000Y241227D01*
X1694945Y241305D01*
X1695785Y241540D01*
X1696415Y241853D01*
X1696940Y242323D01*
X1697150Y242950D01*
X1696940Y243577D01*
X1696415Y244047D01*
X1695785Y244360D01*
X1694945Y244595D01*
X1694000Y244673D01*
X1693055Y244595D01*
X1692215Y244360D01*
X1691585Y244047D01*
X1691060Y243577D01*
X1690850Y242950D01*
G01X1697150Y250190D02*
X1690850D01*
X1695365Y247292D01*
Y251208D01*
G01X1762247Y410200D02*
Y415200D01*
X1764653D01*
G01X1763767Y412783D02*
X1762247D01*
G01X1767790Y415200D02*
X1769310D01*
G01X1768550D02*
Y410200D01*
G01X1767790D02*
X1769310D01*
G01X1774030Y412700D02*
X1775297D01*
Y411200D01*
X1774917Y410700D01*
X1774473Y410367D01*
X1773840Y410200D01*
X1773207Y410367D01*
X1772763Y410700D01*
X1772383Y411200D01*
X1772130Y411783D01*
X1772003Y412450D01*
Y413033D01*
X1772130Y413533D01*
X1772383Y414117D01*
X1772763Y414617D01*
X1773143Y414950D01*
X1773650Y415200D01*
X1774093D01*
X1774600Y415033D01*
X1774980Y414700D01*
G01X1777357Y415200D02*
Y411617D01*
X1777610Y410867D01*
X1778117Y410367D01*
X1778750Y410200D01*
X1779383Y410367D01*
X1779890Y410867D01*
X1780143Y411617D01*
Y415200D01*
G01X1782583Y410200D02*
Y415200D01*
X1784167D01*
X1784673Y414950D01*
X1784990Y414617D01*
X1785117Y413950D01*
X1784990Y413283D01*
X1784610Y412867D01*
X1784167Y412617D01*
X1782583D01*
G01X1784167D02*
X1785117Y410200D01*
G01X1790217D02*
X1787683D01*
Y415200D01*
X1790217D01*
G01X1789203Y412783D02*
X1787683D01*
G01X1811997Y-174667D02*
X1812440Y-174083D01*
X1812820Y-173750D01*
X1813327Y-173583D01*
X1813770Y-173750D01*
X1814087Y-174083D01*
X1814340Y-174583D01*
X1814403Y-175167D01*
X1814340Y-175667D01*
X1814087Y-176167D01*
X1813707Y-176583D01*
X1813263Y-176750D01*
X1812757Y-176583D01*
X1812313Y-176083D01*
X1812060Y-175333D01*
X1811997Y-174500D01*
X1812123Y-173417D01*
X1812313Y-172833D01*
X1812630Y-172250D01*
X1813073Y-171833D01*
X1813517Y-171750D01*
X1813960Y-171917D01*
X1814277Y-172333D01*
G01X1816907Y-175750D02*
X1817287Y-176333D01*
X1817793Y-176667D01*
X1818363Y-176750D01*
X1818870Y-176667D01*
X1819377Y-176250D01*
X1819693Y-175750D01*
X1819757Y-175250D01*
X1819630Y-174667D01*
X1819187Y-174250D01*
X1818743Y-174083D01*
X1818173D01*
G01X1818743D02*
X1819123Y-173833D01*
X1819440Y-173417D01*
X1819567Y-172917D01*
X1819440Y-172417D01*
X1819123Y-172000D01*
X1818553Y-171750D01*
X1817983Y-171833D01*
X1817413Y-172167D01*
G01X1823400Y-176917D02*
X1823273Y-176833D01*
Y-176667D01*
X1823400Y-176583D01*
X1823527Y-176667D01*
Y-176833D01*
X1823400Y-176917D01*
G01X1828500Y-171750D02*
X1827993Y-171917D01*
X1827613Y-172333D01*
X1827360Y-172833D01*
X1827170Y-173500D01*
X1827107Y-174250D01*
X1827170Y-175000D01*
X1827360Y-175667D01*
X1827613Y-176167D01*
X1827993Y-176583D01*
X1828500Y-176750D01*
X1829007Y-176583D01*
X1829387Y-176167D01*
X1829640Y-175667D01*
X1829830Y-175000D01*
X1829893Y-174250D01*
X1829830Y-173500D01*
X1829640Y-172833D01*
X1829387Y-172333D01*
X1829007Y-171917D01*
X1828500Y-171750D01*
G01X1832650Y-173417D02*
X1834550Y-176750D01*
G01Y-173417D02*
X1832650Y-176750D01*
G01X1837307Y-175750D02*
X1837687Y-176333D01*
X1838193Y-176667D01*
X1838763Y-176750D01*
X1839270Y-176667D01*
X1839777Y-176250D01*
X1840093Y-175750D01*
X1840157Y-175250D01*
X1840030Y-174667D01*
X1839587Y-174250D01*
X1839143Y-174083D01*
X1838573D01*
G01X1839143D02*
X1839523Y-173833D01*
X1839840Y-173417D01*
X1839967Y-172917D01*
X1839840Y-172417D01*
X1839523Y-172000D01*
X1838953Y-171750D01*
X1838383Y-171833D01*
X1837813Y-172167D01*
G01X1843800Y-176750D02*
X1844243Y-176667D01*
X1844750Y-176417D01*
X1845067Y-176000D01*
X1845193Y-175417D01*
X1845067Y-174833D01*
X1844687Y-174333D01*
X1844117Y-174083D01*
X1843483D01*
X1843103Y-173917D01*
X1842787Y-173500D01*
X1842660Y-172917D01*
X1842850Y-172333D01*
X1843293Y-171917D01*
X1843800Y-171750D01*
X1844307Y-171917D01*
X1844750Y-172333D01*
X1844940Y-172917D01*
X1844813Y-173500D01*
X1844497Y-173917D01*
X1844117Y-174083D01*
X1843483D01*
X1842913Y-174333D01*
X1842533Y-174833D01*
X1842407Y-175417D01*
X1842533Y-176000D01*
X1842850Y-176417D01*
X1843357Y-176667D01*
X1843800Y-176750D01*
G01X1848900Y-176917D02*
X1848773Y-176833D01*
Y-176667D01*
X1848900Y-176583D01*
X1849027Y-176667D01*
Y-176833D01*
X1848900Y-176917D01*
G01X1854000Y-171750D02*
X1853493Y-171917D01*
X1853113Y-172333D01*
X1852860Y-172833D01*
X1852670Y-173500D01*
X1852607Y-174250D01*
X1852670Y-175000D01*
X1852860Y-175667D01*
X1853113Y-176167D01*
X1853493Y-176583D01*
X1854000Y-176750D01*
X1854507Y-176583D01*
X1854887Y-176167D01*
X1855140Y-175667D01*
X1855330Y-175000D01*
X1855393Y-174250D01*
X1855330Y-173500D01*
X1855140Y-172833D01*
X1854887Y-172333D01*
X1854507Y-171917D01*
X1854000Y-171750D01*
G01X1823400Y-153050D02*
Y-148050D01*
X1822640Y-149050D01*
G01Y-153050D02*
X1824160D01*
G01X1829260D02*
Y-148050D01*
X1826917Y-151633D01*
X1830083D01*
G01X1832397Y-148883D02*
X1832777Y-148383D01*
X1833220Y-148133D01*
X1833727Y-148050D01*
X1834360Y-148217D01*
X1834803Y-148633D01*
X1834930Y-149133D01*
X1834867Y-149633D01*
X1834613Y-150050D01*
X1833347Y-150883D01*
X1832777Y-151467D01*
X1832397Y-152300D01*
X1832270Y-153050D01*
X1834930D01*
G01X1838700Y-153217D02*
X1838573Y-153133D01*
Y-152967D01*
X1838700Y-152883D01*
X1838827Y-152967D01*
Y-153133D01*
X1838700Y-153217D01*
G01X1843800Y-148050D02*
X1843293Y-148217D01*
X1842913Y-148633D01*
X1842660Y-149133D01*
X1842470Y-149800D01*
X1842407Y-150550D01*
X1842470Y-151300D01*
X1842660Y-151967D01*
X1842913Y-152467D01*
X1843293Y-152883D01*
X1843800Y-153050D01*
X1844307Y-152883D01*
X1844687Y-152467D01*
X1844940Y-151967D01*
X1845130Y-151300D01*
X1845193Y-150550D01*
X1845130Y-149800D01*
X1844940Y-149133D01*
X1844687Y-148633D01*
X1844307Y-148217D01*
X1843800Y-148050D01*
G01X1823400Y-129350D02*
Y-124350D01*
X1822640Y-125350D01*
G01Y-129350D02*
X1824160D01*
G01X1827107Y-128350D02*
X1827487Y-128933D01*
X1827993Y-129267D01*
X1828563Y-129350D01*
X1829070Y-129267D01*
X1829577Y-128850D01*
X1829893Y-128350D01*
X1829957Y-127850D01*
X1829830Y-127267D01*
X1829387Y-126850D01*
X1828943Y-126683D01*
X1828373D01*
G01X1828943D02*
X1829323Y-126433D01*
X1829640Y-126017D01*
X1829767Y-125517D01*
X1829640Y-125017D01*
X1829323Y-124600D01*
X1828753Y-124350D01*
X1828183Y-124433D01*
X1827613Y-124767D01*
G01X1833600Y-129350D02*
X1834043Y-129267D01*
X1834550Y-129017D01*
X1834867Y-128600D01*
X1834993Y-128017D01*
X1834867Y-127433D01*
X1834487Y-126933D01*
X1833917Y-126683D01*
X1833283D01*
X1832903Y-126517D01*
X1832587Y-126100D01*
X1832460Y-125517D01*
X1832650Y-124933D01*
X1833093Y-124517D01*
X1833600Y-124350D01*
X1834107Y-124517D01*
X1834550Y-124933D01*
X1834740Y-125517D01*
X1834613Y-126100D01*
X1834297Y-126517D01*
X1833917Y-126683D01*
X1833283D01*
X1832713Y-126933D01*
X1832333Y-127433D01*
X1832207Y-128017D01*
X1832333Y-128600D01*
X1832650Y-129017D01*
X1833157Y-129267D01*
X1833600Y-129350D01*
G01X1838700Y-129517D02*
X1838573Y-129433D01*
Y-129267D01*
X1838700Y-129183D01*
X1838827Y-129267D01*
Y-129433D01*
X1838700Y-129517D01*
G01X1843800Y-124350D02*
X1843293Y-124517D01*
X1842913Y-124933D01*
X1842660Y-125433D01*
X1842470Y-126100D01*
X1842407Y-126850D01*
X1842470Y-127600D01*
X1842660Y-128267D01*
X1842913Y-128767D01*
X1843293Y-129183D01*
X1843800Y-129350D01*
X1844307Y-129183D01*
X1844687Y-128767D01*
X1844940Y-128267D01*
X1845130Y-127600D01*
X1845193Y-126850D01*
X1845130Y-126100D01*
X1844940Y-125433D01*
X1844687Y-124933D01*
X1844307Y-124517D01*
X1843800Y-124350D01*
G01X1823400Y-105650D02*
Y-100650D01*
X1822640Y-101650D01*
G01Y-105650D02*
X1824160D01*
G01X1827297Y-101483D02*
X1827677Y-100983D01*
X1828120Y-100733D01*
X1828627Y-100650D01*
X1829260Y-100817D01*
X1829703Y-101233D01*
X1829830Y-101733D01*
X1829767Y-102233D01*
X1829513Y-102650D01*
X1828247Y-103483D01*
X1827677Y-104067D01*
X1827297Y-104900D01*
X1827170Y-105650D01*
X1829830D01*
G01X1833600D02*
X1834043Y-105567D01*
X1834550Y-105317D01*
X1834867Y-104900D01*
X1834993Y-104317D01*
X1834867Y-103733D01*
X1834487Y-103233D01*
X1833917Y-102983D01*
X1833283D01*
X1832903Y-102817D01*
X1832587Y-102400D01*
X1832460Y-101817D01*
X1832650Y-101233D01*
X1833093Y-100817D01*
X1833600Y-100650D01*
X1834107Y-100817D01*
X1834550Y-101233D01*
X1834740Y-101817D01*
X1834613Y-102400D01*
X1834297Y-102817D01*
X1833917Y-102983D01*
X1833283D01*
X1832713Y-103233D01*
X1832333Y-103733D01*
X1832207Y-104317D01*
X1832333Y-104900D01*
X1832650Y-105317D01*
X1833157Y-105567D01*
X1833600Y-105650D01*
G01X1838700Y-105817D02*
X1838573Y-105733D01*
Y-105567D01*
X1838700Y-105483D01*
X1838827Y-105567D01*
Y-105733D01*
X1838700Y-105817D01*
G01X1843800Y-100650D02*
X1843293Y-100817D01*
X1842913Y-101233D01*
X1842660Y-101733D01*
X1842470Y-102400D01*
X1842407Y-103150D01*
X1842470Y-103900D01*
X1842660Y-104567D01*
X1842913Y-105067D01*
X1843293Y-105483D01*
X1843800Y-105650D01*
X1844307Y-105483D01*
X1844687Y-105067D01*
X1844940Y-104567D01*
X1845130Y-103900D01*
X1845193Y-103150D01*
X1845130Y-102400D01*
X1844940Y-101733D01*
X1844687Y-101233D01*
X1844307Y-100817D01*
X1843800Y-100650D01*
G01X1825950Y-81950D02*
X1826393Y-81867D01*
X1826900Y-81617D01*
X1827217Y-81200D01*
X1827343Y-80617D01*
X1827217Y-80033D01*
X1826837Y-79533D01*
X1826267Y-79283D01*
X1825633D01*
X1825253Y-79117D01*
X1824937Y-78700D01*
X1824810Y-78117D01*
X1825000Y-77533D01*
X1825443Y-77117D01*
X1825950Y-76950D01*
X1826457Y-77117D01*
X1826900Y-77533D01*
X1827090Y-78117D01*
X1826963Y-78700D01*
X1826647Y-79117D01*
X1826267Y-79283D01*
X1825633D01*
X1825063Y-79533D01*
X1824683Y-80033D01*
X1824557Y-80617D01*
X1824683Y-81200D01*
X1825000Y-81617D01*
X1825507Y-81867D01*
X1825950Y-81950D01*
G01X1829657Y-81200D02*
X1830037Y-81617D01*
X1830480Y-81867D01*
X1831050Y-81950D01*
X1831620Y-81783D01*
X1832063Y-81450D01*
X1832380Y-80867D01*
X1832443Y-80200D01*
X1832317Y-79533D01*
X1832000Y-79117D01*
X1831557Y-78783D01*
X1831113Y-78700D01*
X1830670Y-78783D01*
X1830100Y-79117D01*
X1830290Y-76950D01*
X1832000D01*
G01X1836150Y-82117D02*
X1836023Y-82033D01*
Y-81867D01*
X1836150Y-81783D01*
X1836277Y-81867D01*
Y-82033D01*
X1836150Y-82117D01*
G01X1841250Y-76950D02*
X1840743Y-77117D01*
X1840363Y-77533D01*
X1840110Y-78033D01*
X1839920Y-78700D01*
X1839857Y-79450D01*
X1839920Y-80200D01*
X1840110Y-80867D01*
X1840363Y-81367D01*
X1840743Y-81783D01*
X1841250Y-81950D01*
X1841757Y-81783D01*
X1842137Y-81367D01*
X1842390Y-80867D01*
X1842580Y-80200D01*
X1842643Y-79450D01*
X1842580Y-78700D01*
X1842390Y-78033D01*
X1842137Y-77533D01*
X1841757Y-77117D01*
X1841250Y-76950D01*
G01X1824747Y-56167D02*
X1825190Y-55583D01*
X1825570Y-55250D01*
X1826077Y-55083D01*
X1826520Y-55250D01*
X1826837Y-55583D01*
X1827090Y-56083D01*
X1827153Y-56667D01*
X1827090Y-57167D01*
X1826837Y-57667D01*
X1826457Y-58083D01*
X1826013Y-58250D01*
X1825507Y-58083D01*
X1825063Y-57583D01*
X1824810Y-56833D01*
X1824747Y-56000D01*
X1824873Y-54917D01*
X1825063Y-54333D01*
X1825380Y-53750D01*
X1825823Y-53333D01*
X1826267Y-53250D01*
X1826710Y-53417D01*
X1827027Y-53833D01*
G01X1829657Y-57250D02*
X1830037Y-57833D01*
X1830543Y-58167D01*
X1831113Y-58250D01*
X1831620Y-58167D01*
X1832127Y-57750D01*
X1832443Y-57250D01*
X1832507Y-56750D01*
X1832380Y-56167D01*
X1831937Y-55750D01*
X1831493Y-55583D01*
X1830923D01*
G01X1831493D02*
X1831873Y-55333D01*
X1832190Y-54917D01*
X1832317Y-54417D01*
X1832190Y-53917D01*
X1831873Y-53500D01*
X1831303Y-53250D01*
X1830733Y-53333D01*
X1830163Y-53667D01*
G01X1836150Y-58417D02*
X1836023Y-58333D01*
Y-58167D01*
X1836150Y-58083D01*
X1836277Y-58167D01*
Y-58333D01*
X1836150Y-58417D01*
G01X1841250Y-53250D02*
X1840743Y-53417D01*
X1840363Y-53833D01*
X1840110Y-54333D01*
X1839920Y-55000D01*
X1839857Y-55750D01*
X1839920Y-56500D01*
X1840110Y-57167D01*
X1840363Y-57667D01*
X1840743Y-58083D01*
X1841250Y-58250D01*
X1841757Y-58083D01*
X1842137Y-57667D01*
X1842390Y-57167D01*
X1842580Y-56500D01*
X1842643Y-55750D01*
X1842580Y-55000D01*
X1842390Y-54333D01*
X1842137Y-53833D01*
X1841757Y-53417D01*
X1841250Y-53250D01*
G01X1826710Y-34550D02*
Y-29550D01*
X1824367Y-33133D01*
X1827533D01*
G01X1829657Y-33550D02*
X1830037Y-34133D01*
X1830543Y-34467D01*
X1831113Y-34550D01*
X1831620Y-34467D01*
X1832127Y-34050D01*
X1832443Y-33550D01*
X1832507Y-33050D01*
X1832380Y-32467D01*
X1831937Y-32050D01*
X1831493Y-31883D01*
X1830923D01*
G01X1831493D02*
X1831873Y-31633D01*
X1832190Y-31217D01*
X1832317Y-30717D01*
X1832190Y-30217D01*
X1831873Y-29800D01*
X1831303Y-29550D01*
X1830733Y-29633D01*
X1830163Y-29967D01*
G01X1836150Y-34717D02*
X1836023Y-34633D01*
Y-34467D01*
X1836150Y-34383D01*
X1836277Y-34467D01*
Y-34633D01*
X1836150Y-34717D01*
G01X1841250Y-29550D02*
X1840743Y-29717D01*
X1840363Y-30133D01*
X1840110Y-30633D01*
X1839920Y-31300D01*
X1839857Y-32050D01*
X1839920Y-32800D01*
X1840110Y-33467D01*
X1840363Y-33967D01*
X1840743Y-34383D01*
X1841250Y-34550D01*
X1841757Y-34383D01*
X1842137Y-33967D01*
X1842390Y-33467D01*
X1842580Y-32800D01*
X1842643Y-32050D01*
X1842580Y-31300D01*
X1842390Y-30633D01*
X1842137Y-30133D01*
X1841757Y-29717D01*
X1841250Y-29550D01*
G01X1826710Y-10850D02*
Y-5850D01*
X1824367Y-9433D01*
X1827533D01*
G01X1829847Y-6683D02*
X1830227Y-6183D01*
X1830670Y-5933D01*
X1831177Y-5850D01*
X1831810Y-6017D01*
X1832253Y-6433D01*
X1832380Y-6933D01*
X1832317Y-7433D01*
X1832063Y-7850D01*
X1830797Y-8683D01*
X1830227Y-9267D01*
X1829847Y-10100D01*
X1829720Y-10850D01*
X1832380D01*
G01X1836150Y-11017D02*
X1836023Y-10933D01*
Y-10767D01*
X1836150Y-10683D01*
X1836277Y-10767D01*
Y-10933D01*
X1836150Y-11017D01*
G01X1841250Y-5850D02*
X1840743Y-6017D01*
X1840363Y-6433D01*
X1840110Y-6933D01*
X1839920Y-7600D01*
X1839857Y-8350D01*
X1839920Y-9100D01*
X1840110Y-9767D01*
X1840363Y-10267D01*
X1840743Y-10683D01*
X1841250Y-10850D01*
X1841757Y-10683D01*
X1842137Y-10267D01*
X1842390Y-9767D01*
X1842580Y-9100D01*
X1842643Y-8350D01*
X1842580Y-7600D01*
X1842390Y-6933D01*
X1842137Y-6433D01*
X1841757Y-6017D01*
X1841250Y-5850D01*
G01X1823400Y12850D02*
Y17850D01*
X1822640Y16850D01*
G01Y12850D02*
X1824160D01*
G01X1827107Y13600D02*
X1827487Y13183D01*
X1827930Y12933D01*
X1828500Y12850D01*
X1829070Y13017D01*
X1829513Y13350D01*
X1829830Y13933D01*
X1829893Y14600D01*
X1829767Y15267D01*
X1829450Y15683D01*
X1829007Y16017D01*
X1828563Y16100D01*
X1828120Y16017D01*
X1827550Y15683D01*
X1827740Y17850D01*
X1829450D01*
G01X1833600Y12850D02*
X1834043Y12933D01*
X1834550Y13183D01*
X1834867Y13600D01*
X1834993Y14183D01*
X1834867Y14767D01*
X1834487Y15267D01*
X1833917Y15517D01*
X1833283D01*
X1832903Y15683D01*
X1832587Y16100D01*
X1832460Y16683D01*
X1832650Y17267D01*
X1833093Y17683D01*
X1833600Y17850D01*
X1834107Y17683D01*
X1834550Y17267D01*
X1834740Y16683D01*
X1834613Y16100D01*
X1834297Y15683D01*
X1833917Y15517D01*
X1833283D01*
X1832713Y15267D01*
X1832333Y14767D01*
X1832207Y14183D01*
X1832333Y13600D01*
X1832650Y13183D01*
X1833157Y12933D01*
X1833600Y12850D01*
G01X1838700Y12683D02*
X1838573Y12767D01*
Y12933D01*
X1838700Y13017D01*
X1838827Y12933D01*
Y12767D01*
X1838700Y12683D01*
G01X1843800Y17850D02*
X1843293Y17683D01*
X1842913Y17267D01*
X1842660Y16767D01*
X1842470Y16100D01*
X1842407Y15350D01*
X1842470Y14600D01*
X1842660Y13933D01*
X1842913Y13433D01*
X1843293Y13017D01*
X1843800Y12850D01*
X1844307Y13017D01*
X1844687Y13433D01*
X1844940Y13933D01*
X1845130Y14600D01*
X1845193Y15350D01*
X1845130Y16100D01*
X1844940Y16767D01*
X1844687Y17267D01*
X1844307Y17683D01*
X1843800Y17850D01*
G01X1824873Y37133D02*
X1825317Y36717D01*
X1825823Y36550D01*
X1826330Y36717D01*
X1826773Y37217D01*
X1827090Y37967D01*
X1827217Y38717D01*
Y39633D01*
X1827090Y40383D01*
X1826773Y41050D01*
X1826393Y41383D01*
X1825950Y41550D01*
X1825443Y41383D01*
X1825063Y41050D01*
X1824810Y40550D01*
X1824683Y39883D01*
X1824810Y39300D01*
X1825127Y38717D01*
X1825507Y38383D01*
X1825950Y38300D01*
X1826457Y38467D01*
X1826837Y38883D01*
X1827217Y39633D01*
G01X1829973Y37133D02*
X1830417Y36717D01*
X1830923Y36550D01*
X1831430Y36717D01*
X1831873Y37217D01*
X1832190Y37967D01*
X1832317Y38717D01*
Y39633D01*
X1832190Y40383D01*
X1831873Y41050D01*
X1831493Y41383D01*
X1831050Y41550D01*
X1830543Y41383D01*
X1830163Y41050D01*
X1829910Y40550D01*
X1829783Y39883D01*
X1829910Y39300D01*
X1830227Y38717D01*
X1830607Y38383D01*
X1831050Y38300D01*
X1831557Y38467D01*
X1831937Y38883D01*
X1832317Y39633D01*
G01X1836150Y36383D02*
X1836023Y36467D01*
Y36633D01*
X1836150Y36717D01*
X1836277Y36633D01*
Y36467D01*
X1836150Y36383D01*
G01X1841250Y41550D02*
X1840743Y41383D01*
X1840363Y40967D01*
X1840110Y40467D01*
X1839920Y39800D01*
X1839857Y39050D01*
X1839920Y38300D01*
X1840110Y37633D01*
X1840363Y37133D01*
X1840743Y36717D01*
X1841250Y36550D01*
X1841757Y36717D01*
X1842137Y37133D01*
X1842390Y37633D01*
X1842580Y38300D01*
X1842643Y39050D01*
X1842580Y39800D01*
X1842390Y40467D01*
X1842137Y40967D01*
X1841757Y41383D01*
X1841250Y41550D01*
G01X1825950Y60250D02*
X1826393Y60333D01*
X1826900Y60583D01*
X1827217Y61000D01*
X1827343Y61583D01*
X1827217Y62167D01*
X1826837Y62667D01*
X1826267Y62917D01*
X1825633D01*
X1825253Y63083D01*
X1824937Y63500D01*
X1824810Y64083D01*
X1825000Y64667D01*
X1825443Y65083D01*
X1825950Y65250D01*
X1826457Y65083D01*
X1826900Y64667D01*
X1827090Y64083D01*
X1826963Y63500D01*
X1826647Y63083D01*
X1826267Y62917D01*
X1825633D01*
X1825063Y62667D01*
X1824683Y62167D01*
X1824557Y61583D01*
X1824683Y61000D01*
X1825000Y60583D01*
X1825507Y60333D01*
X1825950Y60250D01*
G01X1831050Y65250D02*
X1830543Y65083D01*
X1830163Y64667D01*
X1829910Y64167D01*
X1829720Y63500D01*
X1829657Y62750D01*
X1829720Y62000D01*
X1829910Y61333D01*
X1830163Y60833D01*
X1830543Y60417D01*
X1831050Y60250D01*
X1831557Y60417D01*
X1831937Y60833D01*
X1832190Y61333D01*
X1832380Y62000D01*
X1832443Y62750D01*
X1832380Y63500D01*
X1832190Y64167D01*
X1831937Y64667D01*
X1831557Y65083D01*
X1831050Y65250D01*
G01X1836150Y60083D02*
X1836023Y60167D01*
Y60333D01*
X1836150Y60417D01*
X1836277Y60333D01*
Y60167D01*
X1836150Y60083D01*
G01X1841250Y65250D02*
X1840743Y65083D01*
X1840363Y64667D01*
X1840110Y64167D01*
X1839920Y63500D01*
X1839857Y62750D01*
X1839920Y62000D01*
X1840110Y61333D01*
X1840363Y60833D01*
X1840743Y60417D01*
X1841250Y60250D01*
X1841757Y60417D01*
X1842137Y60833D01*
X1842390Y61333D01*
X1842580Y62000D01*
X1842643Y62750D01*
X1842580Y63500D01*
X1842390Y64167D01*
X1842137Y64667D01*
X1841757Y65083D01*
X1841250Y65250D01*
G01X1824747Y86033D02*
X1825190Y86617D01*
X1825570Y86950D01*
X1826077Y87117D01*
X1826520Y86950D01*
X1826837Y86617D01*
X1827090Y86117D01*
X1827153Y85533D01*
X1827090Y85033D01*
X1826837Y84533D01*
X1826457Y84117D01*
X1826013Y83950D01*
X1825507Y84117D01*
X1825063Y84617D01*
X1824810Y85367D01*
X1824747Y86200D01*
X1824873Y87283D01*
X1825063Y87867D01*
X1825380Y88450D01*
X1825823Y88867D01*
X1826267Y88950D01*
X1826710Y88783D01*
X1827027Y88367D01*
G01X1829847Y88117D02*
X1830227Y88617D01*
X1830670Y88867D01*
X1831177Y88950D01*
X1831810Y88783D01*
X1832253Y88367D01*
X1832380Y87867D01*
X1832317Y87367D01*
X1832063Y86950D01*
X1830797Y86117D01*
X1830227Y85533D01*
X1829847Y84700D01*
X1829720Y83950D01*
X1832380D01*
G01X1836150Y83783D02*
X1836023Y83867D01*
Y84033D01*
X1836150Y84117D01*
X1836277Y84033D01*
Y83867D01*
X1836150Y83783D01*
G01X1841250Y88950D02*
X1840743Y88783D01*
X1840363Y88367D01*
X1840110Y87867D01*
X1839920Y87200D01*
X1839857Y86450D01*
X1839920Y85700D01*
X1840110Y85033D01*
X1840363Y84533D01*
X1840743Y84117D01*
X1841250Y83950D01*
X1841757Y84117D01*
X1842137Y84533D01*
X1842390Y85033D01*
X1842580Y85700D01*
X1842643Y86450D01*
X1842580Y87200D01*
X1842390Y87867D01*
X1842137Y88367D01*
X1841757Y88783D01*
X1841250Y88950D01*
G01X1826710Y107650D02*
Y112650D01*
X1824367Y109067D01*
X1827533D01*
G01X1829847Y109733D02*
X1830290Y110317D01*
X1830670Y110650D01*
X1831177Y110817D01*
X1831620Y110650D01*
X1831937Y110317D01*
X1832190Y109817D01*
X1832253Y109233D01*
X1832190Y108733D01*
X1831937Y108233D01*
X1831557Y107817D01*
X1831113Y107650D01*
X1830607Y107817D01*
X1830163Y108317D01*
X1829910Y109067D01*
X1829847Y109900D01*
X1829973Y110983D01*
X1830163Y111567D01*
X1830480Y112150D01*
X1830923Y112567D01*
X1831367Y112650D01*
X1831810Y112483D01*
X1832127Y112067D01*
G01X1836150Y107483D02*
X1836023Y107567D01*
Y107733D01*
X1836150Y107817D01*
X1836277Y107733D01*
Y107567D01*
X1836150Y107483D01*
G01X1841250Y112650D02*
X1840743Y112483D01*
X1840363Y112067D01*
X1840110Y111567D01*
X1839920Y110900D01*
X1839857Y110150D01*
X1839920Y109400D01*
X1840110Y108733D01*
X1840363Y108233D01*
X1840743Y107817D01*
X1841250Y107650D01*
X1841757Y107817D01*
X1842137Y108233D01*
X1842390Y108733D01*
X1842580Y109400D01*
X1842643Y110150D01*
X1842580Y110900D01*
X1842390Y111567D01*
X1842137Y112067D01*
X1841757Y112483D01*
X1841250Y112650D01*
G01X1826710Y131350D02*
Y136350D01*
X1824367Y132767D01*
X1827533D01*
G01X1829657Y132350D02*
X1830037Y131767D01*
X1830543Y131433D01*
X1831113Y131350D01*
X1831620Y131433D01*
X1832127Y131850D01*
X1832443Y132350D01*
X1832507Y132850D01*
X1832380Y133433D01*
X1831937Y133850D01*
X1831493Y134017D01*
X1830923D01*
G01X1831493D02*
X1831873Y134267D01*
X1832190Y134683D01*
X1832317Y135183D01*
X1832190Y135683D01*
X1831873Y136100D01*
X1831303Y136350D01*
X1830733Y136267D01*
X1830163Y135933D01*
G01X1836150Y131183D02*
X1836023Y131267D01*
Y131433D01*
X1836150Y131517D01*
X1836277Y131433D01*
Y131267D01*
X1836150Y131183D01*
G01X1841250Y136350D02*
X1840743Y136183D01*
X1840363Y135767D01*
X1840110Y135267D01*
X1839920Y134600D01*
X1839857Y133850D01*
X1839920Y133100D01*
X1840110Y132433D01*
X1840363Y131933D01*
X1840743Y131517D01*
X1841250Y131350D01*
X1841757Y131517D01*
X1842137Y131933D01*
X1842390Y132433D01*
X1842580Y133100D01*
X1842643Y133850D01*
X1842580Y134600D01*
X1842390Y135267D01*
X1842137Y135767D01*
X1841757Y136183D01*
X1841250Y136350D01*
G01X1826710Y155050D02*
Y160050D01*
X1824367Y156467D01*
X1827533D01*
G01X1831050Y155050D02*
Y160050D01*
X1830290Y159050D01*
G01Y155050D02*
X1831810D01*
G01X1836150Y154883D02*
X1836023Y154967D01*
Y155133D01*
X1836150Y155217D01*
X1836277Y155133D01*
Y154967D01*
X1836150Y154883D01*
G01X1841250Y160050D02*
X1840743Y159883D01*
X1840363Y159467D01*
X1840110Y158967D01*
X1839920Y158300D01*
X1839857Y157550D01*
X1839920Y156800D01*
X1840110Y156133D01*
X1840363Y155633D01*
X1840743Y155217D01*
X1841250Y155050D01*
X1841757Y155217D01*
X1842137Y155633D01*
X1842390Y156133D01*
X1842580Y156800D01*
X1842643Y157550D01*
X1842580Y158300D01*
X1842390Y158967D01*
X1842137Y159467D01*
X1841757Y159883D01*
X1841250Y160050D01*
G01X1824557Y179750D02*
X1824937Y179167D01*
X1825443Y178833D01*
X1826013Y178750D01*
X1826520Y178833D01*
X1827027Y179250D01*
X1827343Y179750D01*
X1827407Y180250D01*
X1827280Y180833D01*
X1826837Y181250D01*
X1826393Y181417D01*
X1825823D01*
G01X1826393D02*
X1826773Y181667D01*
X1827090Y182083D01*
X1827217Y182583D01*
X1827090Y183083D01*
X1826773Y183500D01*
X1826203Y183750D01*
X1825633Y183667D01*
X1825063Y183333D01*
G01X1831050Y178750D02*
X1831493Y178833D01*
X1832000Y179083D01*
X1832317Y179500D01*
X1832443Y180083D01*
X1832317Y180667D01*
X1831937Y181167D01*
X1831367Y181417D01*
X1830733D01*
X1830353Y181583D01*
X1830037Y182000D01*
X1829910Y182583D01*
X1830100Y183167D01*
X1830543Y183583D01*
X1831050Y183750D01*
X1831557Y183583D01*
X1832000Y183167D01*
X1832190Y182583D01*
X1832063Y182000D01*
X1831747Y181583D01*
X1831367Y181417D01*
X1830733D01*
X1830163Y181167D01*
X1829783Y180667D01*
X1829657Y180083D01*
X1829783Y179500D01*
X1830100Y179083D01*
X1830607Y178833D01*
X1831050Y178750D01*
G01X1836150Y178583D02*
X1836023Y178667D01*
Y178833D01*
X1836150Y178917D01*
X1836277Y178833D01*
Y178667D01*
X1836150Y178583D01*
G01X1841250Y183750D02*
X1840743Y183583D01*
X1840363Y183167D01*
X1840110Y182667D01*
X1839920Y182000D01*
X1839857Y181250D01*
X1839920Y180500D01*
X1840110Y179833D01*
X1840363Y179333D01*
X1840743Y178917D01*
X1841250Y178750D01*
X1841757Y178917D01*
X1842137Y179333D01*
X1842390Y179833D01*
X1842580Y180500D01*
X1842643Y181250D01*
X1842580Y182000D01*
X1842390Y182667D01*
X1842137Y183167D01*
X1841757Y183583D01*
X1841250Y183750D01*
G01X1824557Y203450D02*
X1824937Y202867D01*
X1825443Y202533D01*
X1826013Y202450D01*
X1826520Y202533D01*
X1827027Y202950D01*
X1827343Y203450D01*
X1827407Y203950D01*
X1827280Y204533D01*
X1826837Y204950D01*
X1826393Y205117D01*
X1825823D01*
G01X1826393D02*
X1826773Y205367D01*
X1827090Y205783D01*
X1827217Y206283D01*
X1827090Y206783D01*
X1826773Y207200D01*
X1826203Y207450D01*
X1825633Y207367D01*
X1825063Y207033D01*
G01X1830923Y202450D02*
X1831050Y203533D01*
X1831240Y204450D01*
X1831493Y205283D01*
X1831810Y206200D01*
X1832317Y207450D01*
X1829783D01*
G01X1836150Y202283D02*
X1836023Y202367D01*
Y202533D01*
X1836150Y202617D01*
X1836277Y202533D01*
Y202367D01*
X1836150Y202283D01*
G01X1841250Y207450D02*
X1840743Y207283D01*
X1840363Y206867D01*
X1840110Y206367D01*
X1839920Y205700D01*
X1839857Y204950D01*
X1839920Y204200D01*
X1840110Y203533D01*
X1840363Y203033D01*
X1840743Y202617D01*
X1841250Y202450D01*
X1841757Y202617D01*
X1842137Y203033D01*
X1842390Y203533D01*
X1842580Y204200D01*
X1842643Y204950D01*
X1842580Y205700D01*
X1842390Y206367D01*
X1842137Y206867D01*
X1841757Y207283D01*
X1841250Y207450D01*
G01X1824557Y227150D02*
X1824937Y226567D01*
X1825443Y226233D01*
X1826013Y226150D01*
X1826520Y226233D01*
X1827027Y226650D01*
X1827343Y227150D01*
X1827407Y227650D01*
X1827280Y228233D01*
X1826837Y228650D01*
X1826393Y228817D01*
X1825823D01*
G01X1826393D02*
X1826773Y229067D01*
X1827090Y229483D01*
X1827217Y229983D01*
X1827090Y230483D01*
X1826773Y230900D01*
X1826203Y231150D01*
X1825633Y231067D01*
X1825063Y230733D01*
G01X1829657Y226900D02*
X1830037Y226483D01*
X1830480Y226233D01*
X1831050Y226150D01*
X1831620Y226317D01*
X1832063Y226650D01*
X1832380Y227233D01*
X1832443Y227900D01*
X1832317Y228567D01*
X1832000Y228983D01*
X1831557Y229317D01*
X1831113Y229400D01*
X1830670Y229317D01*
X1830100Y228983D01*
X1830290Y231150D01*
X1832000D01*
G01X1836150Y225983D02*
X1836023Y226067D01*
Y226233D01*
X1836150Y226317D01*
X1836277Y226233D01*
Y226067D01*
X1836150Y225983D01*
G01X1841250Y231150D02*
X1840743Y230983D01*
X1840363Y230567D01*
X1840110Y230067D01*
X1839920Y229400D01*
X1839857Y228650D01*
X1839920Y227900D01*
X1840110Y227233D01*
X1840363Y226733D01*
X1840743Y226317D01*
X1841250Y226150D01*
X1841757Y226317D01*
X1842137Y226733D01*
X1842390Y227233D01*
X1842580Y227900D01*
X1842643Y228650D01*
X1842580Y229400D01*
X1842390Y230067D01*
X1842137Y230567D01*
X1841757Y230983D01*
X1841250Y231150D01*
G01X1824557Y250850D02*
X1824937Y250267D01*
X1825443Y249933D01*
X1826013Y249850D01*
X1826520Y249933D01*
X1827027Y250350D01*
X1827343Y250850D01*
X1827407Y251350D01*
X1827280Y251933D01*
X1826837Y252350D01*
X1826393Y252517D01*
X1825823D01*
G01X1826393D02*
X1826773Y252767D01*
X1827090Y253183D01*
X1827217Y253683D01*
X1827090Y254183D01*
X1826773Y254600D01*
X1826203Y254850D01*
X1825633Y254767D01*
X1825063Y254433D01*
G01X1829657Y250850D02*
X1830037Y250267D01*
X1830543Y249933D01*
X1831113Y249850D01*
X1831620Y249933D01*
X1832127Y250350D01*
X1832443Y250850D01*
X1832507Y251350D01*
X1832380Y251933D01*
X1831937Y252350D01*
X1831493Y252517D01*
X1830923D01*
G01X1831493D02*
X1831873Y252767D01*
X1832190Y253183D01*
X1832317Y253683D01*
X1832190Y254183D01*
X1831873Y254600D01*
X1831303Y254850D01*
X1830733Y254767D01*
X1830163Y254433D01*
G01X1836150Y249683D02*
X1836023Y249767D01*
Y249933D01*
X1836150Y250017D01*
X1836277Y249933D01*
Y249767D01*
X1836150Y249683D01*
G01X1841250Y254850D02*
X1840743Y254683D01*
X1840363Y254267D01*
X1840110Y253767D01*
X1839920Y253100D01*
X1839857Y252350D01*
X1839920Y251600D01*
X1840110Y250933D01*
X1840363Y250433D01*
X1840743Y250017D01*
X1841250Y249850D01*
X1841757Y250017D01*
X1842137Y250433D01*
X1842390Y250933D01*
X1842580Y251600D01*
X1842643Y252350D01*
X1842580Y253100D01*
X1842390Y253767D01*
X1842137Y254267D01*
X1841757Y254683D01*
X1841250Y254850D01*
G01X1824557Y274550D02*
X1824937Y273967D01*
X1825443Y273633D01*
X1826013Y273550D01*
X1826520Y273633D01*
X1827027Y274050D01*
X1827343Y274550D01*
X1827407Y275050D01*
X1827280Y275633D01*
X1826837Y276050D01*
X1826393Y276217D01*
X1825823D01*
G01X1826393D02*
X1826773Y276467D01*
X1827090Y276883D01*
X1827217Y277383D01*
X1827090Y277883D01*
X1826773Y278300D01*
X1826203Y278550D01*
X1825633Y278467D01*
X1825063Y278133D01*
G01X1831050Y278550D02*
X1830543Y278383D01*
X1830163Y277967D01*
X1829910Y277467D01*
X1829720Y276800D01*
X1829657Y276050D01*
X1829720Y275300D01*
X1829910Y274633D01*
X1830163Y274133D01*
X1830543Y273717D01*
X1831050Y273550D01*
X1831557Y273717D01*
X1831937Y274133D01*
X1832190Y274633D01*
X1832380Y275300D01*
X1832443Y276050D01*
X1832380Y276800D01*
X1832190Y277467D01*
X1831937Y277967D01*
X1831557Y278383D01*
X1831050Y278550D01*
G01X1836150Y273383D02*
X1836023Y273467D01*
Y273633D01*
X1836150Y273717D01*
X1836277Y273633D01*
Y273467D01*
X1836150Y273383D01*
G01X1841250Y278550D02*
X1840743Y278383D01*
X1840363Y277967D01*
X1840110Y277467D01*
X1839920Y276800D01*
X1839857Y276050D01*
X1839920Y275300D01*
X1840110Y274633D01*
X1840363Y274133D01*
X1840743Y273717D01*
X1841250Y273550D01*
X1841757Y273717D01*
X1842137Y274133D01*
X1842390Y274633D01*
X1842580Y275300D01*
X1842643Y276050D01*
X1842580Y276800D01*
X1842390Y277467D01*
X1842137Y277967D01*
X1841757Y278383D01*
X1841250Y278550D01*
G01X1824747Y301417D02*
X1825127Y301917D01*
X1825570Y302167D01*
X1826077Y302250D01*
X1826710Y302083D01*
X1827153Y301667D01*
X1827280Y301167D01*
X1827217Y300667D01*
X1826963Y300250D01*
X1825697Y299417D01*
X1825127Y298833D01*
X1824747Y298000D01*
X1824620Y297250D01*
X1827280D01*
G01X1829847Y301417D02*
X1830227Y301917D01*
X1830670Y302167D01*
X1831177Y302250D01*
X1831810Y302083D01*
X1832253Y301667D01*
X1832380Y301167D01*
X1832317Y300667D01*
X1832063Y300250D01*
X1830797Y299417D01*
X1830227Y298833D01*
X1829847Y298000D01*
X1829720Y297250D01*
X1832380D01*
G01X1836150Y297083D02*
X1836023Y297167D01*
Y297333D01*
X1836150Y297417D01*
X1836277Y297333D01*
Y297167D01*
X1836150Y297083D01*
G01X1841250Y302250D02*
X1840743Y302083D01*
X1840363Y301667D01*
X1840110Y301167D01*
X1839920Y300500D01*
X1839857Y299750D01*
X1839920Y299000D01*
X1840110Y298333D01*
X1840363Y297833D01*
X1840743Y297417D01*
X1841250Y297250D01*
X1841757Y297417D01*
X1842137Y297833D01*
X1842390Y298333D01*
X1842580Y299000D01*
X1842643Y299750D01*
X1842580Y300500D01*
X1842390Y301167D01*
X1842137Y301667D01*
X1841757Y302083D01*
X1841250Y302250D01*
G01X1824747Y325117D02*
X1825127Y325617D01*
X1825570Y325867D01*
X1826077Y325950D01*
X1826710Y325783D01*
X1827153Y325367D01*
X1827280Y324867D01*
X1827217Y324367D01*
X1826963Y323950D01*
X1825697Y323117D01*
X1825127Y322533D01*
X1824747Y321700D01*
X1824620Y320950D01*
X1827280D01*
G01X1831050Y325950D02*
X1830543Y325783D01*
X1830163Y325367D01*
X1829910Y324867D01*
X1829720Y324200D01*
X1829657Y323450D01*
X1829720Y322700D01*
X1829910Y322033D01*
X1830163Y321533D01*
X1830543Y321117D01*
X1831050Y320950D01*
X1831557Y321117D01*
X1831937Y321533D01*
X1832190Y322033D01*
X1832380Y322700D01*
X1832443Y323450D01*
X1832380Y324200D01*
X1832190Y324867D01*
X1831937Y325367D01*
X1831557Y325783D01*
X1831050Y325950D01*
G01X1836150Y320783D02*
X1836023Y320867D01*
Y321033D01*
X1836150Y321117D01*
X1836277Y321033D01*
Y320867D01*
X1836150Y320783D01*
G01X1841250Y325950D02*
X1840743Y325783D01*
X1840363Y325367D01*
X1840110Y324867D01*
X1839920Y324200D01*
X1839857Y323450D01*
X1839920Y322700D01*
X1840110Y322033D01*
X1840363Y321533D01*
X1840743Y321117D01*
X1841250Y320950D01*
X1841757Y321117D01*
X1842137Y321533D01*
X1842390Y322033D01*
X1842580Y322700D01*
X1842643Y323450D01*
X1842580Y324200D01*
X1842390Y324867D01*
X1842137Y325367D01*
X1841757Y325783D01*
X1841250Y325950D01*
G01X1824747Y348817D02*
X1825127Y349317D01*
X1825570Y349567D01*
X1826077Y349650D01*
X1826710Y349483D01*
X1827153Y349067D01*
X1827280Y348567D01*
X1827217Y348067D01*
X1826963Y347650D01*
X1825697Y346817D01*
X1825127Y346233D01*
X1824747Y345400D01*
X1824620Y344650D01*
X1827280D01*
G01X1831050Y349650D02*
X1830543Y349483D01*
X1830163Y349067D01*
X1829910Y348567D01*
X1829720Y347900D01*
X1829657Y347150D01*
X1829720Y346400D01*
X1829910Y345733D01*
X1830163Y345233D01*
X1830543Y344817D01*
X1831050Y344650D01*
X1831557Y344817D01*
X1831937Y345233D01*
X1832190Y345733D01*
X1832380Y346400D01*
X1832443Y347150D01*
X1832380Y347900D01*
X1832190Y348567D01*
X1831937Y349067D01*
X1831557Y349483D01*
X1831050Y349650D01*
G01X1836150Y344483D02*
X1836023Y344567D01*
Y344733D01*
X1836150Y344817D01*
X1836277Y344733D01*
Y344567D01*
X1836150Y344483D01*
G01X1841250Y349650D02*
X1840743Y349483D01*
X1840363Y349067D01*
X1840110Y348567D01*
X1839920Y347900D01*
X1839857Y347150D01*
X1839920Y346400D01*
X1840110Y345733D01*
X1840363Y345233D01*
X1840743Y344817D01*
X1841250Y344650D01*
X1841757Y344817D01*
X1842137Y345233D01*
X1842390Y345733D01*
X1842580Y346400D01*
X1842643Y347150D01*
X1842580Y347900D01*
X1842390Y348567D01*
X1842137Y349067D01*
X1841757Y349483D01*
X1841250Y349650D01*
G01X1825950Y368350D02*
Y373350D01*
X1825190Y372350D01*
G01Y368350D02*
X1826710D01*
G01X1831050Y373350D02*
X1830543Y373183D01*
X1830163Y372767D01*
X1829910Y372267D01*
X1829720Y371600D01*
X1829657Y370850D01*
X1829720Y370100D01*
X1829910Y369433D01*
X1830163Y368933D01*
X1830543Y368517D01*
X1831050Y368350D01*
X1831557Y368517D01*
X1831937Y368933D01*
X1832190Y369433D01*
X1832380Y370100D01*
X1832443Y370850D01*
X1832380Y371600D01*
X1832190Y372267D01*
X1831937Y372767D01*
X1831557Y373183D01*
X1831050Y373350D01*
G01X1836150Y368183D02*
X1836023Y368267D01*
Y368433D01*
X1836150Y368517D01*
X1836277Y368433D01*
Y368267D01*
X1836150Y368183D01*
G01X1841250Y373350D02*
X1840743Y373183D01*
X1840363Y372767D01*
X1840110Y372267D01*
X1839920Y371600D01*
X1839857Y370850D01*
X1839920Y370100D01*
X1840110Y369433D01*
X1840363Y368933D01*
X1840743Y368517D01*
X1841250Y368350D01*
X1841757Y368517D01*
X1842137Y368933D01*
X1842390Y369433D01*
X1842580Y370100D01*
X1842643Y370850D01*
X1842580Y371600D01*
X1842390Y372267D01*
X1842137Y372767D01*
X1841757Y373183D01*
X1841250Y373350D01*
G01X1825950Y392050D02*
Y397050D01*
X1825190Y396050D01*
G01Y392050D02*
X1826710D01*
G01X1831050Y397050D02*
X1830543Y396883D01*
X1830163Y396467D01*
X1829910Y395967D01*
X1829720Y395300D01*
X1829657Y394550D01*
X1829720Y393800D01*
X1829910Y393133D01*
X1830163Y392633D01*
X1830543Y392217D01*
X1831050Y392050D01*
X1831557Y392217D01*
X1831937Y392633D01*
X1832190Y393133D01*
X1832380Y393800D01*
X1832443Y394550D01*
X1832380Y395300D01*
X1832190Y395967D01*
X1831937Y396467D01*
X1831557Y396883D01*
X1831050Y397050D01*
G01X1836150Y391883D02*
X1836023Y391967D01*
Y392133D01*
X1836150Y392217D01*
X1836277Y392133D01*
Y391967D01*
X1836150Y391883D01*
G01X1841250Y397050D02*
X1840743Y396883D01*
X1840363Y396467D01*
X1840110Y395967D01*
X1839920Y395300D01*
X1839857Y394550D01*
X1839920Y393800D01*
X1840110Y393133D01*
X1840363Y392633D01*
X1840743Y392217D01*
X1841250Y392050D01*
X1841757Y392217D01*
X1842137Y392633D01*
X1842390Y393133D01*
X1842580Y393800D01*
X1842643Y394550D01*
X1842580Y395300D01*
X1842390Y395967D01*
X1842137Y396467D01*
X1841757Y396883D01*
X1841250Y397050D01*
G01X1824620Y410867D02*
X1825127Y410450D01*
X1825697Y410200D01*
X1826203D01*
X1826710Y410450D01*
X1827090Y410867D01*
X1827280Y411450D01*
X1827153Y412033D01*
X1826837Y412533D01*
X1826267Y412867D01*
X1825507Y413033D01*
X1825063Y413367D01*
X1824873Y413950D01*
X1825000Y414533D01*
X1825317Y414950D01*
X1825760Y415200D01*
X1826203D01*
X1826647Y415033D01*
X1827027Y414617D01*
G01X1830290Y415200D02*
X1831810D01*
G01X1831050D02*
Y410200D01*
G01X1830290D02*
X1831810D01*
G01X1834947Y415200D02*
X1837353D01*
X1834947Y410200D01*
X1837353D01*
G01X1842517D02*
X1839983D01*
Y415200D01*
X1842517D01*
G01X1841503Y412783D02*
X1839983D01*
G01X1843517Y421500D02*
X1845100Y426500D01*
X1846683Y421500D01*
G01X1846113Y423250D02*
X1844087D01*
G01X1848933Y426500D02*
Y421500D01*
X1851467D01*
G01X1854033Y426500D02*
Y421500D01*
X1856567D01*
G01X1864107Y426500D02*
Y422917D01*
X1864360Y422167D01*
X1864867Y421667D01*
X1865500Y421500D01*
X1866133Y421667D01*
X1866640Y422167D01*
X1866893Y422917D01*
Y426500D01*
G01X1869143Y421500D02*
Y426500D01*
X1872057Y421500D01*
Y426500D01*
G01X1874940D02*
X1876460D01*
G01X1875700D02*
Y421500D01*
G01X1874940D02*
X1876460D01*
G01X1880800Y426500D02*
Y421500D01*
G01X1879343Y426500D02*
X1882257D01*
G01X1884570Y422167D02*
X1885077Y421750D01*
X1885647Y421500D01*
X1886153D01*
X1886660Y421750D01*
X1887040Y422167D01*
X1887230Y422750D01*
X1887103Y423333D01*
X1886787Y423833D01*
X1886217Y424167D01*
X1885457Y424333D01*
X1885013Y424667D01*
X1884823Y425250D01*
X1884950Y425833D01*
X1885267Y426250D01*
X1885710Y426500D01*
X1886153D01*
X1886597Y426333D01*
X1886977Y425917D01*
G01X1894517Y421500D02*
X1896100Y426500D01*
X1897683Y421500D01*
G01X1897113Y423250D02*
X1895087D01*
G01X1899933Y421500D02*
Y426500D01*
X1901517D01*
X1902023Y426250D01*
X1902340Y425917D01*
X1902467Y425250D01*
X1902340Y424583D01*
X1901960Y424167D01*
X1901517Y423917D01*
X1899933D01*
G01X1901517D02*
X1902467Y421500D01*
G01X1907567D02*
X1905033D01*
Y426500D01*
X1907567D01*
G01X1906553Y424083D02*
X1905033D01*
G01X1915740Y426500D02*
X1917260D01*
G01X1916500D02*
Y421500D01*
G01X1915740D02*
X1917260D01*
G01X1920143D02*
Y426500D01*
X1923057Y421500D01*
Y426500D01*
G01X1930153Y421500D02*
Y426500D01*
X1931800Y422333D01*
X1933447Y426500D01*
Y421500D01*
G01X1936140Y426500D02*
X1937660D01*
G01X1936900D02*
Y421500D01*
G01X1936140D02*
X1937660D01*
G01X1940733Y426500D02*
Y421500D01*
X1943267D01*
G01X1945770Y422167D02*
X1946277Y421750D01*
X1946847Y421500D01*
X1947353D01*
X1947860Y421750D01*
X1948240Y422167D01*
X1948430Y422750D01*
X1948303Y423333D01*
X1947987Y423833D01*
X1947417Y424167D01*
X1946657Y424333D01*
X1946213Y424667D01*
X1946023Y425250D01*
X1946150Y425833D01*
X1946467Y426250D01*
X1946910Y426500D01*
X1947353D01*
X1947797Y426333D01*
X1948177Y425917D01*
G01X1830957Y446500D02*
Y451500D01*
X1832223D01*
X1832730Y451250D01*
X1833110Y450917D01*
X1833427Y450417D01*
X1833680Y449833D01*
X1833743Y449000D01*
X1833680Y448167D01*
X1833427Y447583D01*
X1833110Y447083D01*
X1832730Y446750D01*
X1832223Y446500D01*
X1830957D01*
G01X1836183D02*
Y451500D01*
X1837767D01*
X1838273Y451250D01*
X1838590Y450917D01*
X1838717Y450250D01*
X1838590Y449583D01*
X1838210Y449167D01*
X1837767Y448917D01*
X1836183D01*
G01X1837767D02*
X1838717Y446500D01*
G01X1841790Y451500D02*
X1843310D01*
G01X1842550D02*
Y446500D01*
G01X1841790D02*
X1843310D01*
G01X1846383Y451500D02*
Y446500D01*
X1848917D01*
G01X1851483Y451500D02*
Y446500D01*
X1854017D01*
G01X1864343Y451083D02*
X1863963Y451333D01*
X1863520Y451500D01*
X1863013D01*
X1862443Y451250D01*
X1862000Y450833D01*
X1861683Y450333D01*
X1861430Y449500D01*
X1861367Y448750D01*
X1861493Y448000D01*
X1861683Y447500D01*
X1862063Y447000D01*
X1862507Y446667D01*
X1862950Y446500D01*
X1863393D01*
X1863837Y446667D01*
X1864217Y446917D01*
X1864533Y447250D01*
G01X1866720Y446500D02*
Y451500D01*
G01X1869380D02*
Y446500D01*
G01Y449000D02*
X1866720D01*
G01X1871567Y446500D02*
X1873150Y451500D01*
X1874733Y446500D01*
G01X1874163Y448250D02*
X1872137D01*
G01X1876983Y446500D02*
Y451500D01*
X1878567D01*
X1879073Y451250D01*
X1879390Y450917D01*
X1879517Y450250D01*
X1879390Y449583D01*
X1879010Y449167D01*
X1878567Y448917D01*
X1876983D01*
G01X1878567D02*
X1879517Y446500D01*
G01X1883350Y451500D02*
Y446500D01*
G01X1881893Y451500D02*
X1884807D01*
G01X1888450Y446333D02*
X1888323Y446417D01*
Y446583D01*
X1888450Y446667D01*
X1888577Y446583D01*
Y446417D01*
X1888450Y446333D01*
G01Y448583D02*
X1888323Y448667D01*
Y448833D01*
X1888450Y448917D01*
X1888577Y448833D01*
Y448667D01*
X1888450Y448583D01*
G01X1898650Y451500D02*
Y446500D01*
G01X1897193Y451500D02*
X1900107D01*
G01X1903750Y446500D02*
X1903243Y446583D01*
X1902800Y446917D01*
X1902420Y447417D01*
X1902167Y448000D01*
X1902040Y448667D01*
Y449333D01*
X1902167Y450000D01*
X1902420Y450583D01*
X1902800Y451083D01*
X1903243Y451417D01*
X1903750Y451500D01*
X1904257Y451417D01*
X1904700Y451083D01*
X1905080Y450583D01*
X1905333Y450000D01*
X1905460Y449333D01*
Y448667D01*
X1905333Y448000D01*
X1905080Y447417D01*
X1904700Y446917D01*
X1904257Y446583D01*
X1903750Y446500D01*
G01X1907583D02*
Y451500D01*
X1909103D01*
X1909610Y451250D01*
X1909990Y450667D01*
X1910117Y450000D01*
X1909990Y449333D01*
X1909673Y448833D01*
X1909103Y448583D01*
X1907583D01*
G01X1919050Y451500D02*
Y446500D01*
G01X1918163Y449833D02*
X1919937D01*
G01X1924150Y446500D02*
X1923770Y446583D01*
X1923390Y446917D01*
X1923137Y447500D01*
X1923010Y448167D01*
X1923137Y448833D01*
X1923390Y449417D01*
X1923770Y449750D01*
X1924150Y449833D01*
X1924530Y449750D01*
X1924910Y449417D01*
X1925163Y448833D01*
X1925227Y448167D01*
X1925163Y447500D01*
X1924910Y446917D01*
X1924530Y446583D01*
X1924150Y446500D01*
G01X1934857Y449167D02*
X1935110Y449417D01*
X1935300Y449833D01*
X1935427Y450417D01*
X1935300Y450917D01*
X1935047Y451250D01*
X1934603Y451500D01*
X1932893D01*
Y446500D01*
X1934983D01*
X1935427Y446833D01*
X1935680Y447333D01*
X1935807Y447917D01*
X1935680Y448500D01*
X1935300Y449000D01*
X1934857Y449167D01*
X1932893D01*
G01X1939450Y446500D02*
X1938943Y446583D01*
X1938500Y446917D01*
X1938120Y447417D01*
X1937867Y448000D01*
X1937740Y448667D01*
Y449333D01*
X1937867Y450000D01*
X1938120Y450583D01*
X1938500Y451083D01*
X1938943Y451417D01*
X1939450Y451500D01*
X1939957Y451417D01*
X1940400Y451083D01*
X1940780Y450583D01*
X1941033Y450000D01*
X1941160Y449333D01*
Y448667D01*
X1941033Y448000D01*
X1940780Y447417D01*
X1940400Y446917D01*
X1939957Y446583D01*
X1939450Y446500D01*
G01X1944550Y451500D02*
Y446500D01*
G01X1943093Y451500D02*
X1946007D01*
G01X1949650D02*
Y446500D01*
G01X1948193Y451500D02*
X1951107D01*
G01X1954750Y446500D02*
X1954243Y446583D01*
X1953800Y446917D01*
X1953420Y447417D01*
X1953167Y448000D01*
X1953040Y448667D01*
Y449333D01*
X1953167Y450000D01*
X1953420Y450583D01*
X1953800Y451083D01*
X1954243Y451417D01*
X1954750Y451500D01*
X1955257Y451417D01*
X1955700Y451083D01*
X1956080Y450583D01*
X1956333Y450000D01*
X1956460Y449333D01*
Y448667D01*
X1956333Y448000D01*
X1956080Y447417D01*
X1955700Y446917D01*
X1955257Y446583D01*
X1954750Y446500D01*
G01X1958203D02*
Y451500D01*
X1959850Y447333D01*
X1961497Y451500D01*
Y446500D01*
G01X1890303Y-175083D02*
X1891823D01*
G01X1891000Y-174000D02*
Y-176167D01*
G01X1896860Y-176750D02*
Y-171750D01*
X1894517Y-175333D01*
X1897683D01*
G01X1901200Y-176917D02*
X1901073Y-176833D01*
Y-176667D01*
X1901200Y-176583D01*
X1901327Y-176667D01*
Y-176833D01*
X1901200Y-176917D01*
G01X1906300Y-171750D02*
X1905793Y-171917D01*
X1905413Y-172333D01*
X1905160Y-172833D01*
X1904970Y-173500D01*
X1904907Y-174250D01*
X1904970Y-175000D01*
X1905160Y-175667D01*
X1905413Y-176167D01*
X1905793Y-176583D01*
X1906300Y-176750D01*
X1906807Y-176583D01*
X1907187Y-176167D01*
X1907440Y-175667D01*
X1907630Y-175000D01*
X1907693Y-174250D01*
X1907630Y-173500D01*
X1907440Y-172833D01*
X1907187Y-172333D01*
X1906807Y-171917D01*
X1906300Y-171750D01*
G01X1910260Y-176917D02*
X1912540Y-171750D01*
G01X1915677Y-175083D02*
X1917323D01*
G01X1922360Y-176750D02*
Y-171750D01*
X1920017Y-175333D01*
X1923183D01*
G01X1926700Y-176917D02*
X1926573Y-176833D01*
Y-176667D01*
X1926700Y-176583D01*
X1926827Y-176667D01*
Y-176833D01*
X1926700Y-176917D01*
G01X1931800Y-171750D02*
X1931293Y-171917D01*
X1930913Y-172333D01*
X1930660Y-172833D01*
X1930470Y-173500D01*
X1930407Y-174250D01*
X1930470Y-175000D01*
X1930660Y-175667D01*
X1930913Y-176167D01*
X1931293Y-176583D01*
X1931800Y-176750D01*
X1932307Y-176583D01*
X1932687Y-176167D01*
X1932940Y-175667D01*
X1933130Y-175000D01*
X1933193Y-174250D01*
X1933130Y-173500D01*
X1932940Y-172833D01*
X1932687Y-172333D01*
X1932307Y-171917D01*
X1931800Y-171750D01*
G01X1890303Y-151383D02*
X1891823D01*
G01X1891000Y-150300D02*
Y-152467D01*
G01X1894897Y-148883D02*
X1895277Y-148383D01*
X1895720Y-148133D01*
X1896227Y-148050D01*
X1896860Y-148217D01*
X1897303Y-148633D01*
X1897430Y-149133D01*
X1897367Y-149633D01*
X1897113Y-150050D01*
X1895847Y-150883D01*
X1895277Y-151467D01*
X1894897Y-152300D01*
X1894770Y-153050D01*
X1897430D01*
G01X1901200Y-153217D02*
X1901073Y-153133D01*
Y-152967D01*
X1901200Y-152883D01*
X1901327Y-152967D01*
Y-153133D01*
X1901200Y-153217D01*
G01X1906300Y-148050D02*
X1905793Y-148217D01*
X1905413Y-148633D01*
X1905160Y-149133D01*
X1904970Y-149800D01*
X1904907Y-150550D01*
X1904970Y-151300D01*
X1905160Y-151967D01*
X1905413Y-152467D01*
X1905793Y-152883D01*
X1906300Y-153050D01*
X1906807Y-152883D01*
X1907187Y-152467D01*
X1907440Y-151967D01*
X1907630Y-151300D01*
X1907693Y-150550D01*
X1907630Y-149800D01*
X1907440Y-149133D01*
X1907187Y-148633D01*
X1906807Y-148217D01*
X1906300Y-148050D01*
G01X1910260Y-153217D02*
X1912540Y-148050D01*
G01X1915677Y-151383D02*
X1917323D01*
G01X1920397Y-148883D02*
X1920777Y-148383D01*
X1921220Y-148133D01*
X1921727Y-148050D01*
X1922360Y-148217D01*
X1922803Y-148633D01*
X1922930Y-149133D01*
X1922867Y-149633D01*
X1922613Y-150050D01*
X1921347Y-150883D01*
X1920777Y-151467D01*
X1920397Y-152300D01*
X1920270Y-153050D01*
X1922930D01*
G01X1926700Y-153217D02*
X1926573Y-153133D01*
Y-152967D01*
X1926700Y-152883D01*
X1926827Y-152967D01*
Y-153133D01*
X1926700Y-153217D01*
G01X1931800Y-148050D02*
X1931293Y-148217D01*
X1930913Y-148633D01*
X1930660Y-149133D01*
X1930470Y-149800D01*
X1930407Y-150550D01*
X1930470Y-151300D01*
X1930660Y-151967D01*
X1930913Y-152467D01*
X1931293Y-152883D01*
X1931800Y-153050D01*
X1932307Y-152883D01*
X1932687Y-152467D01*
X1932940Y-151967D01*
X1933130Y-151300D01*
X1933193Y-150550D01*
X1933130Y-149800D01*
X1932940Y-149133D01*
X1932687Y-148633D01*
X1932307Y-148217D01*
X1931800Y-148050D01*
G01X1890303Y-127683D02*
X1891823D01*
G01X1891000Y-126600D02*
Y-128767D01*
G01X1894897Y-125183D02*
X1895277Y-124683D01*
X1895720Y-124433D01*
X1896227Y-124350D01*
X1896860Y-124517D01*
X1897303Y-124933D01*
X1897430Y-125433D01*
X1897367Y-125933D01*
X1897113Y-126350D01*
X1895847Y-127183D01*
X1895277Y-127767D01*
X1894897Y-128600D01*
X1894770Y-129350D01*
X1897430D01*
G01X1901200Y-129517D02*
X1901073Y-129433D01*
Y-129267D01*
X1901200Y-129183D01*
X1901327Y-129267D01*
Y-129433D01*
X1901200Y-129517D01*
G01X1906300Y-124350D02*
X1905793Y-124517D01*
X1905413Y-124933D01*
X1905160Y-125433D01*
X1904970Y-126100D01*
X1904907Y-126850D01*
X1904970Y-127600D01*
X1905160Y-128267D01*
X1905413Y-128767D01*
X1905793Y-129183D01*
X1906300Y-129350D01*
X1906807Y-129183D01*
X1907187Y-128767D01*
X1907440Y-128267D01*
X1907630Y-127600D01*
X1907693Y-126850D01*
X1907630Y-126100D01*
X1907440Y-125433D01*
X1907187Y-124933D01*
X1906807Y-124517D01*
X1906300Y-124350D01*
G01X1910260Y-129517D02*
X1912540Y-124350D01*
G01X1915677Y-127683D02*
X1917323D01*
G01X1920397Y-125183D02*
X1920777Y-124683D01*
X1921220Y-124433D01*
X1921727Y-124350D01*
X1922360Y-124517D01*
X1922803Y-124933D01*
X1922930Y-125433D01*
X1922867Y-125933D01*
X1922613Y-126350D01*
X1921347Y-127183D01*
X1920777Y-127767D01*
X1920397Y-128600D01*
X1920270Y-129350D01*
X1922930D01*
G01X1926700Y-129517D02*
X1926573Y-129433D01*
Y-129267D01*
X1926700Y-129183D01*
X1926827Y-129267D01*
Y-129433D01*
X1926700Y-129517D01*
G01X1931800Y-124350D02*
X1931293Y-124517D01*
X1930913Y-124933D01*
X1930660Y-125433D01*
X1930470Y-126100D01*
X1930407Y-126850D01*
X1930470Y-127600D01*
X1930660Y-128267D01*
X1930913Y-128767D01*
X1931293Y-129183D01*
X1931800Y-129350D01*
X1932307Y-129183D01*
X1932687Y-128767D01*
X1932940Y-128267D01*
X1933130Y-127600D01*
X1933193Y-126850D01*
X1933130Y-126100D01*
X1932940Y-125433D01*
X1932687Y-124933D01*
X1932307Y-124517D01*
X1931800Y-124350D01*
G01X1890303Y-103983D02*
X1891823D01*
G01X1891000Y-102900D02*
Y-105067D01*
G01X1894897Y-101483D02*
X1895277Y-100983D01*
X1895720Y-100733D01*
X1896227Y-100650D01*
X1896860Y-100817D01*
X1897303Y-101233D01*
X1897430Y-101733D01*
X1897367Y-102233D01*
X1897113Y-102650D01*
X1895847Y-103483D01*
X1895277Y-104067D01*
X1894897Y-104900D01*
X1894770Y-105650D01*
X1897430D01*
G01X1901200Y-105817D02*
X1901073Y-105733D01*
Y-105567D01*
X1901200Y-105483D01*
X1901327Y-105567D01*
Y-105733D01*
X1901200Y-105817D01*
G01X1906300Y-100650D02*
X1905793Y-100817D01*
X1905413Y-101233D01*
X1905160Y-101733D01*
X1904970Y-102400D01*
X1904907Y-103150D01*
X1904970Y-103900D01*
X1905160Y-104567D01*
X1905413Y-105067D01*
X1905793Y-105483D01*
X1906300Y-105650D01*
X1906807Y-105483D01*
X1907187Y-105067D01*
X1907440Y-104567D01*
X1907630Y-103900D01*
X1907693Y-103150D01*
X1907630Y-102400D01*
X1907440Y-101733D01*
X1907187Y-101233D01*
X1906807Y-100817D01*
X1906300Y-100650D01*
G01X1910260Y-105817D02*
X1912540Y-100650D01*
G01X1915677Y-103983D02*
X1917323D01*
G01X1920397Y-101483D02*
X1920777Y-100983D01*
X1921220Y-100733D01*
X1921727Y-100650D01*
X1922360Y-100817D01*
X1922803Y-101233D01*
X1922930Y-101733D01*
X1922867Y-102233D01*
X1922613Y-102650D01*
X1921347Y-103483D01*
X1920777Y-104067D01*
X1920397Y-104900D01*
X1920270Y-105650D01*
X1922930D01*
G01X1926700Y-105817D02*
X1926573Y-105733D01*
Y-105567D01*
X1926700Y-105483D01*
X1926827Y-105567D01*
Y-105733D01*
X1926700Y-105817D01*
G01X1931800Y-100650D02*
X1931293Y-100817D01*
X1930913Y-101233D01*
X1930660Y-101733D01*
X1930470Y-102400D01*
X1930407Y-103150D01*
X1930470Y-103900D01*
X1930660Y-104567D01*
X1930913Y-105067D01*
X1931293Y-105483D01*
X1931800Y-105650D01*
X1932307Y-105483D01*
X1932687Y-105067D01*
X1932940Y-104567D01*
X1933130Y-103900D01*
X1933193Y-103150D01*
X1933130Y-102400D01*
X1932940Y-101733D01*
X1932687Y-101233D01*
X1932307Y-100817D01*
X1931800Y-100650D01*
G01X1890303Y-80283D02*
X1891823D01*
G01X1891000Y-79200D02*
Y-81367D01*
G01X1894897Y-77783D02*
X1895277Y-77283D01*
X1895720Y-77033D01*
X1896227Y-76950D01*
X1896860Y-77117D01*
X1897303Y-77533D01*
X1897430Y-78033D01*
X1897367Y-78533D01*
X1897113Y-78950D01*
X1895847Y-79783D01*
X1895277Y-80367D01*
X1894897Y-81200D01*
X1894770Y-81950D01*
X1897430D01*
G01X1901200Y-82117D02*
X1901073Y-82033D01*
Y-81867D01*
X1901200Y-81783D01*
X1901327Y-81867D01*
Y-82033D01*
X1901200Y-82117D01*
G01X1906300Y-76950D02*
X1905793Y-77117D01*
X1905413Y-77533D01*
X1905160Y-78033D01*
X1904970Y-78700D01*
X1904907Y-79450D01*
X1904970Y-80200D01*
X1905160Y-80867D01*
X1905413Y-81367D01*
X1905793Y-81783D01*
X1906300Y-81950D01*
X1906807Y-81783D01*
X1907187Y-81367D01*
X1907440Y-80867D01*
X1907630Y-80200D01*
X1907693Y-79450D01*
X1907630Y-78700D01*
X1907440Y-78033D01*
X1907187Y-77533D01*
X1906807Y-77117D01*
X1906300Y-76950D01*
G01X1910260Y-82117D02*
X1912540Y-76950D01*
G01X1915677Y-80283D02*
X1917323D01*
G01X1920397Y-77783D02*
X1920777Y-77283D01*
X1921220Y-77033D01*
X1921727Y-76950D01*
X1922360Y-77117D01*
X1922803Y-77533D01*
X1922930Y-78033D01*
X1922867Y-78533D01*
X1922613Y-78950D01*
X1921347Y-79783D01*
X1920777Y-80367D01*
X1920397Y-81200D01*
X1920270Y-81950D01*
X1922930D01*
G01X1926700Y-82117D02*
X1926573Y-82033D01*
Y-81867D01*
X1926700Y-81783D01*
X1926827Y-81867D01*
Y-82033D01*
X1926700Y-82117D01*
G01X1931800Y-76950D02*
X1931293Y-77117D01*
X1930913Y-77533D01*
X1930660Y-78033D01*
X1930470Y-78700D01*
X1930407Y-79450D01*
X1930470Y-80200D01*
X1930660Y-80867D01*
X1930913Y-81367D01*
X1931293Y-81783D01*
X1931800Y-81950D01*
X1932307Y-81783D01*
X1932687Y-81367D01*
X1932940Y-80867D01*
X1933130Y-80200D01*
X1933193Y-79450D01*
X1933130Y-78700D01*
X1932940Y-78033D01*
X1932687Y-77533D01*
X1932307Y-77117D01*
X1931800Y-76950D01*
G01X1890303Y-56583D02*
X1891823D01*
G01X1891000Y-55500D02*
Y-57667D01*
G01X1894897Y-54083D02*
X1895277Y-53583D01*
X1895720Y-53333D01*
X1896227Y-53250D01*
X1896860Y-53417D01*
X1897303Y-53833D01*
X1897430Y-54333D01*
X1897367Y-54833D01*
X1897113Y-55250D01*
X1895847Y-56083D01*
X1895277Y-56667D01*
X1894897Y-57500D01*
X1894770Y-58250D01*
X1897430D01*
G01X1901200Y-58417D02*
X1901073Y-58333D01*
Y-58167D01*
X1901200Y-58083D01*
X1901327Y-58167D01*
Y-58333D01*
X1901200Y-58417D01*
G01X1906300Y-53250D02*
X1905793Y-53417D01*
X1905413Y-53833D01*
X1905160Y-54333D01*
X1904970Y-55000D01*
X1904907Y-55750D01*
X1904970Y-56500D01*
X1905160Y-57167D01*
X1905413Y-57667D01*
X1905793Y-58083D01*
X1906300Y-58250D01*
X1906807Y-58083D01*
X1907187Y-57667D01*
X1907440Y-57167D01*
X1907630Y-56500D01*
X1907693Y-55750D01*
X1907630Y-55000D01*
X1907440Y-54333D01*
X1907187Y-53833D01*
X1906807Y-53417D01*
X1906300Y-53250D01*
G01X1910260Y-58417D02*
X1912540Y-53250D01*
G01X1915677Y-56583D02*
X1917323D01*
G01X1920397Y-54083D02*
X1920777Y-53583D01*
X1921220Y-53333D01*
X1921727Y-53250D01*
X1922360Y-53417D01*
X1922803Y-53833D01*
X1922930Y-54333D01*
X1922867Y-54833D01*
X1922613Y-55250D01*
X1921347Y-56083D01*
X1920777Y-56667D01*
X1920397Y-57500D01*
X1920270Y-58250D01*
X1922930D01*
G01X1926700Y-58417D02*
X1926573Y-58333D01*
Y-58167D01*
X1926700Y-58083D01*
X1926827Y-58167D01*
Y-58333D01*
X1926700Y-58417D01*
G01X1931800Y-53250D02*
X1931293Y-53417D01*
X1930913Y-53833D01*
X1930660Y-54333D01*
X1930470Y-55000D01*
X1930407Y-55750D01*
X1930470Y-56500D01*
X1930660Y-57167D01*
X1930913Y-57667D01*
X1931293Y-58083D01*
X1931800Y-58250D01*
X1932307Y-58083D01*
X1932687Y-57667D01*
X1932940Y-57167D01*
X1933130Y-56500D01*
X1933193Y-55750D01*
X1933130Y-55000D01*
X1932940Y-54333D01*
X1932687Y-53833D01*
X1932307Y-53417D01*
X1931800Y-53250D01*
G01X1890303Y-32883D02*
X1891823D01*
G01X1891000Y-31800D02*
Y-33967D01*
G01X1894897Y-30383D02*
X1895277Y-29883D01*
X1895720Y-29633D01*
X1896227Y-29550D01*
X1896860Y-29717D01*
X1897303Y-30133D01*
X1897430Y-30633D01*
X1897367Y-31133D01*
X1897113Y-31550D01*
X1895847Y-32383D01*
X1895277Y-32967D01*
X1894897Y-33800D01*
X1894770Y-34550D01*
X1897430D01*
G01X1901200Y-34717D02*
X1901073Y-34633D01*
Y-34467D01*
X1901200Y-34383D01*
X1901327Y-34467D01*
Y-34633D01*
X1901200Y-34717D01*
G01X1906300Y-29550D02*
X1905793Y-29717D01*
X1905413Y-30133D01*
X1905160Y-30633D01*
X1904970Y-31300D01*
X1904907Y-32050D01*
X1904970Y-32800D01*
X1905160Y-33467D01*
X1905413Y-33967D01*
X1905793Y-34383D01*
X1906300Y-34550D01*
X1906807Y-34383D01*
X1907187Y-33967D01*
X1907440Y-33467D01*
X1907630Y-32800D01*
X1907693Y-32050D01*
X1907630Y-31300D01*
X1907440Y-30633D01*
X1907187Y-30133D01*
X1906807Y-29717D01*
X1906300Y-29550D01*
G01X1910260Y-34717D02*
X1912540Y-29550D01*
G01X1915677Y-32883D02*
X1917323D01*
G01X1920397Y-30383D02*
X1920777Y-29883D01*
X1921220Y-29633D01*
X1921727Y-29550D01*
X1922360Y-29717D01*
X1922803Y-30133D01*
X1922930Y-30633D01*
X1922867Y-31133D01*
X1922613Y-31550D01*
X1921347Y-32383D01*
X1920777Y-32967D01*
X1920397Y-33800D01*
X1920270Y-34550D01*
X1922930D01*
G01X1926700Y-34717D02*
X1926573Y-34633D01*
Y-34467D01*
X1926700Y-34383D01*
X1926827Y-34467D01*
Y-34633D01*
X1926700Y-34717D01*
G01X1931800Y-29550D02*
X1931293Y-29717D01*
X1930913Y-30133D01*
X1930660Y-30633D01*
X1930470Y-31300D01*
X1930407Y-32050D01*
X1930470Y-32800D01*
X1930660Y-33467D01*
X1930913Y-33967D01*
X1931293Y-34383D01*
X1931800Y-34550D01*
X1932307Y-34383D01*
X1932687Y-33967D01*
X1932940Y-33467D01*
X1933130Y-32800D01*
X1933193Y-32050D01*
X1933130Y-31300D01*
X1932940Y-30633D01*
X1932687Y-30133D01*
X1932307Y-29717D01*
X1931800Y-29550D01*
G01X1890303Y-9183D02*
X1891823D01*
G01X1891000Y-8100D02*
Y-10267D01*
G01X1894897Y-6683D02*
X1895277Y-6183D01*
X1895720Y-5933D01*
X1896227Y-5850D01*
X1896860Y-6017D01*
X1897303Y-6433D01*
X1897430Y-6933D01*
X1897367Y-7433D01*
X1897113Y-7850D01*
X1895847Y-8683D01*
X1895277Y-9267D01*
X1894897Y-10100D01*
X1894770Y-10850D01*
X1897430D01*
G01X1901200Y-11017D02*
X1901073Y-10933D01*
Y-10767D01*
X1901200Y-10683D01*
X1901327Y-10767D01*
Y-10933D01*
X1901200Y-11017D01*
G01X1906300Y-5850D02*
X1905793Y-6017D01*
X1905413Y-6433D01*
X1905160Y-6933D01*
X1904970Y-7600D01*
X1904907Y-8350D01*
X1904970Y-9100D01*
X1905160Y-9767D01*
X1905413Y-10267D01*
X1905793Y-10683D01*
X1906300Y-10850D01*
X1906807Y-10683D01*
X1907187Y-10267D01*
X1907440Y-9767D01*
X1907630Y-9100D01*
X1907693Y-8350D01*
X1907630Y-7600D01*
X1907440Y-6933D01*
X1907187Y-6433D01*
X1906807Y-6017D01*
X1906300Y-5850D01*
G01X1910260Y-11017D02*
X1912540Y-5850D01*
G01X1915677Y-9183D02*
X1917323D01*
G01X1920397Y-6683D02*
X1920777Y-6183D01*
X1921220Y-5933D01*
X1921727Y-5850D01*
X1922360Y-6017D01*
X1922803Y-6433D01*
X1922930Y-6933D01*
X1922867Y-7433D01*
X1922613Y-7850D01*
X1921347Y-8683D01*
X1920777Y-9267D01*
X1920397Y-10100D01*
X1920270Y-10850D01*
X1922930D01*
G01X1926700Y-11017D02*
X1926573Y-10933D01*
Y-10767D01*
X1926700Y-10683D01*
X1926827Y-10767D01*
Y-10933D01*
X1926700Y-11017D01*
G01X1931800Y-5850D02*
X1931293Y-6017D01*
X1930913Y-6433D01*
X1930660Y-6933D01*
X1930470Y-7600D01*
X1930407Y-8350D01*
X1930470Y-9100D01*
X1930660Y-9767D01*
X1930913Y-10267D01*
X1931293Y-10683D01*
X1931800Y-10850D01*
X1932307Y-10683D01*
X1932687Y-10267D01*
X1932940Y-9767D01*
X1933130Y-9100D01*
X1933193Y-8350D01*
X1933130Y-7600D01*
X1932940Y-6933D01*
X1932687Y-6433D01*
X1932307Y-6017D01*
X1931800Y-5850D01*
G01X1890303Y14517D02*
X1891823D01*
G01X1891000Y15600D02*
Y13433D01*
G01X1894707Y13850D02*
X1895087Y13267D01*
X1895593Y12933D01*
X1896163Y12850D01*
X1896670Y12933D01*
X1897177Y13350D01*
X1897493Y13850D01*
X1897557Y14350D01*
X1897430Y14933D01*
X1896987Y15350D01*
X1896543Y15517D01*
X1895973D01*
G01X1896543D02*
X1896923Y15767D01*
X1897240Y16183D01*
X1897367Y16683D01*
X1897240Y17183D01*
X1896923Y17600D01*
X1896353Y17850D01*
X1895783Y17767D01*
X1895213Y17433D01*
G01X1901200Y12683D02*
X1901073Y12767D01*
Y12933D01*
X1901200Y13017D01*
X1901327Y12933D01*
Y12767D01*
X1901200Y12683D01*
G01X1906300Y17850D02*
X1905793Y17683D01*
X1905413Y17267D01*
X1905160Y16767D01*
X1904970Y16100D01*
X1904907Y15350D01*
X1904970Y14600D01*
X1905160Y13933D01*
X1905413Y13433D01*
X1905793Y13017D01*
X1906300Y12850D01*
X1906807Y13017D01*
X1907187Y13433D01*
X1907440Y13933D01*
X1907630Y14600D01*
X1907693Y15350D01*
X1907630Y16100D01*
X1907440Y16767D01*
X1907187Y17267D01*
X1906807Y17683D01*
X1906300Y17850D01*
G01X1910260Y12683D02*
X1912540Y17850D01*
G01X1915677Y14517D02*
X1917323D01*
G01X1920207Y13850D02*
X1920587Y13267D01*
X1921093Y12933D01*
X1921663Y12850D01*
X1922170Y12933D01*
X1922677Y13350D01*
X1922993Y13850D01*
X1923057Y14350D01*
X1922930Y14933D01*
X1922487Y15350D01*
X1922043Y15517D01*
X1921473D01*
G01X1922043D02*
X1922423Y15767D01*
X1922740Y16183D01*
X1922867Y16683D01*
X1922740Y17183D01*
X1922423Y17600D01*
X1921853Y17850D01*
X1921283Y17767D01*
X1920713Y17433D01*
G01X1926700Y12683D02*
X1926573Y12767D01*
Y12933D01*
X1926700Y13017D01*
X1926827Y12933D01*
Y12767D01*
X1926700Y12683D01*
G01X1931800Y17850D02*
X1931293Y17683D01*
X1930913Y17267D01*
X1930660Y16767D01*
X1930470Y16100D01*
X1930407Y15350D01*
X1930470Y14600D01*
X1930660Y13933D01*
X1930913Y13433D01*
X1931293Y13017D01*
X1931800Y12850D01*
X1932307Y13017D01*
X1932687Y13433D01*
X1932940Y13933D01*
X1933130Y14600D01*
X1933193Y15350D01*
X1933130Y16100D01*
X1932940Y16767D01*
X1932687Y17267D01*
X1932307Y17683D01*
X1931800Y17850D01*
G01X1890303Y38217D02*
X1891823D01*
G01X1891000Y39300D02*
Y37133D01*
G01X1894707Y37550D02*
X1895087Y36967D01*
X1895593Y36633D01*
X1896163Y36550D01*
X1896670Y36633D01*
X1897177Y37050D01*
X1897493Y37550D01*
X1897557Y38050D01*
X1897430Y38633D01*
X1896987Y39050D01*
X1896543Y39217D01*
X1895973D01*
G01X1896543D02*
X1896923Y39467D01*
X1897240Y39883D01*
X1897367Y40383D01*
X1897240Y40883D01*
X1896923Y41300D01*
X1896353Y41550D01*
X1895783Y41467D01*
X1895213Y41133D01*
G01X1901200Y36383D02*
X1901073Y36467D01*
Y36633D01*
X1901200Y36717D01*
X1901327Y36633D01*
Y36467D01*
X1901200Y36383D01*
G01X1906300Y41550D02*
X1905793Y41383D01*
X1905413Y40967D01*
X1905160Y40467D01*
X1904970Y39800D01*
X1904907Y39050D01*
X1904970Y38300D01*
X1905160Y37633D01*
X1905413Y37133D01*
X1905793Y36717D01*
X1906300Y36550D01*
X1906807Y36717D01*
X1907187Y37133D01*
X1907440Y37633D01*
X1907630Y38300D01*
X1907693Y39050D01*
X1907630Y39800D01*
X1907440Y40467D01*
X1907187Y40967D01*
X1906807Y41383D01*
X1906300Y41550D01*
G01X1910260Y36383D02*
X1912540Y41550D01*
G01X1915677Y38217D02*
X1917323D01*
G01X1920207Y37550D02*
X1920587Y36967D01*
X1921093Y36633D01*
X1921663Y36550D01*
X1922170Y36633D01*
X1922677Y37050D01*
X1922993Y37550D01*
X1923057Y38050D01*
X1922930Y38633D01*
X1922487Y39050D01*
X1922043Y39217D01*
X1921473D01*
G01X1922043D02*
X1922423Y39467D01*
X1922740Y39883D01*
X1922867Y40383D01*
X1922740Y40883D01*
X1922423Y41300D01*
X1921853Y41550D01*
X1921283Y41467D01*
X1920713Y41133D01*
G01X1926700Y36383D02*
X1926573Y36467D01*
Y36633D01*
X1926700Y36717D01*
X1926827Y36633D01*
Y36467D01*
X1926700Y36383D01*
G01X1931800Y41550D02*
X1931293Y41383D01*
X1930913Y40967D01*
X1930660Y40467D01*
X1930470Y39800D01*
X1930407Y39050D01*
X1930470Y38300D01*
X1930660Y37633D01*
X1930913Y37133D01*
X1931293Y36717D01*
X1931800Y36550D01*
X1932307Y36717D01*
X1932687Y37133D01*
X1932940Y37633D01*
X1933130Y38300D01*
X1933193Y39050D01*
X1933130Y39800D01*
X1932940Y40467D01*
X1932687Y40967D01*
X1932307Y41383D01*
X1931800Y41550D01*
G01X1890303Y61917D02*
X1891823D01*
G01X1891000Y63000D02*
Y60833D01*
G01X1894707Y61250D02*
X1895087Y60667D01*
X1895593Y60333D01*
X1896163Y60250D01*
X1896670Y60333D01*
X1897177Y60750D01*
X1897493Y61250D01*
X1897557Y61750D01*
X1897430Y62333D01*
X1896987Y62750D01*
X1896543Y62917D01*
X1895973D01*
G01X1896543D02*
X1896923Y63167D01*
X1897240Y63583D01*
X1897367Y64083D01*
X1897240Y64583D01*
X1896923Y65000D01*
X1896353Y65250D01*
X1895783Y65167D01*
X1895213Y64833D01*
G01X1901200Y60083D02*
X1901073Y60167D01*
Y60333D01*
X1901200Y60417D01*
X1901327Y60333D01*
Y60167D01*
X1901200Y60083D01*
G01X1906300Y65250D02*
X1905793Y65083D01*
X1905413Y64667D01*
X1905160Y64167D01*
X1904970Y63500D01*
X1904907Y62750D01*
X1904970Y62000D01*
X1905160Y61333D01*
X1905413Y60833D01*
X1905793Y60417D01*
X1906300Y60250D01*
X1906807Y60417D01*
X1907187Y60833D01*
X1907440Y61333D01*
X1907630Y62000D01*
X1907693Y62750D01*
X1907630Y63500D01*
X1907440Y64167D01*
X1907187Y64667D01*
X1906807Y65083D01*
X1906300Y65250D01*
G01X1910260Y60083D02*
X1912540Y65250D01*
G01X1915677Y61917D02*
X1917323D01*
G01X1920207Y61250D02*
X1920587Y60667D01*
X1921093Y60333D01*
X1921663Y60250D01*
X1922170Y60333D01*
X1922677Y60750D01*
X1922993Y61250D01*
X1923057Y61750D01*
X1922930Y62333D01*
X1922487Y62750D01*
X1922043Y62917D01*
X1921473D01*
G01X1922043D02*
X1922423Y63167D01*
X1922740Y63583D01*
X1922867Y64083D01*
X1922740Y64583D01*
X1922423Y65000D01*
X1921853Y65250D01*
X1921283Y65167D01*
X1920713Y64833D01*
G01X1926700Y60083D02*
X1926573Y60167D01*
Y60333D01*
X1926700Y60417D01*
X1926827Y60333D01*
Y60167D01*
X1926700Y60083D01*
G01X1931800Y65250D02*
X1931293Y65083D01*
X1930913Y64667D01*
X1930660Y64167D01*
X1930470Y63500D01*
X1930407Y62750D01*
X1930470Y62000D01*
X1930660Y61333D01*
X1930913Y60833D01*
X1931293Y60417D01*
X1931800Y60250D01*
X1932307Y60417D01*
X1932687Y60833D01*
X1932940Y61333D01*
X1933130Y62000D01*
X1933193Y62750D01*
X1933130Y63500D01*
X1932940Y64167D01*
X1932687Y64667D01*
X1932307Y65083D01*
X1931800Y65250D01*
G01X1890303Y85617D02*
X1891823D01*
G01X1891000Y86700D02*
Y84533D01*
G01X1894707Y84950D02*
X1895087Y84367D01*
X1895593Y84033D01*
X1896163Y83950D01*
X1896670Y84033D01*
X1897177Y84450D01*
X1897493Y84950D01*
X1897557Y85450D01*
X1897430Y86033D01*
X1896987Y86450D01*
X1896543Y86617D01*
X1895973D01*
G01X1896543D02*
X1896923Y86867D01*
X1897240Y87283D01*
X1897367Y87783D01*
X1897240Y88283D01*
X1896923Y88700D01*
X1896353Y88950D01*
X1895783Y88867D01*
X1895213Y88533D01*
G01X1901200Y83783D02*
X1901073Y83867D01*
Y84033D01*
X1901200Y84117D01*
X1901327Y84033D01*
Y83867D01*
X1901200Y83783D01*
G01X1906300Y88950D02*
X1905793Y88783D01*
X1905413Y88367D01*
X1905160Y87867D01*
X1904970Y87200D01*
X1904907Y86450D01*
X1904970Y85700D01*
X1905160Y85033D01*
X1905413Y84533D01*
X1905793Y84117D01*
X1906300Y83950D01*
X1906807Y84117D01*
X1907187Y84533D01*
X1907440Y85033D01*
X1907630Y85700D01*
X1907693Y86450D01*
X1907630Y87200D01*
X1907440Y87867D01*
X1907187Y88367D01*
X1906807Y88783D01*
X1906300Y88950D01*
G01X1910260Y83783D02*
X1912540Y88950D01*
G01X1915677Y85617D02*
X1917323D01*
G01X1920207Y84950D02*
X1920587Y84367D01*
X1921093Y84033D01*
X1921663Y83950D01*
X1922170Y84033D01*
X1922677Y84450D01*
X1922993Y84950D01*
X1923057Y85450D01*
X1922930Y86033D01*
X1922487Y86450D01*
X1922043Y86617D01*
X1921473D01*
G01X1922043D02*
X1922423Y86867D01*
X1922740Y87283D01*
X1922867Y87783D01*
X1922740Y88283D01*
X1922423Y88700D01*
X1921853Y88950D01*
X1921283Y88867D01*
X1920713Y88533D01*
G01X1926700Y83783D02*
X1926573Y83867D01*
Y84033D01*
X1926700Y84117D01*
X1926827Y84033D01*
Y83867D01*
X1926700Y83783D01*
G01X1931800Y88950D02*
X1931293Y88783D01*
X1930913Y88367D01*
X1930660Y87867D01*
X1930470Y87200D01*
X1930407Y86450D01*
X1930470Y85700D01*
X1930660Y85033D01*
X1930913Y84533D01*
X1931293Y84117D01*
X1931800Y83950D01*
X1932307Y84117D01*
X1932687Y84533D01*
X1932940Y85033D01*
X1933130Y85700D01*
X1933193Y86450D01*
X1933130Y87200D01*
X1932940Y87867D01*
X1932687Y88367D01*
X1932307Y88783D01*
X1931800Y88950D01*
G01X1890303Y109317D02*
X1891823D01*
G01X1891000Y110400D02*
Y108233D01*
G01X1894707Y108650D02*
X1895087Y108067D01*
X1895593Y107733D01*
X1896163Y107650D01*
X1896670Y107733D01*
X1897177Y108150D01*
X1897493Y108650D01*
X1897557Y109150D01*
X1897430Y109733D01*
X1896987Y110150D01*
X1896543Y110317D01*
X1895973D01*
G01X1896543D02*
X1896923Y110567D01*
X1897240Y110983D01*
X1897367Y111483D01*
X1897240Y111983D01*
X1896923Y112400D01*
X1896353Y112650D01*
X1895783Y112567D01*
X1895213Y112233D01*
G01X1901200Y107483D02*
X1901073Y107567D01*
Y107733D01*
X1901200Y107817D01*
X1901327Y107733D01*
Y107567D01*
X1901200Y107483D01*
G01X1906300Y112650D02*
X1905793Y112483D01*
X1905413Y112067D01*
X1905160Y111567D01*
X1904970Y110900D01*
X1904907Y110150D01*
X1904970Y109400D01*
X1905160Y108733D01*
X1905413Y108233D01*
X1905793Y107817D01*
X1906300Y107650D01*
X1906807Y107817D01*
X1907187Y108233D01*
X1907440Y108733D01*
X1907630Y109400D01*
X1907693Y110150D01*
X1907630Y110900D01*
X1907440Y111567D01*
X1907187Y112067D01*
X1906807Y112483D01*
X1906300Y112650D01*
G01X1910260Y107483D02*
X1912540Y112650D01*
G01X1915677Y109317D02*
X1917323D01*
G01X1920207Y108650D02*
X1920587Y108067D01*
X1921093Y107733D01*
X1921663Y107650D01*
X1922170Y107733D01*
X1922677Y108150D01*
X1922993Y108650D01*
X1923057Y109150D01*
X1922930Y109733D01*
X1922487Y110150D01*
X1922043Y110317D01*
X1921473D01*
G01X1922043D02*
X1922423Y110567D01*
X1922740Y110983D01*
X1922867Y111483D01*
X1922740Y111983D01*
X1922423Y112400D01*
X1921853Y112650D01*
X1921283Y112567D01*
X1920713Y112233D01*
G01X1926700Y107483D02*
X1926573Y107567D01*
Y107733D01*
X1926700Y107817D01*
X1926827Y107733D01*
Y107567D01*
X1926700Y107483D01*
G01X1931800Y112650D02*
X1931293Y112483D01*
X1930913Y112067D01*
X1930660Y111567D01*
X1930470Y110900D01*
X1930407Y110150D01*
X1930470Y109400D01*
X1930660Y108733D01*
X1930913Y108233D01*
X1931293Y107817D01*
X1931800Y107650D01*
X1932307Y107817D01*
X1932687Y108233D01*
X1932940Y108733D01*
X1933130Y109400D01*
X1933193Y110150D01*
X1933130Y110900D01*
X1932940Y111567D01*
X1932687Y112067D01*
X1932307Y112483D01*
X1931800Y112650D01*
G01X1890303Y133017D02*
X1891823D01*
G01X1891000Y134100D02*
Y131933D01*
G01X1894707Y132350D02*
X1895087Y131767D01*
X1895593Y131433D01*
X1896163Y131350D01*
X1896670Y131433D01*
X1897177Y131850D01*
X1897493Y132350D01*
X1897557Y132850D01*
X1897430Y133433D01*
X1896987Y133850D01*
X1896543Y134017D01*
X1895973D01*
G01X1896543D02*
X1896923Y134267D01*
X1897240Y134683D01*
X1897367Y135183D01*
X1897240Y135683D01*
X1896923Y136100D01*
X1896353Y136350D01*
X1895783Y136267D01*
X1895213Y135933D01*
G01X1901200Y131183D02*
X1901073Y131267D01*
Y131433D01*
X1901200Y131517D01*
X1901327Y131433D01*
Y131267D01*
X1901200Y131183D01*
G01X1906300Y136350D02*
X1905793Y136183D01*
X1905413Y135767D01*
X1905160Y135267D01*
X1904970Y134600D01*
X1904907Y133850D01*
X1904970Y133100D01*
X1905160Y132433D01*
X1905413Y131933D01*
X1905793Y131517D01*
X1906300Y131350D01*
X1906807Y131517D01*
X1907187Y131933D01*
X1907440Y132433D01*
X1907630Y133100D01*
X1907693Y133850D01*
X1907630Y134600D01*
X1907440Y135267D01*
X1907187Y135767D01*
X1906807Y136183D01*
X1906300Y136350D01*
G01X1910260Y131183D02*
X1912540Y136350D01*
G01X1915677Y133017D02*
X1917323D01*
G01X1920207Y132350D02*
X1920587Y131767D01*
X1921093Y131433D01*
X1921663Y131350D01*
X1922170Y131433D01*
X1922677Y131850D01*
X1922993Y132350D01*
X1923057Y132850D01*
X1922930Y133433D01*
X1922487Y133850D01*
X1922043Y134017D01*
X1921473D01*
G01X1922043D02*
X1922423Y134267D01*
X1922740Y134683D01*
X1922867Y135183D01*
X1922740Y135683D01*
X1922423Y136100D01*
X1921853Y136350D01*
X1921283Y136267D01*
X1920713Y135933D01*
G01X1926700Y131183D02*
X1926573Y131267D01*
Y131433D01*
X1926700Y131517D01*
X1926827Y131433D01*
Y131267D01*
X1926700Y131183D01*
G01X1931800Y136350D02*
X1931293Y136183D01*
X1930913Y135767D01*
X1930660Y135267D01*
X1930470Y134600D01*
X1930407Y133850D01*
X1930470Y133100D01*
X1930660Y132433D01*
X1930913Y131933D01*
X1931293Y131517D01*
X1931800Y131350D01*
X1932307Y131517D01*
X1932687Y131933D01*
X1932940Y132433D01*
X1933130Y133100D01*
X1933193Y133850D01*
X1933130Y134600D01*
X1932940Y135267D01*
X1932687Y135767D01*
X1932307Y136183D01*
X1931800Y136350D01*
G01X1890303Y156717D02*
X1891823D01*
G01X1891000Y157800D02*
Y155633D01*
G01X1894897Y159217D02*
X1895277Y159717D01*
X1895720Y159967D01*
X1896227Y160050D01*
X1896860Y159883D01*
X1897303Y159467D01*
X1897430Y158967D01*
X1897367Y158467D01*
X1897113Y158050D01*
X1895847Y157217D01*
X1895277Y156633D01*
X1894897Y155800D01*
X1894770Y155050D01*
X1897430D01*
G01X1901200Y154883D02*
X1901073Y154967D01*
Y155133D01*
X1901200Y155217D01*
X1901327Y155133D01*
Y154967D01*
X1901200Y154883D01*
G01X1906300Y160050D02*
X1905793Y159883D01*
X1905413Y159467D01*
X1905160Y158967D01*
X1904970Y158300D01*
X1904907Y157550D01*
X1904970Y156800D01*
X1905160Y156133D01*
X1905413Y155633D01*
X1905793Y155217D01*
X1906300Y155050D01*
X1906807Y155217D01*
X1907187Y155633D01*
X1907440Y156133D01*
X1907630Y156800D01*
X1907693Y157550D01*
X1907630Y158300D01*
X1907440Y158967D01*
X1907187Y159467D01*
X1906807Y159883D01*
X1906300Y160050D01*
G01X1910260Y154883D02*
X1912540Y160050D01*
G01X1915677Y156717D02*
X1917323D01*
G01X1920397Y159217D02*
X1920777Y159717D01*
X1921220Y159967D01*
X1921727Y160050D01*
X1922360Y159883D01*
X1922803Y159467D01*
X1922930Y158967D01*
X1922867Y158467D01*
X1922613Y158050D01*
X1921347Y157217D01*
X1920777Y156633D01*
X1920397Y155800D01*
X1920270Y155050D01*
X1922930D01*
G01X1926700Y154883D02*
X1926573Y154967D01*
Y155133D01*
X1926700Y155217D01*
X1926827Y155133D01*
Y154967D01*
X1926700Y154883D01*
G01X1931800Y160050D02*
X1931293Y159883D01*
X1930913Y159467D01*
X1930660Y158967D01*
X1930470Y158300D01*
X1930407Y157550D01*
X1930470Y156800D01*
X1930660Y156133D01*
X1930913Y155633D01*
X1931293Y155217D01*
X1931800Y155050D01*
X1932307Y155217D01*
X1932687Y155633D01*
X1932940Y156133D01*
X1933130Y156800D01*
X1933193Y157550D01*
X1933130Y158300D01*
X1932940Y158967D01*
X1932687Y159467D01*
X1932307Y159883D01*
X1931800Y160050D01*
G01X1890303Y180417D02*
X1891823D01*
G01X1891000Y181500D02*
Y179333D01*
G01X1894707Y179750D02*
X1895087Y179167D01*
X1895593Y178833D01*
X1896163Y178750D01*
X1896670Y178833D01*
X1897177Y179250D01*
X1897493Y179750D01*
X1897557Y180250D01*
X1897430Y180833D01*
X1896987Y181250D01*
X1896543Y181417D01*
X1895973D01*
G01X1896543D02*
X1896923Y181667D01*
X1897240Y182083D01*
X1897367Y182583D01*
X1897240Y183083D01*
X1896923Y183500D01*
X1896353Y183750D01*
X1895783Y183667D01*
X1895213Y183333D01*
G01X1901200Y178583D02*
X1901073Y178667D01*
Y178833D01*
X1901200Y178917D01*
X1901327Y178833D01*
Y178667D01*
X1901200Y178583D01*
G01X1906300Y183750D02*
X1905793Y183583D01*
X1905413Y183167D01*
X1905160Y182667D01*
X1904970Y182000D01*
X1904907Y181250D01*
X1904970Y180500D01*
X1905160Y179833D01*
X1905413Y179333D01*
X1905793Y178917D01*
X1906300Y178750D01*
X1906807Y178917D01*
X1907187Y179333D01*
X1907440Y179833D01*
X1907630Y180500D01*
X1907693Y181250D01*
X1907630Y182000D01*
X1907440Y182667D01*
X1907187Y183167D01*
X1906807Y183583D01*
X1906300Y183750D01*
G01X1910260Y178583D02*
X1912540Y183750D01*
G01X1915677Y180417D02*
X1917323D01*
G01X1920207Y179750D02*
X1920587Y179167D01*
X1921093Y178833D01*
X1921663Y178750D01*
X1922170Y178833D01*
X1922677Y179250D01*
X1922993Y179750D01*
X1923057Y180250D01*
X1922930Y180833D01*
X1922487Y181250D01*
X1922043Y181417D01*
X1921473D01*
G01X1922043D02*
X1922423Y181667D01*
X1922740Y182083D01*
X1922867Y182583D01*
X1922740Y183083D01*
X1922423Y183500D01*
X1921853Y183750D01*
X1921283Y183667D01*
X1920713Y183333D01*
G01X1926700Y178583D02*
X1926573Y178667D01*
Y178833D01*
X1926700Y178917D01*
X1926827Y178833D01*
Y178667D01*
X1926700Y178583D01*
G01X1931800Y183750D02*
X1931293Y183583D01*
X1930913Y183167D01*
X1930660Y182667D01*
X1930470Y182000D01*
X1930407Y181250D01*
X1930470Y180500D01*
X1930660Y179833D01*
X1930913Y179333D01*
X1931293Y178917D01*
X1931800Y178750D01*
X1932307Y178917D01*
X1932687Y179333D01*
X1932940Y179833D01*
X1933130Y180500D01*
X1933193Y181250D01*
X1933130Y182000D01*
X1932940Y182667D01*
X1932687Y183167D01*
X1932307Y183583D01*
X1931800Y183750D01*
G01X1890303Y204117D02*
X1891823D01*
G01X1891000Y205200D02*
Y203033D01*
G01X1894897Y206617D02*
X1895277Y207117D01*
X1895720Y207367D01*
X1896227Y207450D01*
X1896860Y207283D01*
X1897303Y206867D01*
X1897430Y206367D01*
X1897367Y205867D01*
X1897113Y205450D01*
X1895847Y204617D01*
X1895277Y204033D01*
X1894897Y203200D01*
X1894770Y202450D01*
X1897430D01*
G01X1901200Y202283D02*
X1901073Y202367D01*
Y202533D01*
X1901200Y202617D01*
X1901327Y202533D01*
Y202367D01*
X1901200Y202283D01*
G01X1906300Y207450D02*
X1905793Y207283D01*
X1905413Y206867D01*
X1905160Y206367D01*
X1904970Y205700D01*
X1904907Y204950D01*
X1904970Y204200D01*
X1905160Y203533D01*
X1905413Y203033D01*
X1905793Y202617D01*
X1906300Y202450D01*
X1906807Y202617D01*
X1907187Y203033D01*
X1907440Y203533D01*
X1907630Y204200D01*
X1907693Y204950D01*
X1907630Y205700D01*
X1907440Y206367D01*
X1907187Y206867D01*
X1906807Y207283D01*
X1906300Y207450D01*
G01X1910260Y202283D02*
X1912540Y207450D01*
G01X1915677Y204117D02*
X1917323D01*
G01X1920397Y206617D02*
X1920777Y207117D01*
X1921220Y207367D01*
X1921727Y207450D01*
X1922360Y207283D01*
X1922803Y206867D01*
X1922930Y206367D01*
X1922867Y205867D01*
X1922613Y205450D01*
X1921347Y204617D01*
X1920777Y204033D01*
X1920397Y203200D01*
X1920270Y202450D01*
X1922930D01*
G01X1926700Y202283D02*
X1926573Y202367D01*
Y202533D01*
X1926700Y202617D01*
X1926827Y202533D01*
Y202367D01*
X1926700Y202283D01*
G01X1931800Y207450D02*
X1931293Y207283D01*
X1930913Y206867D01*
X1930660Y206367D01*
X1930470Y205700D01*
X1930407Y204950D01*
X1930470Y204200D01*
X1930660Y203533D01*
X1930913Y203033D01*
X1931293Y202617D01*
X1931800Y202450D01*
X1932307Y202617D01*
X1932687Y203033D01*
X1932940Y203533D01*
X1933130Y204200D01*
X1933193Y204950D01*
X1933130Y205700D01*
X1932940Y206367D01*
X1932687Y206867D01*
X1932307Y207283D01*
X1931800Y207450D01*
G01X1890303Y227817D02*
X1891823D01*
G01X1891000Y228900D02*
Y226733D01*
G01X1894707Y227150D02*
X1895087Y226567D01*
X1895593Y226233D01*
X1896163Y226150D01*
X1896670Y226233D01*
X1897177Y226650D01*
X1897493Y227150D01*
X1897557Y227650D01*
X1897430Y228233D01*
X1896987Y228650D01*
X1896543Y228817D01*
X1895973D01*
G01X1896543D02*
X1896923Y229067D01*
X1897240Y229483D01*
X1897367Y229983D01*
X1897240Y230483D01*
X1896923Y230900D01*
X1896353Y231150D01*
X1895783Y231067D01*
X1895213Y230733D01*
G01X1901200Y225983D02*
X1901073Y226067D01*
Y226233D01*
X1901200Y226317D01*
X1901327Y226233D01*
Y226067D01*
X1901200Y225983D01*
G01X1906300Y231150D02*
X1905793Y230983D01*
X1905413Y230567D01*
X1905160Y230067D01*
X1904970Y229400D01*
X1904907Y228650D01*
X1904970Y227900D01*
X1905160Y227233D01*
X1905413Y226733D01*
X1905793Y226317D01*
X1906300Y226150D01*
X1906807Y226317D01*
X1907187Y226733D01*
X1907440Y227233D01*
X1907630Y227900D01*
X1907693Y228650D01*
X1907630Y229400D01*
X1907440Y230067D01*
X1907187Y230567D01*
X1906807Y230983D01*
X1906300Y231150D01*
G01X1910260Y225983D02*
X1912540Y231150D01*
G01X1915677Y227817D02*
X1917323D01*
G01X1920207Y227150D02*
X1920587Y226567D01*
X1921093Y226233D01*
X1921663Y226150D01*
X1922170Y226233D01*
X1922677Y226650D01*
X1922993Y227150D01*
X1923057Y227650D01*
X1922930Y228233D01*
X1922487Y228650D01*
X1922043Y228817D01*
X1921473D01*
G01X1922043D02*
X1922423Y229067D01*
X1922740Y229483D01*
X1922867Y229983D01*
X1922740Y230483D01*
X1922423Y230900D01*
X1921853Y231150D01*
X1921283Y231067D01*
X1920713Y230733D01*
G01X1926700Y225983D02*
X1926573Y226067D01*
Y226233D01*
X1926700Y226317D01*
X1926827Y226233D01*
Y226067D01*
X1926700Y225983D01*
G01X1931800Y231150D02*
X1931293Y230983D01*
X1930913Y230567D01*
X1930660Y230067D01*
X1930470Y229400D01*
X1930407Y228650D01*
X1930470Y227900D01*
X1930660Y227233D01*
X1930913Y226733D01*
X1931293Y226317D01*
X1931800Y226150D01*
X1932307Y226317D01*
X1932687Y226733D01*
X1932940Y227233D01*
X1933130Y227900D01*
X1933193Y228650D01*
X1933130Y229400D01*
X1932940Y230067D01*
X1932687Y230567D01*
X1932307Y230983D01*
X1931800Y231150D01*
G01X1890303Y251517D02*
X1891823D01*
G01X1891000Y252600D02*
Y250433D01*
G01X1894897Y254017D02*
X1895277Y254517D01*
X1895720Y254767D01*
X1896227Y254850D01*
X1896860Y254683D01*
X1897303Y254267D01*
X1897430Y253767D01*
X1897367Y253267D01*
X1897113Y252850D01*
X1895847Y252017D01*
X1895277Y251433D01*
X1894897Y250600D01*
X1894770Y249850D01*
X1897430D01*
G01X1901200Y249683D02*
X1901073Y249767D01*
Y249933D01*
X1901200Y250017D01*
X1901327Y249933D01*
Y249767D01*
X1901200Y249683D01*
G01X1906300Y254850D02*
X1905793Y254683D01*
X1905413Y254267D01*
X1905160Y253767D01*
X1904970Y253100D01*
X1904907Y252350D01*
X1904970Y251600D01*
X1905160Y250933D01*
X1905413Y250433D01*
X1905793Y250017D01*
X1906300Y249850D01*
X1906807Y250017D01*
X1907187Y250433D01*
X1907440Y250933D01*
X1907630Y251600D01*
X1907693Y252350D01*
X1907630Y253100D01*
X1907440Y253767D01*
X1907187Y254267D01*
X1906807Y254683D01*
X1906300Y254850D01*
G01X1910260Y249683D02*
X1912540Y254850D01*
G01X1915677Y251517D02*
X1917323D01*
G01X1920397Y254017D02*
X1920777Y254517D01*
X1921220Y254767D01*
X1921727Y254850D01*
X1922360Y254683D01*
X1922803Y254267D01*
X1922930Y253767D01*
X1922867Y253267D01*
X1922613Y252850D01*
X1921347Y252017D01*
X1920777Y251433D01*
X1920397Y250600D01*
X1920270Y249850D01*
X1922930D01*
G01X1926700Y249683D02*
X1926573Y249767D01*
Y249933D01*
X1926700Y250017D01*
X1926827Y249933D01*
Y249767D01*
X1926700Y249683D01*
G01X1931800Y254850D02*
X1931293Y254683D01*
X1930913Y254267D01*
X1930660Y253767D01*
X1930470Y253100D01*
X1930407Y252350D01*
X1930470Y251600D01*
X1930660Y250933D01*
X1930913Y250433D01*
X1931293Y250017D01*
X1931800Y249850D01*
X1932307Y250017D01*
X1932687Y250433D01*
X1932940Y250933D01*
X1933130Y251600D01*
X1933193Y252350D01*
X1933130Y253100D01*
X1932940Y253767D01*
X1932687Y254267D01*
X1932307Y254683D01*
X1931800Y254850D01*
G01X1890303Y275217D02*
X1891823D01*
G01X1891000Y276300D02*
Y274133D01*
G01X1894897Y277717D02*
X1895277Y278217D01*
X1895720Y278467D01*
X1896227Y278550D01*
X1896860Y278383D01*
X1897303Y277967D01*
X1897430Y277467D01*
X1897367Y276967D01*
X1897113Y276550D01*
X1895847Y275717D01*
X1895277Y275133D01*
X1894897Y274300D01*
X1894770Y273550D01*
X1897430D01*
G01X1901200Y273383D02*
X1901073Y273467D01*
Y273633D01*
X1901200Y273717D01*
X1901327Y273633D01*
Y273467D01*
X1901200Y273383D01*
G01X1906300Y278550D02*
X1905793Y278383D01*
X1905413Y277967D01*
X1905160Y277467D01*
X1904970Y276800D01*
X1904907Y276050D01*
X1904970Y275300D01*
X1905160Y274633D01*
X1905413Y274133D01*
X1905793Y273717D01*
X1906300Y273550D01*
X1906807Y273717D01*
X1907187Y274133D01*
X1907440Y274633D01*
X1907630Y275300D01*
X1907693Y276050D01*
X1907630Y276800D01*
X1907440Y277467D01*
X1907187Y277967D01*
X1906807Y278383D01*
X1906300Y278550D01*
G01X1910260Y273383D02*
X1912540Y278550D01*
G01X1915677Y275217D02*
X1917323D01*
G01X1920397Y277717D02*
X1920777Y278217D01*
X1921220Y278467D01*
X1921727Y278550D01*
X1922360Y278383D01*
X1922803Y277967D01*
X1922930Y277467D01*
X1922867Y276967D01*
X1922613Y276550D01*
X1921347Y275717D01*
X1920777Y275133D01*
X1920397Y274300D01*
X1920270Y273550D01*
X1922930D01*
G01X1926700Y273383D02*
X1926573Y273467D01*
Y273633D01*
X1926700Y273717D01*
X1926827Y273633D01*
Y273467D01*
X1926700Y273383D01*
G01X1931800Y278550D02*
X1931293Y278383D01*
X1930913Y277967D01*
X1930660Y277467D01*
X1930470Y276800D01*
X1930407Y276050D01*
X1930470Y275300D01*
X1930660Y274633D01*
X1930913Y274133D01*
X1931293Y273717D01*
X1931800Y273550D01*
X1932307Y273717D01*
X1932687Y274133D01*
X1932940Y274633D01*
X1933130Y275300D01*
X1933193Y276050D01*
X1933130Y276800D01*
X1932940Y277467D01*
X1932687Y277967D01*
X1932307Y278383D01*
X1931800Y278550D01*
G01X1890303Y298917D02*
X1891823D01*
G01X1891000Y300000D02*
Y297833D01*
G01X1894707Y298250D02*
X1895087Y297667D01*
X1895593Y297333D01*
X1896163Y297250D01*
X1896670Y297333D01*
X1897177Y297750D01*
X1897493Y298250D01*
X1897557Y298750D01*
X1897430Y299333D01*
X1896987Y299750D01*
X1896543Y299917D01*
X1895973D01*
G01X1896543D02*
X1896923Y300167D01*
X1897240Y300583D01*
X1897367Y301083D01*
X1897240Y301583D01*
X1896923Y302000D01*
X1896353Y302250D01*
X1895783Y302167D01*
X1895213Y301833D01*
G01X1901200Y297083D02*
X1901073Y297167D01*
Y297333D01*
X1901200Y297417D01*
X1901327Y297333D01*
Y297167D01*
X1901200Y297083D01*
G01X1906300Y302250D02*
X1905793Y302083D01*
X1905413Y301667D01*
X1905160Y301167D01*
X1904970Y300500D01*
X1904907Y299750D01*
X1904970Y299000D01*
X1905160Y298333D01*
X1905413Y297833D01*
X1905793Y297417D01*
X1906300Y297250D01*
X1906807Y297417D01*
X1907187Y297833D01*
X1907440Y298333D01*
X1907630Y299000D01*
X1907693Y299750D01*
X1907630Y300500D01*
X1907440Y301167D01*
X1907187Y301667D01*
X1906807Y302083D01*
X1906300Y302250D01*
G01X1910260Y297083D02*
X1912540Y302250D01*
G01X1915677Y298917D02*
X1917323D01*
G01X1920207Y298250D02*
X1920587Y297667D01*
X1921093Y297333D01*
X1921663Y297250D01*
X1922170Y297333D01*
X1922677Y297750D01*
X1922993Y298250D01*
X1923057Y298750D01*
X1922930Y299333D01*
X1922487Y299750D01*
X1922043Y299917D01*
X1921473D01*
G01X1922043D02*
X1922423Y300167D01*
X1922740Y300583D01*
X1922867Y301083D01*
X1922740Y301583D01*
X1922423Y302000D01*
X1921853Y302250D01*
X1921283Y302167D01*
X1920713Y301833D01*
G01X1926700Y297083D02*
X1926573Y297167D01*
Y297333D01*
X1926700Y297417D01*
X1926827Y297333D01*
Y297167D01*
X1926700Y297083D01*
G01X1931800Y302250D02*
X1931293Y302083D01*
X1930913Y301667D01*
X1930660Y301167D01*
X1930470Y300500D01*
X1930407Y299750D01*
X1930470Y299000D01*
X1930660Y298333D01*
X1930913Y297833D01*
X1931293Y297417D01*
X1931800Y297250D01*
X1932307Y297417D01*
X1932687Y297833D01*
X1932940Y298333D01*
X1933130Y299000D01*
X1933193Y299750D01*
X1933130Y300500D01*
X1932940Y301167D01*
X1932687Y301667D01*
X1932307Y302083D01*
X1931800Y302250D01*
G01X1890303Y322617D02*
X1891823D01*
G01X1891000Y323700D02*
Y321533D01*
G01X1894707Y321950D02*
X1895087Y321367D01*
X1895593Y321033D01*
X1896163Y320950D01*
X1896670Y321033D01*
X1897177Y321450D01*
X1897493Y321950D01*
X1897557Y322450D01*
X1897430Y323033D01*
X1896987Y323450D01*
X1896543Y323617D01*
X1895973D01*
G01X1896543D02*
X1896923Y323867D01*
X1897240Y324283D01*
X1897367Y324783D01*
X1897240Y325283D01*
X1896923Y325700D01*
X1896353Y325950D01*
X1895783Y325867D01*
X1895213Y325533D01*
G01X1901200Y320783D02*
X1901073Y320867D01*
Y321033D01*
X1901200Y321117D01*
X1901327Y321033D01*
Y320867D01*
X1901200Y320783D01*
G01X1906300Y325950D02*
X1905793Y325783D01*
X1905413Y325367D01*
X1905160Y324867D01*
X1904970Y324200D01*
X1904907Y323450D01*
X1904970Y322700D01*
X1905160Y322033D01*
X1905413Y321533D01*
X1905793Y321117D01*
X1906300Y320950D01*
X1906807Y321117D01*
X1907187Y321533D01*
X1907440Y322033D01*
X1907630Y322700D01*
X1907693Y323450D01*
X1907630Y324200D01*
X1907440Y324867D01*
X1907187Y325367D01*
X1906807Y325783D01*
X1906300Y325950D01*
G01X1910260Y320783D02*
X1912540Y325950D01*
G01X1915677Y322617D02*
X1917323D01*
G01X1920207Y321950D02*
X1920587Y321367D01*
X1921093Y321033D01*
X1921663Y320950D01*
X1922170Y321033D01*
X1922677Y321450D01*
X1922993Y321950D01*
X1923057Y322450D01*
X1922930Y323033D01*
X1922487Y323450D01*
X1922043Y323617D01*
X1921473D01*
G01X1922043D02*
X1922423Y323867D01*
X1922740Y324283D01*
X1922867Y324783D01*
X1922740Y325283D01*
X1922423Y325700D01*
X1921853Y325950D01*
X1921283Y325867D01*
X1920713Y325533D01*
G01X1926700Y320783D02*
X1926573Y320867D01*
Y321033D01*
X1926700Y321117D01*
X1926827Y321033D01*
Y320867D01*
X1926700Y320783D01*
G01X1931800Y325950D02*
X1931293Y325783D01*
X1930913Y325367D01*
X1930660Y324867D01*
X1930470Y324200D01*
X1930407Y323450D01*
X1930470Y322700D01*
X1930660Y322033D01*
X1930913Y321533D01*
X1931293Y321117D01*
X1931800Y320950D01*
X1932307Y321117D01*
X1932687Y321533D01*
X1932940Y322033D01*
X1933130Y322700D01*
X1933193Y323450D01*
X1933130Y324200D01*
X1932940Y324867D01*
X1932687Y325367D01*
X1932307Y325783D01*
X1931800Y325950D01*
G01X1890303Y346317D02*
X1891823D01*
G01X1891000Y347400D02*
Y345233D01*
G01X1894897Y348817D02*
X1895277Y349317D01*
X1895720Y349567D01*
X1896227Y349650D01*
X1896860Y349483D01*
X1897303Y349067D01*
X1897430Y348567D01*
X1897367Y348067D01*
X1897113Y347650D01*
X1895847Y346817D01*
X1895277Y346233D01*
X1894897Y345400D01*
X1894770Y344650D01*
X1897430D01*
G01X1901200Y344483D02*
X1901073Y344567D01*
Y344733D01*
X1901200Y344817D01*
X1901327Y344733D01*
Y344567D01*
X1901200Y344483D01*
G01X1906300Y349650D02*
X1905793Y349483D01*
X1905413Y349067D01*
X1905160Y348567D01*
X1904970Y347900D01*
X1904907Y347150D01*
X1904970Y346400D01*
X1905160Y345733D01*
X1905413Y345233D01*
X1905793Y344817D01*
X1906300Y344650D01*
X1906807Y344817D01*
X1907187Y345233D01*
X1907440Y345733D01*
X1907630Y346400D01*
X1907693Y347150D01*
X1907630Y347900D01*
X1907440Y348567D01*
X1907187Y349067D01*
X1906807Y349483D01*
X1906300Y349650D01*
G01X1910260Y344483D02*
X1912540Y349650D01*
G01X1915677Y346317D02*
X1917323D01*
G01X1920397Y348817D02*
X1920777Y349317D01*
X1921220Y349567D01*
X1921727Y349650D01*
X1922360Y349483D01*
X1922803Y349067D01*
X1922930Y348567D01*
X1922867Y348067D01*
X1922613Y347650D01*
X1921347Y346817D01*
X1920777Y346233D01*
X1920397Y345400D01*
X1920270Y344650D01*
X1922930D01*
G01X1926700Y344483D02*
X1926573Y344567D01*
Y344733D01*
X1926700Y344817D01*
X1926827Y344733D01*
Y344567D01*
X1926700Y344483D01*
G01X1931800Y349650D02*
X1931293Y349483D01*
X1930913Y349067D01*
X1930660Y348567D01*
X1930470Y347900D01*
X1930407Y347150D01*
X1930470Y346400D01*
X1930660Y345733D01*
X1930913Y345233D01*
X1931293Y344817D01*
X1931800Y344650D01*
X1932307Y344817D01*
X1932687Y345233D01*
X1932940Y345733D01*
X1933130Y346400D01*
X1933193Y347150D01*
X1933130Y347900D01*
X1932940Y348567D01*
X1932687Y349067D01*
X1932307Y349483D01*
X1931800Y349650D01*
G01X1890303Y370017D02*
X1891823D01*
G01X1891000Y371100D02*
Y368933D01*
G01X1894707Y369350D02*
X1895087Y368767D01*
X1895593Y368433D01*
X1896163Y368350D01*
X1896670Y368433D01*
X1897177Y368850D01*
X1897493Y369350D01*
X1897557Y369850D01*
X1897430Y370433D01*
X1896987Y370850D01*
X1896543Y371017D01*
X1895973D01*
G01X1896543D02*
X1896923Y371267D01*
X1897240Y371683D01*
X1897367Y372183D01*
X1897240Y372683D01*
X1896923Y373100D01*
X1896353Y373350D01*
X1895783Y373267D01*
X1895213Y372933D01*
G01X1901200Y368183D02*
X1901073Y368267D01*
Y368433D01*
X1901200Y368517D01*
X1901327Y368433D01*
Y368267D01*
X1901200Y368183D01*
G01X1906300Y373350D02*
X1905793Y373183D01*
X1905413Y372767D01*
X1905160Y372267D01*
X1904970Y371600D01*
X1904907Y370850D01*
X1904970Y370100D01*
X1905160Y369433D01*
X1905413Y368933D01*
X1905793Y368517D01*
X1906300Y368350D01*
X1906807Y368517D01*
X1907187Y368933D01*
X1907440Y369433D01*
X1907630Y370100D01*
X1907693Y370850D01*
X1907630Y371600D01*
X1907440Y372267D01*
X1907187Y372767D01*
X1906807Y373183D01*
X1906300Y373350D01*
G01X1910260Y368183D02*
X1912540Y373350D01*
G01X1915677Y370017D02*
X1917323D01*
G01X1920207Y369350D02*
X1920587Y368767D01*
X1921093Y368433D01*
X1921663Y368350D01*
X1922170Y368433D01*
X1922677Y368850D01*
X1922993Y369350D01*
X1923057Y369850D01*
X1922930Y370433D01*
X1922487Y370850D01*
X1922043Y371017D01*
X1921473D01*
G01X1922043D02*
X1922423Y371267D01*
X1922740Y371683D01*
X1922867Y372183D01*
X1922740Y372683D01*
X1922423Y373100D01*
X1921853Y373350D01*
X1921283Y373267D01*
X1920713Y372933D01*
G01X1926700Y368183D02*
X1926573Y368267D01*
Y368433D01*
X1926700Y368517D01*
X1926827Y368433D01*
Y368267D01*
X1926700Y368183D01*
G01X1931800Y373350D02*
X1931293Y373183D01*
X1930913Y372767D01*
X1930660Y372267D01*
X1930470Y371600D01*
X1930407Y370850D01*
X1930470Y370100D01*
X1930660Y369433D01*
X1930913Y368933D01*
X1931293Y368517D01*
X1931800Y368350D01*
X1932307Y368517D01*
X1932687Y368933D01*
X1932940Y369433D01*
X1933130Y370100D01*
X1933193Y370850D01*
X1933130Y371600D01*
X1932940Y372267D01*
X1932687Y372767D01*
X1932307Y373183D01*
X1931800Y373350D01*
G01X1890303Y393717D02*
X1891823D01*
G01X1891000Y394800D02*
Y392633D01*
G01X1894707Y393050D02*
X1895087Y392467D01*
X1895593Y392133D01*
X1896163Y392050D01*
X1896670Y392133D01*
X1897177Y392550D01*
X1897493Y393050D01*
X1897557Y393550D01*
X1897430Y394133D01*
X1896987Y394550D01*
X1896543Y394717D01*
X1895973D01*
G01X1896543D02*
X1896923Y394967D01*
X1897240Y395383D01*
X1897367Y395883D01*
X1897240Y396383D01*
X1896923Y396800D01*
X1896353Y397050D01*
X1895783Y396967D01*
X1895213Y396633D01*
G01X1901200Y391883D02*
X1901073Y391967D01*
Y392133D01*
X1901200Y392217D01*
X1901327Y392133D01*
Y391967D01*
X1901200Y391883D01*
G01X1906300Y397050D02*
X1905793Y396883D01*
X1905413Y396467D01*
X1905160Y395967D01*
X1904970Y395300D01*
X1904907Y394550D01*
X1904970Y393800D01*
X1905160Y393133D01*
X1905413Y392633D01*
X1905793Y392217D01*
X1906300Y392050D01*
X1906807Y392217D01*
X1907187Y392633D01*
X1907440Y393133D01*
X1907630Y393800D01*
X1907693Y394550D01*
X1907630Y395300D01*
X1907440Y395967D01*
X1907187Y396467D01*
X1906807Y396883D01*
X1906300Y397050D01*
G01X1910260Y391883D02*
X1912540Y397050D01*
G01X1915677Y393717D02*
X1917323D01*
G01X1920207Y393050D02*
X1920587Y392467D01*
X1921093Y392133D01*
X1921663Y392050D01*
X1922170Y392133D01*
X1922677Y392550D01*
X1922993Y393050D01*
X1923057Y393550D01*
X1922930Y394133D01*
X1922487Y394550D01*
X1922043Y394717D01*
X1921473D01*
G01X1922043D02*
X1922423Y394967D01*
X1922740Y395383D01*
X1922867Y395883D01*
X1922740Y396383D01*
X1922423Y396800D01*
X1921853Y397050D01*
X1921283Y396967D01*
X1920713Y396633D01*
G01X1926700Y391883D02*
X1926573Y391967D01*
Y392133D01*
X1926700Y392217D01*
X1926827Y392133D01*
Y391967D01*
X1926700Y391883D01*
G01X1931800Y397050D02*
X1931293Y396883D01*
X1930913Y396467D01*
X1930660Y395967D01*
X1930470Y395300D01*
X1930407Y394550D01*
X1930470Y393800D01*
X1930660Y393133D01*
X1930913Y392633D01*
X1931293Y392217D01*
X1931800Y392050D01*
X1932307Y392217D01*
X1932687Y392633D01*
X1932940Y393133D01*
X1933130Y393800D01*
X1933193Y394550D01*
X1933130Y395300D01*
X1932940Y395967D01*
X1932687Y396467D01*
X1932307Y396883D01*
X1931800Y397050D01*
G01X1891000Y415200D02*
Y410200D01*
G01X1889543Y415200D02*
X1892457D01*
G01X1896100Y410200D02*
X1895593Y410283D01*
X1895150Y410617D01*
X1894770Y411117D01*
X1894517Y411700D01*
X1894390Y412367D01*
Y413033D01*
X1894517Y413700D01*
X1894770Y414283D01*
X1895150Y414783D01*
X1895593Y415117D01*
X1896100Y415200D01*
X1896607Y415117D01*
X1897050Y414783D01*
X1897430Y414283D01*
X1897683Y413700D01*
X1897810Y413033D01*
Y412367D01*
X1897683Y411700D01*
X1897430Y411117D01*
X1897050Y410617D01*
X1896607Y410283D01*
X1896100Y410200D01*
G01X1899933Y415200D02*
Y410200D01*
X1902467D01*
G01X1907567D02*
X1905033D01*
Y415200D01*
X1907567D01*
G01X1906553Y412783D02*
X1905033D01*
G01X1910133Y410200D02*
Y415200D01*
X1911717D01*
X1912223Y414950D01*
X1912540Y414617D01*
X1912667Y413950D01*
X1912540Y413283D01*
X1912160Y412867D01*
X1911717Y412617D01*
X1910133D01*
G01X1911717D02*
X1912667Y410200D01*
G01X1914917D02*
X1916500Y415200D01*
X1918083Y410200D01*
G01X1917513Y411950D02*
X1915487D01*
G01X1920143Y410200D02*
Y415200D01*
X1923057Y410200D01*
Y415200D01*
G01X1928093Y414783D02*
X1927713Y415033D01*
X1927270Y415200D01*
X1926763D01*
X1926193Y414950D01*
X1925750Y414533D01*
X1925433Y414033D01*
X1925180Y413200D01*
X1925117Y412450D01*
X1925243Y411700D01*
X1925433Y411200D01*
X1925813Y410700D01*
X1926257Y410367D01*
X1926700Y410200D01*
X1927143D01*
X1927587Y410367D01*
X1927967Y410617D01*
X1928283Y410950D01*
G01X1933067Y410200D02*
X1930533D01*
Y415200D01*
X1933067D01*
G01X1932053Y412783D02*
X1930533D01*
G01X1952043Y-176750D02*
Y-171750D01*
X1954957Y-176750D01*
Y-171750D01*
G01X1958600Y-176750D02*
X1958093Y-176667D01*
X1957650Y-176333D01*
X1957270Y-175833D01*
X1957017Y-175250D01*
X1956890Y-174583D01*
Y-173917D01*
X1957017Y-173250D01*
X1957270Y-172667D01*
X1957650Y-172167D01*
X1958093Y-171833D01*
X1958600Y-171750D01*
X1959107Y-171833D01*
X1959550Y-172167D01*
X1959930Y-172667D01*
X1960183Y-173250D01*
X1960310Y-173917D01*
Y-174583D01*
X1960183Y-175250D01*
X1959930Y-175833D01*
X1959550Y-176333D01*
X1959107Y-176667D01*
X1958600Y-176750D01*
G01X1962243D02*
Y-171750D01*
X1965157Y-176750D01*
Y-171750D01*
G01X1967977Y-175083D02*
X1969623D01*
G01X1972633Y-176750D02*
Y-171750D01*
X1974153D01*
X1974660Y-172000D01*
X1975040Y-172583D01*
X1975167Y-173250D01*
X1975040Y-173917D01*
X1974723Y-174417D01*
X1974153Y-174667D01*
X1972633D01*
G01X1977733Y-171750D02*
Y-176750D01*
X1980267D01*
G01X1982517D02*
X1984100Y-171750D01*
X1985683Y-176750D01*
G01X1985113Y-175000D02*
X1983087D01*
G01X1989200Y-171750D02*
Y-176750D01*
G01X1987743Y-171750D02*
X1990657D01*
G01X1995567Y-176750D02*
X1993033D01*
Y-171750D01*
X1995567D01*
G01X1994553Y-174167D02*
X1993033D01*
G01X1998007Y-176750D02*
Y-171750D01*
X1999273D01*
X1999780Y-172000D01*
X2000160Y-172333D01*
X2000477Y-172833D01*
X2000730Y-173417D01*
X2000793Y-174250D01*
X2000730Y-175083D01*
X2000477Y-175667D01*
X2000160Y-176167D01*
X1999780Y-176500D01*
X1999273Y-176750D01*
X1998007D01*
G01X1952043Y-153050D02*
Y-148050D01*
X1954957Y-153050D01*
Y-148050D01*
G01X1958600Y-153050D02*
X1958093Y-152967D01*
X1957650Y-152633D01*
X1957270Y-152133D01*
X1957017Y-151550D01*
X1956890Y-150883D01*
Y-150217D01*
X1957017Y-149550D01*
X1957270Y-148967D01*
X1957650Y-148467D01*
X1958093Y-148133D01*
X1958600Y-148050D01*
X1959107Y-148133D01*
X1959550Y-148467D01*
X1959930Y-148967D01*
X1960183Y-149550D01*
X1960310Y-150217D01*
Y-150883D01*
X1960183Y-151550D01*
X1959930Y-152133D01*
X1959550Y-152633D01*
X1959107Y-152967D01*
X1958600Y-153050D01*
G01X1962243D02*
Y-148050D01*
X1965157Y-153050D01*
Y-148050D01*
G01X1967977Y-151383D02*
X1969623D01*
G01X1972633Y-153050D02*
Y-148050D01*
X1974153D01*
X1974660Y-148300D01*
X1975040Y-148883D01*
X1975167Y-149550D01*
X1975040Y-150217D01*
X1974723Y-150717D01*
X1974153Y-150967D01*
X1972633D01*
G01X1977733Y-148050D02*
Y-153050D01*
X1980267D01*
G01X1982517D02*
X1984100Y-148050D01*
X1985683Y-153050D01*
G01X1985113Y-151300D02*
X1983087D01*
G01X1989200Y-148050D02*
Y-153050D01*
G01X1987743Y-148050D02*
X1990657D01*
G01X1995567Y-153050D02*
X1993033D01*
Y-148050D01*
X1995567D01*
G01X1994553Y-150467D02*
X1993033D01*
G01X1998007Y-153050D02*
Y-148050D01*
X1999273D01*
X1999780Y-148300D01*
X2000160Y-148633D01*
X2000477Y-149133D01*
X2000730Y-149717D01*
X2000793Y-150550D01*
X2000730Y-151383D01*
X2000477Y-151967D01*
X2000160Y-152467D01*
X1999780Y-152800D01*
X1999273Y-153050D01*
X1998007D01*
G01X1952043Y-129350D02*
Y-124350D01*
X1954957Y-129350D01*
Y-124350D01*
G01X1958600Y-129350D02*
X1958093Y-129267D01*
X1957650Y-128933D01*
X1957270Y-128433D01*
X1957017Y-127850D01*
X1956890Y-127183D01*
Y-126517D01*
X1957017Y-125850D01*
X1957270Y-125267D01*
X1957650Y-124767D01*
X1958093Y-124433D01*
X1958600Y-124350D01*
X1959107Y-124433D01*
X1959550Y-124767D01*
X1959930Y-125267D01*
X1960183Y-125850D01*
X1960310Y-126517D01*
Y-127183D01*
X1960183Y-127850D01*
X1959930Y-128433D01*
X1959550Y-128933D01*
X1959107Y-129267D01*
X1958600Y-129350D01*
G01X1962243D02*
Y-124350D01*
X1965157Y-129350D01*
Y-124350D01*
G01X1967977Y-127683D02*
X1969623D01*
G01X1972633Y-129350D02*
Y-124350D01*
X1974153D01*
X1974660Y-124600D01*
X1975040Y-125183D01*
X1975167Y-125850D01*
X1975040Y-126517D01*
X1974723Y-127017D01*
X1974153Y-127267D01*
X1972633D01*
G01X1977733Y-124350D02*
Y-129350D01*
X1980267D01*
G01X1982517D02*
X1984100Y-124350D01*
X1985683Y-129350D01*
G01X1985113Y-127600D02*
X1983087D01*
G01X1989200Y-124350D02*
Y-129350D01*
G01X1987743Y-124350D02*
X1990657D01*
G01X1995567Y-129350D02*
X1993033D01*
Y-124350D01*
X1995567D01*
G01X1994553Y-126767D02*
X1993033D01*
G01X1998007Y-129350D02*
Y-124350D01*
X1999273D01*
X1999780Y-124600D01*
X2000160Y-124933D01*
X2000477Y-125433D01*
X2000730Y-126017D01*
X2000793Y-126850D01*
X2000730Y-127683D01*
X2000477Y-128267D01*
X2000160Y-128767D01*
X1999780Y-129100D01*
X1999273Y-129350D01*
X1998007D01*
G01X1952043Y-105650D02*
Y-100650D01*
X1954957Y-105650D01*
Y-100650D01*
G01X1958600Y-105650D02*
X1958093Y-105567D01*
X1957650Y-105233D01*
X1957270Y-104733D01*
X1957017Y-104150D01*
X1956890Y-103483D01*
Y-102817D01*
X1957017Y-102150D01*
X1957270Y-101567D01*
X1957650Y-101067D01*
X1958093Y-100733D01*
X1958600Y-100650D01*
X1959107Y-100733D01*
X1959550Y-101067D01*
X1959930Y-101567D01*
X1960183Y-102150D01*
X1960310Y-102817D01*
Y-103483D01*
X1960183Y-104150D01*
X1959930Y-104733D01*
X1959550Y-105233D01*
X1959107Y-105567D01*
X1958600Y-105650D01*
G01X1962243D02*
Y-100650D01*
X1965157Y-105650D01*
Y-100650D01*
G01X1967977Y-103983D02*
X1969623D01*
G01X1972633Y-105650D02*
Y-100650D01*
X1974153D01*
X1974660Y-100900D01*
X1975040Y-101483D01*
X1975167Y-102150D01*
X1975040Y-102817D01*
X1974723Y-103317D01*
X1974153Y-103567D01*
X1972633D01*
G01X1977733Y-100650D02*
Y-105650D01*
X1980267D01*
G01X1982517D02*
X1984100Y-100650D01*
X1985683Y-105650D01*
G01X1985113Y-103900D02*
X1983087D01*
G01X1989200Y-100650D02*
Y-105650D01*
G01X1987743Y-100650D02*
X1990657D01*
G01X1995567Y-105650D02*
X1993033D01*
Y-100650D01*
X1995567D01*
G01X1994553Y-103067D02*
X1993033D01*
G01X1998007Y-105650D02*
Y-100650D01*
X1999273D01*
X1999780Y-100900D01*
X2000160Y-101233D01*
X2000477Y-101733D01*
X2000730Y-102317D01*
X2000793Y-103150D01*
X2000730Y-103983D01*
X2000477Y-104567D01*
X2000160Y-105067D01*
X1999780Y-105400D01*
X1999273Y-105650D01*
X1998007D01*
G01X1952043Y-81950D02*
Y-76950D01*
X1954957Y-81950D01*
Y-76950D01*
G01X1958600Y-81950D02*
X1958093Y-81867D01*
X1957650Y-81533D01*
X1957270Y-81033D01*
X1957017Y-80450D01*
X1956890Y-79783D01*
Y-79117D01*
X1957017Y-78450D01*
X1957270Y-77867D01*
X1957650Y-77367D01*
X1958093Y-77033D01*
X1958600Y-76950D01*
X1959107Y-77033D01*
X1959550Y-77367D01*
X1959930Y-77867D01*
X1960183Y-78450D01*
X1960310Y-79117D01*
Y-79783D01*
X1960183Y-80450D01*
X1959930Y-81033D01*
X1959550Y-81533D01*
X1959107Y-81867D01*
X1958600Y-81950D01*
G01X1962243D02*
Y-76950D01*
X1965157Y-81950D01*
Y-76950D01*
G01X1967977Y-80283D02*
X1969623D01*
G01X1972633Y-81950D02*
Y-76950D01*
X1974153D01*
X1974660Y-77200D01*
X1975040Y-77783D01*
X1975167Y-78450D01*
X1975040Y-79117D01*
X1974723Y-79617D01*
X1974153Y-79867D01*
X1972633D01*
G01X1977733Y-76950D02*
Y-81950D01*
X1980267D01*
G01X1982517D02*
X1984100Y-76950D01*
X1985683Y-81950D01*
G01X1985113Y-80200D02*
X1983087D01*
G01X1989200Y-76950D02*
Y-81950D01*
G01X1987743Y-76950D02*
X1990657D01*
G01X1995567Y-81950D02*
X1993033D01*
Y-76950D01*
X1995567D01*
G01X1994553Y-79367D02*
X1993033D01*
G01X1998007Y-81950D02*
Y-76950D01*
X1999273D01*
X1999780Y-77200D01*
X2000160Y-77533D01*
X2000477Y-78033D01*
X2000730Y-78617D01*
X2000793Y-79450D01*
X2000730Y-80283D01*
X2000477Y-80867D01*
X2000160Y-81367D01*
X1999780Y-81700D01*
X1999273Y-81950D01*
X1998007D01*
G01X1952043Y-58250D02*
Y-53250D01*
X1954957Y-58250D01*
Y-53250D01*
G01X1958600Y-58250D02*
X1958093Y-58167D01*
X1957650Y-57833D01*
X1957270Y-57333D01*
X1957017Y-56750D01*
X1956890Y-56083D01*
Y-55417D01*
X1957017Y-54750D01*
X1957270Y-54167D01*
X1957650Y-53667D01*
X1958093Y-53333D01*
X1958600Y-53250D01*
X1959107Y-53333D01*
X1959550Y-53667D01*
X1959930Y-54167D01*
X1960183Y-54750D01*
X1960310Y-55417D01*
Y-56083D01*
X1960183Y-56750D01*
X1959930Y-57333D01*
X1959550Y-57833D01*
X1959107Y-58167D01*
X1958600Y-58250D01*
G01X1962243D02*
Y-53250D01*
X1965157Y-58250D01*
Y-53250D01*
G01X1967977Y-56583D02*
X1969623D01*
G01X1972633Y-58250D02*
Y-53250D01*
X1974153D01*
X1974660Y-53500D01*
X1975040Y-54083D01*
X1975167Y-54750D01*
X1975040Y-55417D01*
X1974723Y-55917D01*
X1974153Y-56167D01*
X1972633D01*
G01X1977733Y-53250D02*
Y-58250D01*
X1980267D01*
G01X1982517D02*
X1984100Y-53250D01*
X1985683Y-58250D01*
G01X1985113Y-56500D02*
X1983087D01*
G01X1989200Y-53250D02*
Y-58250D01*
G01X1987743Y-53250D02*
X1990657D01*
G01X1995567Y-58250D02*
X1993033D01*
Y-53250D01*
X1995567D01*
G01X1994553Y-55667D02*
X1993033D01*
G01X1998007Y-58250D02*
Y-53250D01*
X1999273D01*
X1999780Y-53500D01*
X2000160Y-53833D01*
X2000477Y-54333D01*
X2000730Y-54917D01*
X2000793Y-55750D01*
X2000730Y-56583D01*
X2000477Y-57167D01*
X2000160Y-57667D01*
X1999780Y-58000D01*
X1999273Y-58250D01*
X1998007D01*
G01X1952043Y-34550D02*
Y-29550D01*
X1954957Y-34550D01*
Y-29550D01*
G01X1958600Y-34550D02*
X1958093Y-34467D01*
X1957650Y-34133D01*
X1957270Y-33633D01*
X1957017Y-33050D01*
X1956890Y-32383D01*
Y-31717D01*
X1957017Y-31050D01*
X1957270Y-30467D01*
X1957650Y-29967D01*
X1958093Y-29633D01*
X1958600Y-29550D01*
X1959107Y-29633D01*
X1959550Y-29967D01*
X1959930Y-30467D01*
X1960183Y-31050D01*
X1960310Y-31717D01*
Y-32383D01*
X1960183Y-33050D01*
X1959930Y-33633D01*
X1959550Y-34133D01*
X1959107Y-34467D01*
X1958600Y-34550D01*
G01X1962243D02*
Y-29550D01*
X1965157Y-34550D01*
Y-29550D01*
G01X1967977Y-32883D02*
X1969623D01*
G01X1972633Y-34550D02*
Y-29550D01*
X1974153D01*
X1974660Y-29800D01*
X1975040Y-30383D01*
X1975167Y-31050D01*
X1975040Y-31717D01*
X1974723Y-32217D01*
X1974153Y-32467D01*
X1972633D01*
G01X1977733Y-29550D02*
Y-34550D01*
X1980267D01*
G01X1982517D02*
X1984100Y-29550D01*
X1985683Y-34550D01*
G01X1985113Y-32800D02*
X1983087D01*
G01X1989200Y-29550D02*
Y-34550D01*
G01X1987743Y-29550D02*
X1990657D01*
G01X1995567Y-34550D02*
X1993033D01*
Y-29550D01*
X1995567D01*
G01X1994553Y-31967D02*
X1993033D01*
G01X1998007Y-34550D02*
Y-29550D01*
X1999273D01*
X1999780Y-29800D01*
X2000160Y-30133D01*
X2000477Y-30633D01*
X2000730Y-31217D01*
X2000793Y-32050D01*
X2000730Y-32883D01*
X2000477Y-33467D01*
X2000160Y-33967D01*
X1999780Y-34300D01*
X1999273Y-34550D01*
X1998007D01*
G01X1952043Y-10850D02*
Y-5850D01*
X1954957Y-10850D01*
Y-5850D01*
G01X1958600Y-10850D02*
X1958093Y-10767D01*
X1957650Y-10433D01*
X1957270Y-9933D01*
X1957017Y-9350D01*
X1956890Y-8683D01*
Y-8017D01*
X1957017Y-7350D01*
X1957270Y-6767D01*
X1957650Y-6267D01*
X1958093Y-5933D01*
X1958600Y-5850D01*
X1959107Y-5933D01*
X1959550Y-6267D01*
X1959930Y-6767D01*
X1960183Y-7350D01*
X1960310Y-8017D01*
Y-8683D01*
X1960183Y-9350D01*
X1959930Y-9933D01*
X1959550Y-10433D01*
X1959107Y-10767D01*
X1958600Y-10850D01*
G01X1962243D02*
Y-5850D01*
X1965157Y-10850D01*
Y-5850D01*
G01X1967977Y-9183D02*
X1969623D01*
G01X1972633Y-10850D02*
Y-5850D01*
X1974153D01*
X1974660Y-6100D01*
X1975040Y-6683D01*
X1975167Y-7350D01*
X1975040Y-8017D01*
X1974723Y-8517D01*
X1974153Y-8767D01*
X1972633D01*
G01X1977733Y-5850D02*
Y-10850D01*
X1980267D01*
G01X1982517D02*
X1984100Y-5850D01*
X1985683Y-10850D01*
G01X1985113Y-9100D02*
X1983087D01*
G01X1989200Y-5850D02*
Y-10850D01*
G01X1987743Y-5850D02*
X1990657D01*
G01X1995567Y-10850D02*
X1993033D01*
Y-5850D01*
X1995567D01*
G01X1994553Y-8267D02*
X1993033D01*
G01X1998007Y-10850D02*
Y-5850D01*
X1999273D01*
X1999780Y-6100D01*
X2000160Y-6433D01*
X2000477Y-6933D01*
X2000730Y-7517D01*
X2000793Y-8350D01*
X2000730Y-9183D01*
X2000477Y-9767D01*
X2000160Y-10267D01*
X1999780Y-10600D01*
X1999273Y-10850D01*
X1998007D01*
G01X1962433Y12850D02*
Y17850D01*
X1963953D01*
X1964460Y17600D01*
X1964840Y17017D01*
X1964967Y16350D01*
X1964840Y15683D01*
X1964523Y15183D01*
X1963953Y14933D01*
X1962433D01*
G01X1967533Y17850D02*
Y12850D01*
X1970067D01*
G01X1972317D02*
X1973900Y17850D01*
X1975483Y12850D01*
G01X1974913Y14600D02*
X1972887D01*
G01X1979000Y17850D02*
Y12850D01*
G01X1977543Y17850D02*
X1980457D01*
G01X1985367Y12850D02*
X1982833D01*
Y17850D01*
X1985367D01*
G01X1984353Y15433D02*
X1982833D01*
G01X1987807Y12850D02*
Y17850D01*
X1989073D01*
X1989580Y17600D01*
X1989960Y17267D01*
X1990277Y16767D01*
X1990530Y16183D01*
X1990593Y15350D01*
X1990530Y14517D01*
X1990277Y13933D01*
X1989960Y13433D01*
X1989580Y13100D01*
X1989073Y12850D01*
X1987807D01*
G01X1962433Y36550D02*
Y41550D01*
X1963953D01*
X1964460Y41300D01*
X1964840Y40717D01*
X1964967Y40050D01*
X1964840Y39383D01*
X1964523Y38883D01*
X1963953Y38633D01*
X1962433D01*
G01X1967533Y41550D02*
Y36550D01*
X1970067D01*
G01X1972317D02*
X1973900Y41550D01*
X1975483Y36550D01*
G01X1974913Y38300D02*
X1972887D01*
G01X1979000Y41550D02*
Y36550D01*
G01X1977543Y41550D02*
X1980457D01*
G01X1985367Y36550D02*
X1982833D01*
Y41550D01*
X1985367D01*
G01X1984353Y39133D02*
X1982833D01*
G01X1987807Y36550D02*
Y41550D01*
X1989073D01*
X1989580Y41300D01*
X1989960Y40967D01*
X1990277Y40467D01*
X1990530Y39883D01*
X1990593Y39050D01*
X1990530Y38217D01*
X1990277Y37633D01*
X1989960Y37133D01*
X1989580Y36800D01*
X1989073Y36550D01*
X1987807D01*
G01X1962433Y60250D02*
Y65250D01*
X1963953D01*
X1964460Y65000D01*
X1964840Y64417D01*
X1964967Y63750D01*
X1964840Y63083D01*
X1964523Y62583D01*
X1963953Y62333D01*
X1962433D01*
G01X1967533Y65250D02*
Y60250D01*
X1970067D01*
G01X1972317D02*
X1973900Y65250D01*
X1975483Y60250D01*
G01X1974913Y62000D02*
X1972887D01*
G01X1979000Y65250D02*
Y60250D01*
G01X1977543Y65250D02*
X1980457D01*
G01X1985367Y60250D02*
X1982833D01*
Y65250D01*
X1985367D01*
G01X1984353Y62833D02*
X1982833D01*
G01X1987807Y60250D02*
Y65250D01*
X1989073D01*
X1989580Y65000D01*
X1989960Y64667D01*
X1990277Y64167D01*
X1990530Y63583D01*
X1990593Y62750D01*
X1990530Y61917D01*
X1990277Y61333D01*
X1989960Y60833D01*
X1989580Y60500D01*
X1989073Y60250D01*
X1987807D01*
G01X1962433Y83950D02*
Y88950D01*
X1963953D01*
X1964460Y88700D01*
X1964840Y88117D01*
X1964967Y87450D01*
X1964840Y86783D01*
X1964523Y86283D01*
X1963953Y86033D01*
X1962433D01*
G01X1967533Y88950D02*
Y83950D01*
X1970067D01*
G01X1972317D02*
X1973900Y88950D01*
X1975483Y83950D01*
G01X1974913Y85700D02*
X1972887D01*
G01X1979000Y88950D02*
Y83950D01*
G01X1977543Y88950D02*
X1980457D01*
G01X1985367Y83950D02*
X1982833D01*
Y88950D01*
X1985367D01*
G01X1984353Y86533D02*
X1982833D01*
G01X1987807Y83950D02*
Y88950D01*
X1989073D01*
X1989580Y88700D01*
X1989960Y88367D01*
X1990277Y87867D01*
X1990530Y87283D01*
X1990593Y86450D01*
X1990530Y85617D01*
X1990277Y85033D01*
X1989960Y84533D01*
X1989580Y84200D01*
X1989073Y83950D01*
X1987807D01*
G01X1962433Y107650D02*
Y112650D01*
X1963953D01*
X1964460Y112400D01*
X1964840Y111817D01*
X1964967Y111150D01*
X1964840Y110483D01*
X1964523Y109983D01*
X1963953Y109733D01*
X1962433D01*
G01X1967533Y112650D02*
Y107650D01*
X1970067D01*
G01X1972317D02*
X1973900Y112650D01*
X1975483Y107650D01*
G01X1974913Y109400D02*
X1972887D01*
G01X1979000Y112650D02*
Y107650D01*
G01X1977543Y112650D02*
X1980457D01*
G01X1985367Y107650D02*
X1982833D01*
Y112650D01*
X1985367D01*
G01X1984353Y110233D02*
X1982833D01*
G01X1987807Y107650D02*
Y112650D01*
X1989073D01*
X1989580Y112400D01*
X1989960Y112067D01*
X1990277Y111567D01*
X1990530Y110983D01*
X1990593Y110150D01*
X1990530Y109317D01*
X1990277Y108733D01*
X1989960Y108233D01*
X1989580Y107900D01*
X1989073Y107650D01*
X1987807D01*
G01X1962433Y131350D02*
Y136350D01*
X1963953D01*
X1964460Y136100D01*
X1964840Y135517D01*
X1964967Y134850D01*
X1964840Y134183D01*
X1964523Y133683D01*
X1963953Y133433D01*
X1962433D01*
G01X1967533Y136350D02*
Y131350D01*
X1970067D01*
G01X1972317D02*
X1973900Y136350D01*
X1975483Y131350D01*
G01X1974913Y133100D02*
X1972887D01*
G01X1979000Y136350D02*
Y131350D01*
G01X1977543Y136350D02*
X1980457D01*
G01X1985367Y131350D02*
X1982833D01*
Y136350D01*
X1985367D01*
G01X1984353Y133933D02*
X1982833D01*
G01X1987807Y131350D02*
Y136350D01*
X1989073D01*
X1989580Y136100D01*
X1989960Y135767D01*
X1990277Y135267D01*
X1990530Y134683D01*
X1990593Y133850D01*
X1990530Y133017D01*
X1990277Y132433D01*
X1989960Y131933D01*
X1989580Y131600D01*
X1989073Y131350D01*
X1987807D01*
G01X1962433Y155050D02*
Y160050D01*
X1963953D01*
X1964460Y159800D01*
X1964840Y159217D01*
X1964967Y158550D01*
X1964840Y157883D01*
X1964523Y157383D01*
X1963953Y157133D01*
X1962433D01*
G01X1967533Y160050D02*
Y155050D01*
X1970067D01*
G01X1972317D02*
X1973900Y160050D01*
X1975483Y155050D01*
G01X1974913Y156800D02*
X1972887D01*
G01X1979000Y160050D02*
Y155050D01*
G01X1977543Y160050D02*
X1980457D01*
G01X1985367Y155050D02*
X1982833D01*
Y160050D01*
X1985367D01*
G01X1984353Y157633D02*
X1982833D01*
G01X1987807Y155050D02*
Y160050D01*
X1989073D01*
X1989580Y159800D01*
X1989960Y159467D01*
X1990277Y158967D01*
X1990530Y158383D01*
X1990593Y157550D01*
X1990530Y156717D01*
X1990277Y156133D01*
X1989960Y155633D01*
X1989580Y155300D01*
X1989073Y155050D01*
X1987807D01*
G01X1962433Y178750D02*
Y183750D01*
X1963953D01*
X1964460Y183500D01*
X1964840Y182917D01*
X1964967Y182250D01*
X1964840Y181583D01*
X1964523Y181083D01*
X1963953Y180833D01*
X1962433D01*
G01X1967533Y183750D02*
Y178750D01*
X1970067D01*
G01X1972317D02*
X1973900Y183750D01*
X1975483Y178750D01*
G01X1974913Y180500D02*
X1972887D01*
G01X1979000Y183750D02*
Y178750D01*
G01X1977543Y183750D02*
X1980457D01*
G01X1985367Y178750D02*
X1982833D01*
Y183750D01*
X1985367D01*
G01X1984353Y181333D02*
X1982833D01*
G01X1987807Y178750D02*
Y183750D01*
X1989073D01*
X1989580Y183500D01*
X1989960Y183167D01*
X1990277Y182667D01*
X1990530Y182083D01*
X1990593Y181250D01*
X1990530Y180417D01*
X1990277Y179833D01*
X1989960Y179333D01*
X1989580Y179000D01*
X1989073Y178750D01*
X1987807D01*
G01X1962433Y202450D02*
Y207450D01*
X1963953D01*
X1964460Y207200D01*
X1964840Y206617D01*
X1964967Y205950D01*
X1964840Y205283D01*
X1964523Y204783D01*
X1963953Y204533D01*
X1962433D01*
G01X1967533Y207450D02*
Y202450D01*
X1970067D01*
G01X1972317D02*
X1973900Y207450D01*
X1975483Y202450D01*
G01X1974913Y204200D02*
X1972887D01*
G01X1979000Y207450D02*
Y202450D01*
G01X1977543Y207450D02*
X1980457D01*
G01X1985367Y202450D02*
X1982833D01*
Y207450D01*
X1985367D01*
G01X1984353Y205033D02*
X1982833D01*
G01X1987807Y202450D02*
Y207450D01*
X1989073D01*
X1989580Y207200D01*
X1989960Y206867D01*
X1990277Y206367D01*
X1990530Y205783D01*
X1990593Y204950D01*
X1990530Y204117D01*
X1990277Y203533D01*
X1989960Y203033D01*
X1989580Y202700D01*
X1989073Y202450D01*
X1987807D01*
G01X1962433Y226150D02*
Y231150D01*
X1963953D01*
X1964460Y230900D01*
X1964840Y230317D01*
X1964967Y229650D01*
X1964840Y228983D01*
X1964523Y228483D01*
X1963953Y228233D01*
X1962433D01*
G01X1967533Y231150D02*
Y226150D01*
X1970067D01*
G01X1972317D02*
X1973900Y231150D01*
X1975483Y226150D01*
G01X1974913Y227900D02*
X1972887D01*
G01X1979000Y231150D02*
Y226150D01*
G01X1977543Y231150D02*
X1980457D01*
G01X1985367Y226150D02*
X1982833D01*
Y231150D01*
X1985367D01*
G01X1984353Y228733D02*
X1982833D01*
G01X1987807Y226150D02*
Y231150D01*
X1989073D01*
X1989580Y230900D01*
X1989960Y230567D01*
X1990277Y230067D01*
X1990530Y229483D01*
X1990593Y228650D01*
X1990530Y227817D01*
X1990277Y227233D01*
X1989960Y226733D01*
X1989580Y226400D01*
X1989073Y226150D01*
X1987807D01*
G01X1962433Y249850D02*
Y254850D01*
X1963953D01*
X1964460Y254600D01*
X1964840Y254017D01*
X1964967Y253350D01*
X1964840Y252683D01*
X1964523Y252183D01*
X1963953Y251933D01*
X1962433D01*
G01X1967533Y254850D02*
Y249850D01*
X1970067D01*
G01X1972317D02*
X1973900Y254850D01*
X1975483Y249850D01*
G01X1974913Y251600D02*
X1972887D01*
G01X1979000Y254850D02*
Y249850D01*
G01X1977543Y254850D02*
X1980457D01*
G01X1985367Y249850D02*
X1982833D01*
Y254850D01*
X1985367D01*
G01X1984353Y252433D02*
X1982833D01*
G01X1987807Y249850D02*
Y254850D01*
X1989073D01*
X1989580Y254600D01*
X1989960Y254267D01*
X1990277Y253767D01*
X1990530Y253183D01*
X1990593Y252350D01*
X1990530Y251517D01*
X1990277Y250933D01*
X1989960Y250433D01*
X1989580Y250100D01*
X1989073Y249850D01*
X1987807D01*
G01X1962433Y273550D02*
Y278550D01*
X1963953D01*
X1964460Y278300D01*
X1964840Y277717D01*
X1964967Y277050D01*
X1964840Y276383D01*
X1964523Y275883D01*
X1963953Y275633D01*
X1962433D01*
G01X1967533Y278550D02*
Y273550D01*
X1970067D01*
G01X1972317D02*
X1973900Y278550D01*
X1975483Y273550D01*
G01X1974913Y275300D02*
X1972887D01*
G01X1979000Y278550D02*
Y273550D01*
G01X1977543Y278550D02*
X1980457D01*
G01X1985367Y273550D02*
X1982833D01*
Y278550D01*
X1985367D01*
G01X1984353Y276133D02*
X1982833D01*
G01X1987807Y273550D02*
Y278550D01*
X1989073D01*
X1989580Y278300D01*
X1989960Y277967D01*
X1990277Y277467D01*
X1990530Y276883D01*
X1990593Y276050D01*
X1990530Y275217D01*
X1990277Y274633D01*
X1989960Y274133D01*
X1989580Y273800D01*
X1989073Y273550D01*
X1987807D01*
G01X1962433Y297250D02*
Y302250D01*
X1963953D01*
X1964460Y302000D01*
X1964840Y301417D01*
X1964967Y300750D01*
X1964840Y300083D01*
X1964523Y299583D01*
X1963953Y299333D01*
X1962433D01*
G01X1967533Y302250D02*
Y297250D01*
X1970067D01*
G01X1972317D02*
X1973900Y302250D01*
X1975483Y297250D01*
G01X1974913Y299000D02*
X1972887D01*
G01X1979000Y302250D02*
Y297250D01*
G01X1977543Y302250D02*
X1980457D01*
G01X1985367Y297250D02*
X1982833D01*
Y302250D01*
X1985367D01*
G01X1984353Y299833D02*
X1982833D01*
G01X1987807Y297250D02*
Y302250D01*
X1989073D01*
X1989580Y302000D01*
X1989960Y301667D01*
X1990277Y301167D01*
X1990530Y300583D01*
X1990593Y299750D01*
X1990530Y298917D01*
X1990277Y298333D01*
X1989960Y297833D01*
X1989580Y297500D01*
X1989073Y297250D01*
X1987807D01*
G01X1962433Y320950D02*
Y325950D01*
X1963953D01*
X1964460Y325700D01*
X1964840Y325117D01*
X1964967Y324450D01*
X1964840Y323783D01*
X1964523Y323283D01*
X1963953Y323033D01*
X1962433D01*
G01X1967533Y325950D02*
Y320950D01*
X1970067D01*
G01X1972317D02*
X1973900Y325950D01*
X1975483Y320950D01*
G01X1974913Y322700D02*
X1972887D01*
G01X1979000Y325950D02*
Y320950D01*
G01X1977543Y325950D02*
X1980457D01*
G01X1985367Y320950D02*
X1982833D01*
Y325950D01*
X1985367D01*
G01X1984353Y323533D02*
X1982833D01*
G01X1987807Y320950D02*
Y325950D01*
X1989073D01*
X1989580Y325700D01*
X1989960Y325367D01*
X1990277Y324867D01*
X1990530Y324283D01*
X1990593Y323450D01*
X1990530Y322617D01*
X1990277Y322033D01*
X1989960Y321533D01*
X1989580Y321200D01*
X1989073Y320950D01*
X1987807D01*
G01X1962433Y344650D02*
Y349650D01*
X1963953D01*
X1964460Y349400D01*
X1964840Y348817D01*
X1964967Y348150D01*
X1964840Y347483D01*
X1964523Y346983D01*
X1963953Y346733D01*
X1962433D01*
G01X1967533Y349650D02*
Y344650D01*
X1970067D01*
G01X1972317D02*
X1973900Y349650D01*
X1975483Y344650D01*
G01X1974913Y346400D02*
X1972887D01*
G01X1979000Y349650D02*
Y344650D01*
G01X1977543Y349650D02*
X1980457D01*
G01X1985367Y344650D02*
X1982833D01*
Y349650D01*
X1985367D01*
G01X1984353Y347233D02*
X1982833D01*
G01X1987807Y344650D02*
Y349650D01*
X1989073D01*
X1989580Y349400D01*
X1989960Y349067D01*
X1990277Y348567D01*
X1990530Y347983D01*
X1990593Y347150D01*
X1990530Y346317D01*
X1990277Y345733D01*
X1989960Y345233D01*
X1989580Y344900D01*
X1989073Y344650D01*
X1987807D01*
G01X1962433Y368350D02*
Y373350D01*
X1963953D01*
X1964460Y373100D01*
X1964840Y372517D01*
X1964967Y371850D01*
X1964840Y371183D01*
X1964523Y370683D01*
X1963953Y370433D01*
X1962433D01*
G01X1967533Y373350D02*
Y368350D01*
X1970067D01*
G01X1972317D02*
X1973900Y373350D01*
X1975483Y368350D01*
G01X1974913Y370100D02*
X1972887D01*
G01X1979000Y373350D02*
Y368350D01*
G01X1977543Y373350D02*
X1980457D01*
G01X1985367Y368350D02*
X1982833D01*
Y373350D01*
X1985367D01*
G01X1984353Y370933D02*
X1982833D01*
G01X1987807Y368350D02*
Y373350D01*
X1989073D01*
X1989580Y373100D01*
X1989960Y372767D01*
X1990277Y372267D01*
X1990530Y371683D01*
X1990593Y370850D01*
X1990530Y370017D01*
X1990277Y369433D01*
X1989960Y368933D01*
X1989580Y368600D01*
X1989073Y368350D01*
X1987807D01*
G01X1962433Y392050D02*
Y397050D01*
X1963953D01*
X1964460Y396800D01*
X1964840Y396217D01*
X1964967Y395550D01*
X1964840Y394883D01*
X1964523Y394383D01*
X1963953Y394133D01*
X1962433D01*
G01X1967533Y397050D02*
Y392050D01*
X1970067D01*
G01X1972317D02*
X1973900Y397050D01*
X1975483Y392050D01*
G01X1974913Y393800D02*
X1972887D01*
G01X1979000Y397050D02*
Y392050D01*
G01X1977543Y397050D02*
X1980457D01*
G01X1985367Y392050D02*
X1982833D01*
Y397050D01*
X1985367D01*
G01X1984353Y394633D02*
X1982833D01*
G01X1987807Y392050D02*
Y397050D01*
X1989073D01*
X1989580Y396800D01*
X1989960Y396467D01*
X1990277Y395967D01*
X1990530Y395383D01*
X1990593Y394550D01*
X1990530Y393717D01*
X1990277Y393133D01*
X1989960Y392633D01*
X1989580Y392300D01*
X1989073Y392050D01*
X1987807D01*
G01X1962433Y410200D02*
Y415200D01*
X1963953D01*
X1964460Y414950D01*
X1964840Y414367D01*
X1964967Y413700D01*
X1964840Y413033D01*
X1964523Y412533D01*
X1963953Y412283D01*
X1962433D01*
G01X1967533Y415200D02*
Y410200D01*
X1970067D01*
G01X1972317D02*
X1973900Y415200D01*
X1975483Y410200D01*
G01X1974913Y411950D02*
X1972887D01*
G01X1979000Y415200D02*
Y410200D01*
G01X1977543Y415200D02*
X1980457D01*
G01X1985367Y410200D02*
X1982833D01*
Y415200D01*
X1985367D01*
G01X1984353Y412783D02*
X1982833D01*
G01X1987807Y410200D02*
Y415200D01*
X1989073D01*
X1989580Y414950D01*
X1989960Y414617D01*
X1990277Y414117D01*
X1990530Y413533D01*
X1990593Y412700D01*
X1990530Y411867D01*
X1990277Y411283D01*
X1989960Y410783D01*
X1989580Y410450D01*
X1989073Y410200D01*
X1987807D01*
G01X2019310Y-176750D02*
Y-171750D01*
X2016967Y-175333D01*
X2020133D01*
G01X2017347Y-148883D02*
X2017727Y-148383D01*
X2018170Y-148133D01*
X2018677Y-148050D01*
X2019310Y-148217D01*
X2019753Y-148633D01*
X2019880Y-149133D01*
X2019817Y-149633D01*
X2019563Y-150050D01*
X2018297Y-150883D01*
X2017727Y-151467D01*
X2017347Y-152300D01*
X2017220Y-153050D01*
X2019880D01*
G01X2017347Y-127267D02*
X2017790Y-126683D01*
X2018170Y-126350D01*
X2018677Y-126183D01*
X2019120Y-126350D01*
X2019437Y-126683D01*
X2019690Y-127183D01*
X2019753Y-127767D01*
X2019690Y-128267D01*
X2019437Y-128767D01*
X2019057Y-129183D01*
X2018613Y-129350D01*
X2018107Y-129183D01*
X2017663Y-128683D01*
X2017410Y-127933D01*
X2017347Y-127100D01*
X2017473Y-126017D01*
X2017663Y-125433D01*
X2017980Y-124850D01*
X2018423Y-124433D01*
X2018867Y-124350D01*
X2019310Y-124517D01*
X2019627Y-124933D01*
G01X2019310Y-105650D02*
Y-100650D01*
X2016967Y-104233D01*
X2020133D01*
G01X2017347Y-77783D02*
X2017727Y-77283D01*
X2018170Y-77033D01*
X2018677Y-76950D01*
X2019310Y-77117D01*
X2019753Y-77533D01*
X2019880Y-78033D01*
X2019817Y-78533D01*
X2019563Y-78950D01*
X2018297Y-79783D01*
X2017727Y-80367D01*
X2017347Y-81200D01*
X2017220Y-81950D01*
X2019880D01*
G01X2016000Y-58250D02*
Y-53250D01*
X2015240Y-54250D01*
G01Y-58250D02*
X2016760D01*
G01X2019897Y-54083D02*
X2020277Y-53583D01*
X2020720Y-53333D01*
X2021227Y-53250D01*
X2021860Y-53417D01*
X2022303Y-53833D01*
X2022430Y-54333D01*
X2022367Y-54833D01*
X2022113Y-55250D01*
X2020847Y-56083D01*
X2020277Y-56667D01*
X2019897Y-57500D01*
X2019770Y-58250D01*
X2022430D01*
G01X2017347Y-30383D02*
X2017727Y-29883D01*
X2018170Y-29633D01*
X2018677Y-29550D01*
X2019310Y-29717D01*
X2019753Y-30133D01*
X2019880Y-30633D01*
X2019817Y-31133D01*
X2019563Y-31550D01*
X2018297Y-32383D01*
X2017727Y-32967D01*
X2017347Y-33800D01*
X2017220Y-34550D01*
X2019880D01*
G01X2017347Y-6683D02*
X2017727Y-6183D01*
X2018170Y-5933D01*
X2018677Y-5850D01*
X2019310Y-6017D01*
X2019753Y-6433D01*
X2019880Y-6933D01*
X2019817Y-7433D01*
X2019563Y-7850D01*
X2018297Y-8683D01*
X2017727Y-9267D01*
X2017347Y-10100D01*
X2017220Y-10850D01*
X2019880D01*
G01X2016000Y12850D02*
Y17850D01*
X2015240Y16850D01*
G01Y12850D02*
X2016760D01*
G01X2019897Y17017D02*
X2020277Y17517D01*
X2020720Y17767D01*
X2021227Y17850D01*
X2021860Y17683D01*
X2022303Y17267D01*
X2022430Y16767D01*
X2022367Y16267D01*
X2022113Y15850D01*
X2020847Y15017D01*
X2020277Y14433D01*
X2019897Y13600D01*
X2019770Y12850D01*
X2022430D01*
G01X2018550Y36550D02*
X2018993Y36633D01*
X2019500Y36883D01*
X2019817Y37300D01*
X2019943Y37883D01*
X2019817Y38467D01*
X2019437Y38967D01*
X2018867Y39217D01*
X2018233D01*
X2017853Y39383D01*
X2017537Y39800D01*
X2017410Y40383D01*
X2017600Y40967D01*
X2018043Y41383D01*
X2018550Y41550D01*
X2019057Y41383D01*
X2019500Y40967D01*
X2019690Y40383D01*
X2019563Y39800D01*
X2019247Y39383D01*
X2018867Y39217D01*
X2018233D01*
X2017663Y38967D01*
X2017283Y38467D01*
X2017157Y37883D01*
X2017283Y37300D01*
X2017600Y36883D01*
X2018107Y36633D01*
X2018550Y36550D01*
G01X2016000Y60250D02*
Y65250D01*
X2015240Y64250D01*
G01Y60250D02*
X2016760D01*
G01X2019897Y64417D02*
X2020277Y64917D01*
X2020720Y65167D01*
X2021227Y65250D01*
X2021860Y65083D01*
X2022303Y64667D01*
X2022430Y64167D01*
X2022367Y63667D01*
X2022113Y63250D01*
X2020847Y62417D01*
X2020277Y61833D01*
X2019897Y61000D01*
X2019770Y60250D01*
X2022430D01*
G01X2019310Y83950D02*
Y88950D01*
X2016967Y85367D01*
X2020133D01*
G01X2018550Y107650D02*
X2018993Y107733D01*
X2019500Y107983D01*
X2019817Y108400D01*
X2019943Y108983D01*
X2019817Y109567D01*
X2019437Y110067D01*
X2018867Y110317D01*
X2018233D01*
X2017853Y110483D01*
X2017537Y110900D01*
X2017410Y111483D01*
X2017600Y112067D01*
X2018043Y112483D01*
X2018550Y112650D01*
X2019057Y112483D01*
X2019500Y112067D01*
X2019690Y111483D01*
X2019563Y110900D01*
X2019247Y110483D01*
X2018867Y110317D01*
X2018233D01*
X2017663Y110067D01*
X2017283Y109567D01*
X2017157Y108983D01*
X2017283Y108400D01*
X2017600Y107983D01*
X2018107Y107733D01*
X2018550Y107650D01*
G01X2016000Y131350D02*
Y136350D01*
X2015240Y135350D01*
G01Y131350D02*
X2016760D01*
G01X2021100D02*
X2021543Y131433D01*
X2022050Y131683D01*
X2022367Y132100D01*
X2022493Y132683D01*
X2022367Y133267D01*
X2021987Y133767D01*
X2021417Y134017D01*
X2020783D01*
X2020403Y134183D01*
X2020087Y134600D01*
X2019960Y135183D01*
X2020150Y135767D01*
X2020593Y136183D01*
X2021100Y136350D01*
X2021607Y136183D01*
X2022050Y135767D01*
X2022240Y135183D01*
X2022113Y134600D01*
X2021797Y134183D01*
X2021417Y134017D01*
X2020783D01*
X2020213Y133767D01*
X2019833Y133267D01*
X2019707Y132683D01*
X2019833Y132100D01*
X2020150Y131683D01*
X2020657Y131433D01*
X2021100Y131350D01*
G01X2016760Y155050D02*
Y160050D01*
X2014417Y156467D01*
X2017583D01*
G01X2021100Y160050D02*
X2020593Y159883D01*
X2020213Y159467D01*
X2019960Y158967D01*
X2019770Y158300D01*
X2019707Y157550D01*
X2019770Y156800D01*
X2019960Y156133D01*
X2020213Y155633D01*
X2020593Y155217D01*
X2021100Y155050D01*
X2021607Y155217D01*
X2021987Y155633D01*
X2022240Y156133D01*
X2022430Y156800D01*
X2022493Y157550D01*
X2022430Y158300D01*
X2022240Y158967D01*
X2021987Y159467D01*
X2021607Y159883D01*
X2021100Y160050D01*
G01X2016000Y178750D02*
Y183750D01*
X2015240Y182750D01*
G01Y178750D02*
X2016760D01*
G01X2019897Y182917D02*
X2020277Y183417D01*
X2020720Y183667D01*
X2021227Y183750D01*
X2021860Y183583D01*
X2022303Y183167D01*
X2022430Y182667D01*
X2022367Y182167D01*
X2022113Y181750D01*
X2020847Y180917D01*
X2020277Y180333D01*
X2019897Y179500D01*
X2019770Y178750D01*
X2022430D01*
G01X2014607Y203450D02*
X2014987Y202867D01*
X2015493Y202533D01*
X2016063Y202450D01*
X2016570Y202533D01*
X2017077Y202950D01*
X2017393Y203450D01*
X2017457Y203950D01*
X2017330Y204533D01*
X2016887Y204950D01*
X2016443Y205117D01*
X2015873D01*
G01X2016443D02*
X2016823Y205367D01*
X2017140Y205783D01*
X2017267Y206283D01*
X2017140Y206783D01*
X2016823Y207200D01*
X2016253Y207450D01*
X2015683Y207367D01*
X2015113Y207033D01*
G01X2019897Y204533D02*
X2020340Y205117D01*
X2020720Y205450D01*
X2021227Y205617D01*
X2021670Y205450D01*
X2021987Y205117D01*
X2022240Y204617D01*
X2022303Y204033D01*
X2022240Y203533D01*
X2021987Y203033D01*
X2021607Y202617D01*
X2021163Y202450D01*
X2020657Y202617D01*
X2020213Y203117D01*
X2019960Y203867D01*
X2019897Y204700D01*
X2020023Y205783D01*
X2020213Y206367D01*
X2020530Y206950D01*
X2020973Y207367D01*
X2021417Y207450D01*
X2021860Y207283D01*
X2022177Y206867D01*
G01X2014607Y227150D02*
X2014987Y226567D01*
X2015493Y226233D01*
X2016063Y226150D01*
X2016570Y226233D01*
X2017077Y226650D01*
X2017393Y227150D01*
X2017457Y227650D01*
X2017330Y228233D01*
X2016887Y228650D01*
X2016443Y228817D01*
X2015873D01*
G01X2016443D02*
X2016823Y229067D01*
X2017140Y229483D01*
X2017267Y229983D01*
X2017140Y230483D01*
X2016823Y230900D01*
X2016253Y231150D01*
X2015683Y231067D01*
X2015113Y230733D01*
G01X2019897Y230317D02*
X2020277Y230817D01*
X2020720Y231067D01*
X2021227Y231150D01*
X2021860Y230983D01*
X2022303Y230567D01*
X2022430Y230067D01*
X2022367Y229567D01*
X2022113Y229150D01*
X2020847Y228317D01*
X2020277Y227733D01*
X2019897Y226900D01*
X2019770Y226150D01*
X2022430D01*
G01X2019310Y249850D02*
Y254850D01*
X2016967Y251267D01*
X2020133D01*
G01X2016760Y273550D02*
Y278550D01*
X2014417Y274967D01*
X2017583D01*
G01X2021100Y273550D02*
X2021543Y273633D01*
X2022050Y273883D01*
X2022367Y274300D01*
X2022493Y274883D01*
X2022367Y275467D01*
X2021987Y275967D01*
X2021417Y276217D01*
X2020783D01*
X2020403Y276383D01*
X2020087Y276800D01*
X2019960Y277383D01*
X2020150Y277967D01*
X2020593Y278383D01*
X2021100Y278550D01*
X2021607Y278383D01*
X2022050Y277967D01*
X2022240Y277383D01*
X2022113Y276800D01*
X2021797Y276383D01*
X2021417Y276217D01*
X2020783D01*
X2020213Y275967D01*
X2019833Y275467D01*
X2019707Y274883D01*
X2019833Y274300D01*
X2020150Y273883D01*
X2020657Y273633D01*
X2021100Y273550D01*
G01X2016000Y297250D02*
Y302250D01*
X2015240Y301250D01*
G01Y297250D02*
X2016760D01*
G01X2019897Y299333D02*
X2020340Y299917D01*
X2020720Y300250D01*
X2021227Y300417D01*
X2021670Y300250D01*
X2021987Y299917D01*
X2022240Y299417D01*
X2022303Y298833D01*
X2022240Y298333D01*
X2021987Y297833D01*
X2021607Y297417D01*
X2021163Y297250D01*
X2020657Y297417D01*
X2020213Y297917D01*
X2019960Y298667D01*
X2019897Y299500D01*
X2020023Y300583D01*
X2020213Y301167D01*
X2020530Y301750D01*
X2020973Y302167D01*
X2021417Y302250D01*
X2021860Y302083D01*
X2022177Y301667D01*
G01X2012247Y325117D02*
X2012627Y325617D01*
X2013070Y325867D01*
X2013577Y325950D01*
X2014210Y325783D01*
X2014653Y325367D01*
X2014780Y324867D01*
X2014717Y324367D01*
X2014463Y323950D01*
X2013197Y323117D01*
X2012627Y322533D01*
X2012247Y321700D01*
X2012120Y320950D01*
X2014780D01*
G01X2017473Y321533D02*
X2017917Y321117D01*
X2018423Y320950D01*
X2018930Y321117D01*
X2019373Y321617D01*
X2019690Y322367D01*
X2019817Y323117D01*
Y324033D01*
X2019690Y324783D01*
X2019373Y325450D01*
X2018993Y325783D01*
X2018550Y325950D01*
X2018043Y325783D01*
X2017663Y325450D01*
X2017410Y324950D01*
X2017283Y324283D01*
X2017410Y323700D01*
X2017727Y323117D01*
X2018107Y322783D01*
X2018550Y322700D01*
X2019057Y322867D01*
X2019437Y323283D01*
X2019817Y324033D01*
G01X2023523Y320950D02*
X2023650Y322033D01*
X2023840Y322950D01*
X2024093Y323783D01*
X2024410Y324700D01*
X2024917Y325950D01*
X2022383D01*
G01X2012247Y348817D02*
X2012627Y349317D01*
X2013070Y349567D01*
X2013577Y349650D01*
X2014210Y349483D01*
X2014653Y349067D01*
X2014780Y348567D01*
X2014717Y348067D01*
X2014463Y347650D01*
X2013197Y346817D01*
X2012627Y346233D01*
X2012247Y345400D01*
X2012120Y344650D01*
X2014780D01*
G01X2018550D02*
Y349650D01*
X2017790Y348650D01*
G01Y344650D02*
X2019310D01*
G01X2022447Y346733D02*
X2022890Y347317D01*
X2023270Y347650D01*
X2023777Y347817D01*
X2024220Y347650D01*
X2024537Y347317D01*
X2024790Y346817D01*
X2024853Y346233D01*
X2024790Y345733D01*
X2024537Y345233D01*
X2024157Y344817D01*
X2023713Y344650D01*
X2023207Y344817D01*
X2022763Y345317D01*
X2022510Y346067D01*
X2022447Y346900D01*
X2022573Y347983D01*
X2022763Y348567D01*
X2023080Y349150D01*
X2023523Y349567D01*
X2023967Y349650D01*
X2024410Y349483D01*
X2024727Y349067D01*
G01X2013450Y368350D02*
Y373350D01*
X2012690Y372350D01*
G01Y368350D02*
X2014210D01*
G01X2018423D02*
X2018550Y369433D01*
X2018740Y370350D01*
X2018993Y371183D01*
X2019310Y372100D01*
X2019817Y373350D01*
X2017283D01*
G01X2022447Y370433D02*
X2022890Y371017D01*
X2023270Y371350D01*
X2023777Y371517D01*
X2024220Y371350D01*
X2024537Y371017D01*
X2024790Y370517D01*
X2024853Y369933D01*
X2024790Y369433D01*
X2024537Y368933D01*
X2024157Y368517D01*
X2023713Y368350D01*
X2023207Y368517D01*
X2022763Y369017D01*
X2022510Y369767D01*
X2022447Y370600D01*
X2022573Y371683D01*
X2022763Y372267D01*
X2023080Y372850D01*
X2023523Y373267D01*
X2023967Y373350D01*
X2024410Y373183D01*
X2024727Y372767D01*
G01X2012247Y396217D02*
X2012627Y396717D01*
X2013070Y396967D01*
X2013577Y397050D01*
X2014210Y396883D01*
X2014653Y396467D01*
X2014780Y395967D01*
X2014717Y395467D01*
X2014463Y395050D01*
X2013197Y394217D01*
X2012627Y393633D01*
X2012247Y392800D01*
X2012120Y392050D01*
X2014780D01*
G01X2017347Y394133D02*
X2017790Y394717D01*
X2018170Y395050D01*
X2018677Y395217D01*
X2019120Y395050D01*
X2019437Y394717D01*
X2019690Y394217D01*
X2019753Y393633D01*
X2019690Y393133D01*
X2019437Y392633D01*
X2019057Y392217D01*
X2018613Y392050D01*
X2018107Y392217D01*
X2017663Y392717D01*
X2017410Y393467D01*
X2017347Y394300D01*
X2017473Y395383D01*
X2017663Y395967D01*
X2017980Y396550D01*
X2018423Y396967D01*
X2018867Y397050D01*
X2019310Y396883D01*
X2019627Y396467D01*
G01X2023650Y392050D02*
X2024093Y392133D01*
X2024600Y392383D01*
X2024917Y392800D01*
X2025043Y393383D01*
X2024917Y393967D01*
X2024537Y394467D01*
X2023967Y394717D01*
X2023333D01*
X2022953Y394883D01*
X2022637Y395300D01*
X2022510Y395883D01*
X2022700Y396467D01*
X2023143Y396883D01*
X2023650Y397050D01*
X2024157Y396883D01*
X2024600Y396467D01*
X2024790Y395883D01*
X2024663Y395300D01*
X2024347Y394883D01*
X2023967Y394717D01*
X2023333D01*
X2022763Y394467D01*
X2022383Y393967D01*
X2022257Y393383D01*
X2022383Y392800D01*
X2022700Y392383D01*
X2023207Y392133D01*
X2023650Y392050D01*
G01X2013450Y410200D02*
X2012943Y410283D01*
X2012500Y410617D01*
X2012120Y411117D01*
X2011867Y411700D01*
X2011740Y412367D01*
Y413033D01*
X2011867Y413700D01*
X2012120Y414283D01*
X2012500Y414783D01*
X2012943Y415117D01*
X2013450Y415200D01*
X2013957Y415117D01*
X2014400Y414783D01*
X2014780Y414283D01*
X2015033Y413700D01*
X2015160Y413033D01*
Y412367D01*
X2015033Y411700D01*
X2014780Y411117D01*
X2014400Y410617D01*
X2013957Y410283D01*
X2013450Y410200D01*
G01X2013957Y411533D02*
X2014717Y410200D01*
G01X2018550Y415200D02*
Y410200D01*
G01X2017093Y415200D02*
X2020007D01*
G01X2023650Y410200D02*
Y412450D01*
X2022383Y415200D01*
G01X2024917D02*
X2023650Y412450D01*
G54D13*
X17716Y114173D03*
X314213Y163386D03*
X783661Y18504D03*
X826024Y163386D03*
X1101615Y18504D03*
X1184292Y163386D03*
X1776200Y-126850D03*
G54D22*
X343780Y11810D03*
Y19684D03*
Y27558D03*
X335906Y11810D03*
Y19684D03*
Y27558D03*
X343780Y43306D03*
Y51180D03*
X335906Y43306D03*
Y51180D03*
X343780Y59054D03*
X335906D03*
X367402Y11810D03*
Y19684D03*
Y27558D03*
X359528Y11810D03*
Y19684D03*
Y27558D03*
X367402Y43306D03*
Y51180D03*
X359528Y43306D03*
Y51180D03*
X367402Y59054D03*
X359528D03*
X392776Y32264D03*
X383642Y50375D03*
Y40532D03*
Y70060D03*
Y79902D03*
X396122Y99587D03*
X383642Y88564D03*
Y119272D03*
Y158642D03*
X411673Y32264D03*
X417382Y99587D03*
X405964Y178327D03*
X430571Y32264D03*
X439744Y50375D03*
Y60217D03*
Y70060D03*
Y99587D03*
Y88564D03*
Y138957D03*
Y178327D03*
X466654Y7874D03*
Y29922D03*
Y24410D03*
Y18898D03*
Y13386D03*
Y51969D03*
Y46457D03*
Y40945D03*
Y35433D03*
X474528Y8268D03*
X482402Y7874D03*
X490276Y8268D03*
X474528Y30315D03*
X482402Y29922D03*
X490276Y30315D03*
X474528Y24803D03*
X482402Y24410D03*
X490276Y24803D03*
X474528Y19292D03*
X482402Y18898D03*
X490276Y19292D03*
X474528Y13780D03*
X482402Y13386D03*
X490276Y13780D03*
X474528Y52362D03*
X482402Y51969D03*
X490276Y52362D03*
X474528Y46851D03*
X482402Y46457D03*
X490276Y46851D03*
X474528Y41339D03*
X482402Y40945D03*
X490276Y41339D03*
X474528Y35827D03*
X482402Y35433D03*
X490276Y35827D03*
X498150Y7874D03*
X506024Y8268D03*
X498150Y29922D03*
X506024Y30315D03*
X498150Y24410D03*
X506024Y24803D03*
X498150Y18898D03*
X506024Y19292D03*
X498150Y13386D03*
X506024Y13780D03*
X498150Y51969D03*
X506024Y52362D03*
X498150Y46457D03*
X506024Y46851D03*
X498150Y40945D03*
X506024Y41339D03*
X498150Y35433D03*
X506024Y35827D03*
X532934Y50375D03*
Y40532D03*
Y70060D03*
Y79902D03*
Y88564D03*
Y119272D03*
Y158642D03*
X542068Y32264D03*
X560965D03*
X545414Y99587D03*
X555256Y178327D03*
X579863Y32264D03*
X566674Y99587D03*
X589036Y50375D03*
Y60217D03*
Y70060D03*
Y99587D03*
Y88564D03*
Y138957D03*
Y178327D03*
X649173Y7874D03*
Y29922D03*
Y24410D03*
Y18898D03*
Y13386D03*
Y51969D03*
Y46457D03*
Y40945D03*
Y35433D03*
X657047Y8268D03*
X664921Y7874D03*
X672795Y8268D03*
X657047Y30315D03*
X664921Y29922D03*
X672795Y30315D03*
X657047Y24803D03*
X664921Y24410D03*
X672795Y24803D03*
X657047Y19292D03*
X664921Y18898D03*
X672795Y19292D03*
X657047Y13780D03*
X664921Y13386D03*
X672795Y13780D03*
X657047Y52362D03*
X664921Y51969D03*
X672795Y52362D03*
X657047Y46851D03*
X664921Y46457D03*
X672795Y46851D03*
X657047Y41339D03*
X664921Y40945D03*
X672795Y41339D03*
X657047Y35827D03*
X664921Y35433D03*
X672795Y35827D03*
X680669Y7874D03*
X688543Y8268D03*
X680669Y29922D03*
X688543Y30315D03*
X680669Y24410D03*
X688543Y24803D03*
X680669Y18898D03*
X688543Y19292D03*
X680669Y13386D03*
X688543Y13780D03*
X680669Y51969D03*
X688543Y52362D03*
X680669Y46457D03*
X688543Y46851D03*
X680669Y40945D03*
X688543Y41339D03*
X680669Y35433D03*
X688543Y35827D03*
X1205984Y11810D03*
Y19684D03*
Y27558D03*
Y43306D03*
Y51180D03*
Y59054D03*
X1213858Y11810D03*
Y19684D03*
Y27558D03*
X1229606Y11810D03*
Y19684D03*
Y27558D03*
Y43306D03*
Y51180D03*
X1213858Y43306D03*
Y51180D03*
X1229606Y59054D03*
X1213858D03*
X1237480Y11810D03*
Y19684D03*
Y27558D03*
Y43306D03*
Y51180D03*
X1253721Y40532D03*
X1237480Y59054D03*
X1253721Y79902D03*
Y119272D03*
Y158642D03*
X1262855Y32264D03*
X1253721Y50375D03*
Y70060D03*
X1266201Y99587D03*
X1253721Y88564D03*
X1276043Y178327D03*
X1281752Y32264D03*
X1287461Y99587D03*
X1300650Y32264D03*
X1309823Y50375D03*
Y60217D03*
Y70060D03*
Y99587D03*
Y88564D03*
Y138957D03*
Y178327D03*
X1336733Y7874D03*
X1344607Y8268D03*
X1336733Y29922D03*
X1344607Y30315D03*
X1336733Y24410D03*
X1344607Y24803D03*
X1336733Y18898D03*
X1344607Y19292D03*
X1336733Y13386D03*
X1344607Y13780D03*
X1336733Y51969D03*
X1344607Y52362D03*
X1336733Y46457D03*
X1344607Y46851D03*
X1336733Y40945D03*
X1344607Y41339D03*
X1336733Y35433D03*
X1344607Y35827D03*
X1352481Y7874D03*
X1360355Y8268D03*
X1352481Y29922D03*
X1360355Y30315D03*
X1352481Y24410D03*
X1360355Y24803D03*
X1352481Y18898D03*
X1360355Y19292D03*
X1352481Y13386D03*
X1360355Y13780D03*
X1352481Y51969D03*
X1360355Y52362D03*
X1352481Y46457D03*
X1360355Y46851D03*
X1352481Y40945D03*
X1360355Y41339D03*
X1352481Y35433D03*
X1360355Y35827D03*
X1368229Y7874D03*
X1376103Y8268D03*
X1368229Y29922D03*
X1376103Y30315D03*
X1368229Y24410D03*
X1376103Y24803D03*
X1368229Y18898D03*
X1376103Y19292D03*
X1368229Y13386D03*
X1376103Y13780D03*
X1368229Y51969D03*
X1376103Y52362D03*
X1368229Y46457D03*
X1376103Y46851D03*
X1368229Y40945D03*
X1376103Y41339D03*
X1368229Y35433D03*
X1376103Y35827D03*
X1412146Y32264D03*
X1403012Y50375D03*
Y40532D03*
Y70060D03*
Y79902D03*
Y88564D03*
Y119272D03*
Y158642D03*
X1431043Y32264D03*
X1415492Y99587D03*
X1436752D03*
X1425334Y178327D03*
X1449941Y32264D03*
X1459114Y50375D03*
Y60217D03*
Y70060D03*
Y99587D03*
Y88564D03*
Y138957D03*
Y178327D03*
X1519252Y7874D03*
X1527126Y8268D03*
X1519252Y29922D03*
X1527126Y30315D03*
X1519252Y24410D03*
X1527126Y24803D03*
X1519252Y18898D03*
X1527126Y19292D03*
X1519252Y13386D03*
X1527126Y13780D03*
X1519252Y51969D03*
X1527126Y52362D03*
X1519252Y46457D03*
X1527126Y46851D03*
X1519252Y40945D03*
X1527126Y41339D03*
X1519252Y35433D03*
X1527126Y35827D03*
X1535000Y7874D03*
X1542874Y8268D03*
X1550748Y7874D03*
X1535000Y29922D03*
X1542874Y30315D03*
X1550748Y29922D03*
X1535000Y24410D03*
X1542874Y24803D03*
X1550748Y24410D03*
X1535000Y18898D03*
X1542874Y19292D03*
X1550748Y18898D03*
X1535000Y13386D03*
X1542874Y13780D03*
X1550748Y13386D03*
X1535000Y51969D03*
X1542874Y52362D03*
X1550748Y51969D03*
X1535000Y46457D03*
X1542874Y46851D03*
X1550748Y46457D03*
X1535000Y40945D03*
X1542874Y41339D03*
X1550748Y40945D03*
X1535000Y35433D03*
X1542874Y35827D03*
X1550748Y35433D03*
X1558622Y8268D03*
Y30315D03*
Y24803D03*
Y19292D03*
Y13780D03*
Y52362D03*
Y46851D03*
Y41339D03*
Y35827D03*
X1776200Y157550D03*
Y204950D03*
Y252350D03*
Y276050D03*
Y347150D03*
G54D14*
X40827Y29528D03*
Y147638D03*
X1776200Y-32050D03*
G54D23*
X351654Y37400D03*
X1221732D03*
X1776200Y-79450D03*
G54D15*
X44528Y41339D03*
Y53150D03*
X56339Y41339D03*
Y53150D03*
X44528Y64961D03*
Y76772D03*
X56339Y64961D03*
Y76772D03*
X44528Y88583D03*
Y100394D03*
X56339Y88583D03*
Y100394D03*
X44528Y112205D03*
Y124016D03*
X56339Y112205D03*
Y124016D03*
X44528Y135827D03*
X56339D03*
X1776200Y133850D03*
G54D24*
X392795Y56653D03*
X542087Y56654D03*
X655453Y132244D03*
X702697D03*
X730295D03*
X777539D03*
X1262874Y56654D03*
X1412166Y56653D03*
X1525531Y132244D03*
X1572775D03*
X1600374D03*
X1647618D03*
X1776200Y-55750D03*
G54D16*
X51900Y162300D03*
X53200Y169500D03*
X76900Y20200D03*
X65600Y160400D03*
X57200Y165300D03*
X73200Y162100D03*
X62200Y169900D03*
X70400Y170000D03*
X90200Y22400D03*
X94900Y144500D03*
X83800Y154500D03*
X99000Y148900D03*
X78800Y158000D03*
X93900Y162900D03*
X90200Y169500D03*
X81600Y162600D03*
X92600Y154800D03*
X100700Y163400D03*
X89000Y150200D03*
X88000Y158900D03*
X83500Y169700D03*
X78200Y169900D03*
X96900Y169500D03*
X98000Y157100D03*
X102500Y29400D03*
X107200Y19300D03*
X121200Y33900D03*
X123100Y49600D03*
X102000Y141900D03*
X114000Y145200D03*
X119900Y143200D03*
X108600Y143100D03*
X111800Y151800D03*
X104900Y157400D03*
X120500Y157200D03*
X111900Y164800D03*
X118100Y162100D03*
X104500Y150300D03*
X110900Y159200D03*
X118400Y152000D03*
X106500Y170300D03*
X115300Y170200D03*
X143300Y27300D03*
X123900Y41000D03*
X143800Y53600D03*
X144500Y40000D03*
X138700Y63500D03*
X144100Y72900D03*
X133100Y71300D03*
X139800Y90200D03*
X131400Y91300D03*
X144200Y96300D03*
X129200Y101300D03*
X143000Y105700D03*
X129200Y142400D03*
X126600Y149500D03*
X141900Y154700D03*
X134800Y164000D03*
X144700Y149200D03*
X137100Y158600D03*
X137000Y170400D03*
X127400D03*
X165600Y19400D03*
X150300Y20200D03*
X168100Y48400D03*
X151500Y35800D03*
X166500Y34700D03*
X153100Y49600D03*
X159800Y65100D03*
X161800Y86800D03*
X148800Y85000D03*
X158200Y102400D03*
X163500Y144900D03*
X150300Y144600D03*
X156000Y138200D03*
X156500Y144800D03*
X169900Y146800D03*
X164400Y138200D03*
X169400Y153600D03*
X155600Y157900D03*
X162100Y164300D03*
X168000Y161200D03*
X149300Y164100D03*
X163200Y151600D03*
X162000Y159400D03*
X148000Y158800D03*
X152600Y152000D03*
X155900Y170000D03*
X163800Y170100D03*
X148600D03*
X180300Y20200D03*
X184100Y36600D03*
X183100Y49600D03*
X174300Y73300D03*
X191700Y75400D03*
X175000Y62300D03*
X181400Y84700D03*
X174200Y96300D03*
X190400Y136600D03*
X191200Y142400D03*
X178100Y144600D03*
X184000Y138800D03*
X173600Y138700D03*
X185800Y145400D03*
X190000Y149800D03*
X179300Y156400D03*
X187100Y155800D03*
X192100Y163500D03*
X176300Y164400D03*
X175500Y151300D03*
X173700Y158700D03*
X190400Y169800D03*
X182600Y152000D03*
X171300Y170000D03*
X177800Y170400D03*
X194400Y20200D03*
X197800Y30900D03*
X210300Y20200D03*
X197800Y48000D03*
X214700Y35800D03*
X213100Y49600D03*
X195600Y64100D03*
X206700Y72700D03*
X209400Y60900D03*
X204200Y96300D03*
X196200Y102300D03*
X211300Y138600D03*
X204200Y139200D03*
X195900Y146300D03*
X213300Y146800D03*
X197300Y139100D03*
X205100Y147700D03*
X201500Y154400D03*
X213500Y155400D03*
X197100Y160800D03*
X194600Y154800D03*
X225800Y19600D03*
X229200Y30900D03*
X227100Y43000D03*
X216400Y100500D03*
X234200Y96300D03*
X225600Y104500D03*
X234500Y138700D03*
X230600Y146400D03*
X218100Y140500D03*
X224400Y138200D03*
X236800Y165000D03*
X238800Y157500D03*
X231600Y155100D03*
X221800Y149400D03*
X236500Y185900D03*
X235400Y172900D03*
X254400Y19200D03*
X240300Y20200D03*
X257800Y51200D03*
X244900Y36600D03*
X243100Y49600D03*
X254400Y74300D03*
X251600Y100100D03*
X248600Y142900D03*
X242600Y140100D03*
X254400Y138200D03*
X252200Y159400D03*
X239600Y148700D03*
X245100Y165200D03*
X255400Y148400D03*
X245600Y157000D03*
X248400Y149800D03*
X252800Y179900D03*
X239800Y178700D03*
X243300Y185600D03*
X242300Y171800D03*
X252600Y192000D03*
X242400Y193300D03*
X270300Y20200D03*
X268300Y36200D03*
X273100Y49600D03*
X283600Y69500D03*
X273300Y94900D03*
X264200Y96300D03*
X281800Y100900D03*
X262900Y104900D03*
X267700Y145200D03*
X284400Y138200D03*
X280000Y159800D03*
X281000Y180700D03*
X265300Y170000D03*
X282600Y192000D03*
X294200Y96300D03*
X307800Y101100D03*
X300300Y140000D03*
X287600Y150000D03*
X292800Y169800D03*
X324200Y96300D03*
X314600Y104100D03*
X310200Y135900D03*
X350000Y161800D03*
X338300Y162900D03*
X350200Y181100D03*
X338300Y183800D03*
X359200Y164900D03*
X359100Y184400D03*
X806800Y26700D03*
X813700Y43900D03*
X810700Y65200D03*
X809700Y86500D03*
X836800Y26700D03*
X825200Y111700D03*
X840700Y65200D03*
X839700Y86500D03*
X855200Y111700D03*
X838300Y128100D03*
X855400Y152400D03*
X857000Y189800D03*
X855400Y173000D03*
X866800Y26700D03*
X870700Y65200D03*
X869700Y86500D03*
X868300Y128100D03*
X896800Y26700D03*
X900700Y65200D03*
X899700Y86500D03*
X885200Y111700D03*
X898300Y128100D03*
X885400Y152400D03*
X887000Y189800D03*
X885400Y173000D03*
X926800Y26700D03*
X929700Y86500D03*
X915200Y111700D03*
X928300Y128100D03*
X915400Y152400D03*
X917000Y189800D03*
X915400Y173000D03*
X930700Y65200D03*
X945200Y111700D03*
X945400Y152400D03*
X947000Y189800D03*
X945400Y173000D03*
X959000Y18000D03*
X956800Y26700D03*
X960700Y65200D03*
X959700Y86500D03*
X975200Y111700D03*
X958300Y128100D03*
X975400Y152400D03*
Y173000D03*
X986800Y26700D03*
X990700Y65200D03*
X989700Y86500D03*
X988300Y128100D03*
X977000Y189800D03*
X1018800Y26300D03*
X1005200Y111700D03*
X1018300Y128100D03*
X1005400Y152400D03*
X1007000Y189800D03*
X1005400Y173000D03*
X1043000Y45500D03*
X1022700Y64800D03*
X1031900Y84100D03*
X1037200Y111300D03*
X1035400Y152400D03*
X1037000Y189800D03*
X1035400Y173000D03*
X1063700Y15300D03*
X1048800Y26300D03*
X1052700Y64800D03*
X1061900Y84100D03*
X1067200Y111300D03*
X1048300Y128100D03*
X1065400Y152400D03*
X1067000Y189800D03*
X1067400Y172600D03*
X1078800Y26300D03*
X1073000Y45500D03*
X1082700Y64800D03*
X1078300Y128100D03*
X1091900Y84100D03*
X1097200Y111300D03*
X1108300Y128100D03*
X1095400Y152400D03*
X1097000Y189800D03*
X1097400Y172600D03*
X1136600Y19700D03*
X1135400Y41000D03*
X1120900Y64500D03*
X1121900Y84100D03*
X1127200Y111300D03*
X1125400Y152400D03*
X1127000Y189800D03*
X1127400Y172600D03*
X1147100Y64500D03*
X1151900Y84100D03*
X1155400Y152400D03*
X1157000Y189800D03*
X1157400Y172600D03*
X1776200Y323450D03*
G54D25*
X430591Y56653D03*
X579883Y56654D03*
X1300670D03*
X1449962Y56653D03*
X1776200Y-174250D03*
G54D17*
X64500Y165200D03*
X99100Y127470D03*
X89400Y165300D03*
X102400Y59600D03*
X111958Y73600D03*
X121958Y70900D03*
X116958Y68600D03*
X106958Y68500D03*
X102590Y115680D03*
X115400Y120270D03*
X107390Y125110D03*
X119800Y124390D03*
X108900Y137300D03*
X114300Y134900D03*
X119700Y132400D03*
X111500Y129900D03*
X105800Y165400D03*
X128600Y114510D03*
X132500Y110100D03*
X125000Y126400D03*
X141400Y164800D03*
X129000D03*
X169200Y165200D03*
X155500Y164800D03*
X183300Y164700D03*
X346800Y113500D03*
X345400Y107600D03*
X346200Y102500D03*
X350700Y121642D03*
X345900Y125100D03*
X347350Y143750D03*
X346906Y137693D03*
X362500Y97100D03*
X357800Y114657D03*
X357600Y108561D03*
X356861Y102961D03*
X414900Y6500D03*
X463435Y79865D03*
X453900Y92300D03*
X453300Y86800D03*
X451100Y81400D03*
X452100Y97000D03*
X452000Y102200D03*
X488000Y89800D03*
X477630Y88900D03*
X525700Y99300D03*
X519400Y96400D03*
X520439Y91000D03*
X516500Y87442D03*
X571500Y7500D03*
X604200Y107400D03*
X614900Y90157D03*
X615600Y95139D03*
X625600Y95400D03*
X625700Y90100D03*
X615500Y100157D03*
X622658Y112158D03*
X622200Y120258D03*
X615500Y105157D03*
X626173Y148400D03*
X617949Y147000D03*
X659310Y72900D03*
X664310D03*
X654400Y92100D03*
Y97100D03*
X672638Y93290D03*
X666614Y121000D03*
X661614D03*
X671063Y125930D03*
X676063D03*
X680300Y75600D03*
X689723Y89400D03*
X689311Y96311D03*
X677638Y93290D03*
X689961Y122030D03*
X694961D03*
X680612Y129600D03*
X685612D03*
X701100Y16900D03*
X701670Y97100D03*
Y92100D03*
X740300Y87300D03*
X735807Y96593D03*
X724400Y105600D03*
X729400D03*
X730310Y115390D03*
X725310D03*
X761929Y72900D03*
X756929D03*
X752480Y92830D03*
X747480D03*
X764153Y96153D03*
X745905Y120452D03*
X750905D03*
X764803Y120330D03*
X760410Y124730D03*
X755410D03*
X778200Y92130D03*
Y97130D03*
X776032Y101968D03*
X769803Y120330D03*
X1223200Y99000D03*
X1216500Y119500D03*
X1216700Y114400D03*
X1216500Y108300D03*
X1216400Y102600D03*
X1226900Y119561D03*
Y114043D03*
X1227000Y108361D03*
X1227100Y102861D03*
X1219600Y129400D03*
X1219400Y123900D03*
X1211200Y144900D03*
X1217405Y143895D03*
X1229800Y96400D03*
X1238100Y127900D03*
X1323000Y99239D03*
X1321400Y92800D03*
X1321500Y82600D03*
X1322500Y87800D03*
X1359000Y91000D03*
X1387400Y87242D03*
X1389900Y97600D03*
X1395200Y99500D03*
X1391000Y92400D03*
X1442400Y8200D03*
X1494200Y97800D03*
X1495000Y92800D03*
X1484700Y93057D03*
X1485000Y98057D03*
X1484900Y103257D03*
X1492300Y117558D03*
X1484800Y109357D03*
X1492042Y126358D03*
X1495800Y147800D03*
X1487600Y147000D03*
X1524478Y97100D03*
Y92100D03*
X1534388Y72900D03*
X1529388D03*
X1550500Y75500D03*
X1542716Y93290D03*
X1547716D03*
X1531692Y121000D03*
X1536692D03*
X1546141Y125930D03*
X1550690Y129600D03*
X1541141Y125930D03*
X1570800Y18900D03*
X1571748Y92100D03*
Y97100D03*
X1559802Y89400D03*
X1559389Y96311D03*
X1565039Y122030D03*
X1560039D03*
X1555690Y129600D03*
X1594478Y105600D03*
X1595388Y115390D03*
X1617558Y92830D03*
X1610379Y87300D03*
X1605885Y96593D03*
X1599478Y105600D03*
X1600388Y115390D03*
X1615983Y120452D03*
X1627007Y72900D03*
X1632007D03*
X1622558Y92830D03*
X1634231Y96153D03*
X1620983Y120452D03*
X1639881Y120330D03*
X1634881D03*
X1625488Y124730D03*
X1630488D03*
X1648278Y97130D03*
Y92130D03*
X1646110Y101968D03*
X1776200Y370850D03*
G54D26*
X468859Y115666D03*
Y141650D03*
X488859Y115666D03*
X478859D03*
X483859Y125666D03*
X473859D03*
X478859Y141650D03*
X488859D03*
X473859Y151650D03*
X483859D03*
X498859Y115666D03*
X503859Y125666D03*
X493859D03*
X498859Y141650D03*
X493859Y151650D03*
X503859D03*
X1338938Y115666D03*
X1343938Y125666D03*
X1338938Y141650D03*
X1343938Y151650D03*
X1358938Y115666D03*
X1348938D03*
X1363938Y125666D03*
X1353938D03*
X1348938Y141650D03*
X1358938D03*
X1353938Y151650D03*
X1363938D03*
X1368938Y115666D03*
X1373938Y125666D03*
X1368938Y141650D03*
X1373938Y151650D03*
X1776200Y228650D03*
G54D27*
X452875Y131650D03*
X455867Y153658D03*
X452875Y194642D03*
X516851Y140666D03*
X519843Y115666D03*
Y194642D03*
X1322954Y131650D03*
Y194642D03*
X1325946Y153658D03*
X1389922Y115666D03*
X1386930Y140666D03*
X1389922Y194642D03*
X1776200Y62750D03*
G54D18*
X85866Y72835D03*
Y104331D03*
X1776200Y-8350D03*
G54D28*
X463859Y176650D03*
X508859D03*
X1333938D03*
X1378938D03*
X1776200Y-103150D03*
G54D19*
X81929Y76772D03*
Y68898D03*
X89803Y76772D03*
Y68898D03*
X81929Y100394D03*
Y92520D03*
Y84646D03*
X89803Y100394D03*
Y92520D03*
Y84646D03*
X81929Y108268D03*
X89803D03*
X1776200Y181250D03*
G54D29*
X639283Y108622D03*
Y167677D03*
X793693Y108622D03*
Y167677D03*
X1509362Y108622D03*
Y167677D03*
X1663772Y108622D03*
Y167677D03*
X1776200Y39050D03*
M02*
